G04 ================== begin FILE IDENTIFICATION RECORD ==================*
G04 Layout Name:  15126-1b.brd*
G04 Film Name:    DRILL*
G04 File Format:  Gerber RS274X*
G04 File Origin:  Cadence Allegro 16.6-2015-S079*
G04 Origin Date:  Fri Feb 10 17:21:51 2017*
G04 *
G04 Layer:  MANUFACTURING/NCLEGEND-1-14*
G04 Layer:  MANUFACTURING/DRILL SIZE*
G04 Layer:  DRAWING FORMAT/LAYER_PCB_STORY*
G04 Layer:  DRAWING FORMAT/LAYER_DRILL*
G04 Layer:  BOARD GEOMETRY/PANEL_OUTLINE*
G04 *
G04 Offset:    (0.00 0.00)*
G04 Mirror:    No*
G04 Mode:      Positive*
G04 Rotation:  0*
G04 FullContactRelief:  No*
G04 UndefLineWidth:     6.00*
G04 ================== end FILE IDENTIFICATION RECORD ====================*
%FSLAX35Y35*MOIN*%
%IR0*IPPOS*OFA0.00000B0.00000*MIA0B0*SFA1.00000B1.00000*%
%AMMACRO55*
1,1,.006,-.02933,-.016*
20,1,.006,-.02933,-.016,-.016,.016,0.0*
1,1,.006,-.016,.016*
20,1,.006,-.016,.016,-.00267,-.016,0.0*
1,1,.006,-.00267,-.016*
1,1,.006,-.00747,-.0048*
20,1,.006,-.00747,-.0048,-.02453,-.0048,0.0*
1,1,.006,-.02453,-.0048*
1,1,.006,.00268,-.016*
20,1,.006,.00268,-.016,.01601,.016,0.0*
1,1,.006,.01601,.016*
20,1,.006,.01601,.016,.02934,-.016,0.0*
1,1,.006,.02934,-.016*
1,1,.006,.02454,-.0048*
20,1,.006,.02454,-.0048,.00748,-.0048,0.0*
1,1,.006,.00748,-.0048*
%
%ADD55MACRO55*%
%AMMACRO60*
1,1,.006,-.03667,-.02*
20,1,.006,-.03667,-.02,-.02,.02,0.0*
1,1,.006,-.02,.02*
20,1,.006,-.02,.02,-.00333,-.02,0.0*
1,1,.006,-.00333,-.02*
1,1,.006,-.00933,-.006*
20,1,.006,-.00933,-.006,-.03067,-.006,0.0*
1,1,.006,-.03067,-.006*
1,1,.006,.00534,-.02*
20,1,.006,.00534,-.02,.00534,.02,0.0*
1,1,.006,.00534,.02*
20,1,.006,.00534,.02,.01868,.02,0.0*
1,1,.006,.01868,.02*
20,1,.006,.01868,.02,.02401,.018,0.0*
1,1,.006,.02401,.018*
20,1,.006,.02401,.018,.02801,.01533,0.0*
1,1,.006,.02801,.01533*
20,1,.006,.02801,.01533,.03134,.01133,0.0*
1,1,.006,.03134,.01133*
20,1,.006,.03134,.01133,.03401,.00667,0.0*
1,1,.006,.03401,.00667*
20,1,.006,.03401,.00667,.03468,0.0,0.0*
1,1,.006,.03468,0.0*
20,1,.006,.03468,0.0,.03401,-.00667,0.0*
1,1,.006,.03401,-.00667*
20,1,.006,.03401,-.00667,.03134,-.01133,0.0*
1,1,.006,.03134,-.01133*
20,1,.006,.03134,-.01133,.02801,-.01533,0.0*
1,1,.006,.02801,-.01533*
20,1,.006,.02801,-.01533,.02401,-.018,0.0*
1,1,.006,.02401,-.018*
20,1,.006,.02401,-.018,.01868,-.02,0.0*
1,1,.006,.01868,-.02*
20,1,.006,.01868,-.02,.00534,-.02,0.0*
1,1,.006,.00534,-.02*
%
%ADD60MACRO60*%
%AMMACRO58*
1,1,.006,-.03758,-.0205*
20,1,.006,-.03758,-.0205,-.0205,.0205,0.0*
1,1,.006,-.0205,.0205*
20,1,.006,-.0205,.0205,-.00342,-.0205,0.0*
1,1,.006,-.00342,-.0205*
1,1,.006,-.00957,-.00615*
20,1,.006,-.00957,-.00615,-.03143,-.00615,0.0*
1,1,.006,-.03143,-.00615*
1,1,.006,.03418,-.0205*
20,1,.006,.03418,-.0205,.00684,-.0205,0.0*
1,1,.006,.00684,-.0205*
20,1,.006,.00684,-.0205,.00684,.0205,0.0*
1,1,.006,.00684,.0205*
20,1,.006,.00684,.0205,.03418,.0205,0.0*
1,1,.006,.03418,.0205*
1,1,.006,.02324,.00068*
20,1,.006,.02324,.00068,.00684,.00068,0.0*
1,1,.006,.00684,.00068*
%
%ADD58MACRO58*%
%AMMACRO37*
1,1,.006,-.04583,-.025*
20,1,.006,-.04583,-.025,-.025,.025,0.0*
1,1,.006,-.025,.025*
20,1,.006,-.025,.025,-.00417,-.025,0.0*
1,1,.006,-.00417,-.025*
1,1,.006,-.01167,-.0075*
20,1,.006,-.01167,-.0075,-.03833,-.0075,0.0*
1,1,.006,-.03833,-.0075*
1,1,.006,.01501,.025*
20,1,.006,.01501,.025,.03501,.025,0.0*
1,1,.006,.03501,.025*
1,1,.006,.02501,.025*
20,1,.006,.02501,.025,.02501,-.025,0.0*
1,1,.006,.02501,-.025*
1,1,.006,.01501,-.025*
20,1,.006,.01501,-.025,.03501,-.025,0.0*
1,1,.006,.03501,-.025*
%
%ADD37MACRO37*%
%AMMACRO13*
1,1,.006,.00984,0.0*
20,1,.006,.00984,0.0,.009691,-.001709,0.0*
1,1,.006,.009691,-.001709*
20,1,.006,.009691,-.001709,.009247,-.003365,0.0*
1,1,.006,.009247,-.003365*
20,1,.006,.009247,-.003365,.008522,-.00492,0.0*
1,1,.006,.008522,-.00492*
20,1,.006,.008522,-.00492,.007538,-.006325,0.0*
1,1,.006,.007538,-.006325*
20,1,.006,.007538,-.006325,.006325,-.007538,0.0*
1,1,.006,.006325,-.007538*
20,1,.006,.006325,-.007538,.00492,-.008522,0.0*
1,1,.006,.00492,-.008522*
20,1,.006,.00492,-.008522,.003365,-.009247,0.0*
1,1,.006,.003365,-.009247*
20,1,.006,.003365,-.009247,.001709,-.009691,0.0*
1,1,.006,.001709,-.009691*
20,1,.006,.001709,-.009691,0.0,-.00984,0.0*
1,1,.006,0.0,-.00984*
20,1,.006,0.0,-.00984,-.001709,-.009691,0.0*
1,1,.006,-.001709,-.009691*
20,1,.006,-.001709,-.009691,-.003365,-.009247,0.0*
1,1,.006,-.003365,-.009247*
20,1,.006,-.003365,-.009247,-.00492,-.008522,0.0*
1,1,.006,-.00492,-.008522*
20,1,.006,-.00492,-.008522,-.006325,-.007538,0.0*
1,1,.006,-.006325,-.007538*
20,1,.006,-.006325,-.007538,-.007538,-.006325,0.0*
1,1,.006,-.007538,-.006325*
20,1,.006,-.007538,-.006325,-.008522,-.00492,0.0*
1,1,.006,-.008522,-.00492*
20,1,.006,-.008522,-.00492,-.009247,-.003365,0.0*
1,1,.006,-.009247,-.003365*
20,1,.006,-.009247,-.003365,-.009691,-.001709,0.0*
1,1,.006,-.009691,-.001709*
20,1,.006,-.009691,-.001709,-.00984,0.0,0.0*
1,1,.006,-.00984,0.0*
20,1,.006,-.00984,0.0,-.009691,.001709,0.0*
1,1,.006,-.009691,.001709*
20,1,.006,-.009691,.001709,-.009247,.003365,0.0*
1,1,.006,-.009247,.003365*
20,1,.006,-.009247,.003365,-.008522,.00492,0.0*
1,1,.006,-.008522,.00492*
20,1,.006,-.008522,.00492,-.007538,.006325,0.0*
1,1,.006,-.007538,.006325*
20,1,.006,-.007538,.006325,-.006325,.007538,0.0*
1,1,.006,-.006325,.007538*
20,1,.006,-.006325,.007538,-.00492,.008522,0.0*
1,1,.006,-.00492,.008522*
20,1,.006,-.00492,.008522,-.003365,.009247,0.0*
1,1,.006,-.003365,.009247*
20,1,.006,-.003365,.009247,-.001709,.009691,0.0*
1,1,.006,-.001709,.009691*
20,1,.006,-.001709,.009691,0.0,.00984,0.0*
1,1,.006,0.0,.00984*
20,1,.006,0.0,.00984,.001709,.009691,0.0*
1,1,.006,.001709,.009691*
20,1,.006,.001709,.009691,.003365,.009247,0.0*
1,1,.006,.003365,.009247*
20,1,.006,.003365,.009247,.00492,.008522,0.0*
1,1,.006,.00492,.008522*
20,1,.006,.00492,.008522,.006325,.007538,0.0*
1,1,.006,.006325,.007538*
20,1,.006,.006325,.007538,.007538,.006325,0.0*
1,1,.006,.007538,.006325*
20,1,.006,.007538,.006325,.008522,.00492,0.0*
1,1,.006,.008522,.00492*
20,1,.006,.008522,.00492,.009247,.003365,0.0*
1,1,.006,.009247,.003365*
20,1,.006,.009247,.003365,.009691,.001709,0.0*
1,1,.006,.009691,.001709*
20,1,.006,.009691,.001709,.00984,0.0,0.0*
1,1,.006,.00984,0.0*
1,1,.006,-.00492,-.00492*
20,1,.006,-.00492,-.00492,-.00492,.00492,0.0*
1,1,.006,-.00492,.00492*
20,1,.006,-.00492,.00492,-.00689,.00295,0.0*
1,1,.006,-.00689,.00295*
1,1,.006,-.00689,-.00492*
20,1,.006,-.00689,-.00492,-.00295,-.00492,0.0*
1,1,.006,-.00295,-.00492*
1,1,.006,.00493,-.00492*
20,1,.006,.00493,-.00492,.00493,.00492,0.0*
1,1,.006,.00493,.00492*
20,1,.006,.00493,.00492,.00296,.00295,0.0*
1,1,.006,.00296,.00295*
1,1,.006,.00296,-.00492*
20,1,.006,.00296,-.00492,.0069,-.00492,0.0*
1,1,.006,.0069,-.00492*
%
%ADD13MACRO13*%
%AMMACRO73*
1,1,.006,-.033,-.018*
20,1,.006,-.033,-.018,-.018,.018,0.0*
1,1,.006,-.018,.018*
20,1,.006,-.018,.018,-.003,-.018,0.0*
1,1,.006,-.003,-.018*
1,1,.006,-.0084,-.0054*
20,1,.006,-.0084,-.0054,-.0276,-.0054,0.0*
1,1,.006,-.0276,-.0054*
1,1,.006,.02281,.0012*
20,1,.006,.02281,.0012,.02521,.003,0.0*
1,1,.006,.02521,.003*
20,1,.006,.02521,.003,.02701,.006,0.0*
1,1,.006,.02701,.006*
20,1,.006,.02701,.006,.02821,.0102,0.0*
1,1,.006,.02821,.0102*
20,1,.006,.02821,.0102,.02701,.0138,0.0*
1,1,.006,.02701,.0138*
20,1,.006,.02701,.0138,.02461,.0162,0.0*
1,1,.006,.02461,.0162*
20,1,.006,.02461,.0162,.02041,.018,0.0*
1,1,.006,.02041,.018*
20,1,.006,.02041,.018,.00421,.018,0.0*
1,1,.006,.00421,.018*
20,1,.006,.00421,.018,.00421,-.018,0.0*
1,1,.006,.00421,-.018*
20,1,.006,.00421,-.018,.02401,-.018,0.0*
1,1,.006,.02401,-.018*
20,1,.006,.02401,-.018,.02821,-.0156,0.0*
1,1,.006,.02821,-.0156*
20,1,.006,.02821,-.0156,.03061,-.012,0.0*
1,1,.006,.03061,-.012*
20,1,.006,.03061,-.012,.03181,-.0078,0.0*
1,1,.006,.03181,-.0078*
20,1,.006,.03181,-.0078,.03061,-.0036,0.0*
1,1,.006,.03061,-.0036*
20,1,.006,.03061,-.0036,.02701,0.0,0.0*
1,1,.006,.02701,0.0*
20,1,.006,.02701,0.0,.02281,.0012,0.0*
1,1,.006,.02281,.0012*
20,1,.006,.02281,.0012,.00421,.0012,0.0*
1,1,.006,.00421,.0012*
%
%ADD73MACRO73*%
%AMMACRO36*
1,1,.006,-.04583,-.025*
20,1,.006,-.04583,-.025,-.025,.025,0.0*
1,1,.006,-.025,.025*
20,1,.006,-.025,.025,-.00417,-.025,0.0*
1,1,.006,-.00417,-.025*
1,1,.006,-.01167,-.0075*
20,1,.006,-.01167,-.0075,-.03833,-.0075,0.0*
1,1,.006,-.03833,-.0075*
1,1,.006,.00834,-.015*
20,1,.006,.00834,-.015,.01251,-.02,0.0*
1,1,.006,.01251,-.02*
20,1,.006,.01251,-.02,.01751,-.02333,0.0*
1,1,.006,.01751,-.02333*
20,1,.006,.01751,-.02333,.02334,-.025,0.0*
1,1,.006,.02334,-.025*
20,1,.006,.02334,-.025,.03001,-.02333,0.0*
1,1,.006,.03001,-.02333*
20,1,.006,.03001,-.02333,.03501,-.02,0.0*
1,1,.006,.03501,-.02*
20,1,.006,.03501,-.02,.04001,-.015,0.0*
1,1,.006,.04001,-.015*
20,1,.006,.04001,-.015,.04168,-.00833,0.0*
1,1,.006,.04168,-.00833*
20,1,.006,.04168,-.00833,.04168,.025,0.0*
1,1,.006,.04168,.025*
%
%ADD36MACRO36*%
%AMMACRO42*
1,1,.006,-.04033,-.022*
20,1,.006,-.04033,-.022,-.022,.022,0.0*
1,1,.006,-.022,.022*
20,1,.006,-.022,.022,-.00367,-.022,0.0*
1,1,.006,-.00367,-.022*
1,1,.006,-.01027,-.0066*
20,1,.006,-.01027,-.0066,-.03373,-.0066,0.0*
1,1,.006,-.03373,-.0066*
1,1,.006,.00808,-.022*
20,1,.006,.00808,-.022,.00808,.022,0.0*
1,1,.006,.00808,.022*
20,1,.006,.00808,.022,.03594,.022,0.0*
1,1,.006,.03594,.022*
1,1,.006,.02568,.00073*
20,1,.006,.02568,.00073,.00808,.00073,0.0*
1,1,.006,.00808,.00073*
%
%ADD42MACRO42*%
%AMMACRO32*
1,1,.006,-.1375,-.075*
20,1,.006,-.1375,-.075,-.075,.075,0.0*
1,1,.006,-.075,.075*
20,1,.006,-.075,.075,-.0125,-.075,0.0*
1,1,.006,-.0125,-.075*
1,1,.006,-.035,-.0225*
20,1,.006,-.035,-.0225,-.115,-.0225,0.0*
1,1,.006,-.115,-.0225*
1,1,.006,.02251,-.055*
20,1,.006,.02251,-.055,.04251,-.0675,0.0*
1,1,.006,.04251,-.0675*
20,1,.006,.04251,-.0675,.06501,-.075,0.0*
1,1,.006,.06501,-.075*
20,1,.006,.06501,-.075,.08501,-.075,0.0*
1,1,.006,.08501,-.075*
20,1,.006,.08501,-.075,.10501,-.0675,0.0*
1,1,.006,.10501,-.0675*
20,1,.006,.10501,-.0675,.12001,-.055,0.0*
1,1,.006,.12001,-.055*
20,1,.006,.12001,-.055,.12751,-.0375,0.0*
1,1,.006,.12751,-.0375*
20,1,.006,.12751,-.0375,.12251,-.02,0.0*
1,1,.006,.12251,-.02*
20,1,.006,.12251,-.02,.11001,-.005,0.0*
1,1,.006,.11001,-.005*
20,1,.006,.11001,-.005,.08751,.005,0.0*
1,1,.006,.08751,.005*
20,1,.006,.08751,.005,.05751,.01,0.0*
1,1,.006,.05751,.01*
20,1,.006,.05751,.01,.04001,.02,0.0*
1,1,.006,.04001,.02*
20,1,.006,.04001,.02,.03251,.0375,0.0*
1,1,.006,.03251,.0375*
20,1,.006,.03251,.0375,.03751,.055,0.0*
1,1,.006,.03751,.055*
20,1,.006,.03751,.055,.05001,.0675,0.0*
1,1,.006,.05001,.0675*
20,1,.006,.05001,.0675,.06751,.075,0.0*
1,1,.006,.06751,.075*
20,1,.006,.06751,.075,.08501,.075,0.0*
1,1,.006,.08501,.075*
20,1,.006,.08501,.075,.10251,.07,0.0*
1,1,.006,.10251,.07*
20,1,.006,.10251,.07,.11751,.0575,0.0*
1,1,.006,.11751,.0575*
%
%ADD32MACRO32*%
%AMMACRO40*
1,1,.006,-.03575,-.0195*
20,1,.006,-.03575,-.0195,-.0195,.0195,0.0*
1,1,.006,-.0195,.0195*
20,1,.006,-.0195,.0195,-.00325,-.0195,0.0*
1,1,.006,-.00325,-.0195*
1,1,.006,-.0091,-.00585*
20,1,.006,-.0091,-.00585,-.0299,-.00585,0.0*
1,1,.006,-.0299,-.00585*
1,1,.006,.03381,.01625*
20,1,.006,.03381,.01625,.02991,.0182,0.0*
1,1,.006,.02991,.0182*
20,1,.006,.02991,.0182,.02536,.0195,0.0*
1,1,.006,.02536,.0195*
20,1,.006,.02536,.0195,.02016,.0195,0.0*
1,1,.006,.02016,.0195*
20,1,.006,.02016,.0195,.01431,.01755,0.0*
1,1,.006,.01431,.01755*
20,1,.006,.01431,.01755,.00976,.0143,0.0*
1,1,.006,.00976,.0143*
20,1,.006,.00976,.0143,.00651,.0104,0.0*
1,1,.006,.00651,.0104*
20,1,.006,.00651,.0104,.00391,.0039,0.0*
1,1,.006,.00391,.0039*
20,1,.006,.00391,.0039,.00326,-.00195,0.0*
1,1,.006,.00326,-.00195*
20,1,.006,.00326,-.00195,.00456,-.0078,0.0*
1,1,.006,.00456,-.0078*
20,1,.006,.00456,-.0078,.00651,-.0117,0.0*
1,1,.006,.00651,-.0117*
20,1,.006,.00651,-.0117,.01041,-.0156,0.0*
1,1,.006,.01041,-.0156*
20,1,.006,.01041,-.0156,.01496,-.0182,0.0*
1,1,.006,.01496,-.0182*
20,1,.006,.01496,-.0182,.01951,-.0195,0.0*
1,1,.006,.01951,-.0195*
20,1,.006,.01951,-.0195,.02406,-.0195,0.0*
1,1,.006,.02406,-.0195*
20,1,.006,.02406,-.0195,.02861,-.0182,0.0*
1,1,.006,.02861,-.0182*
20,1,.006,.02861,-.0182,.03251,-.01625,0.0*
1,1,.006,.03251,-.01625*
20,1,.006,.03251,-.01625,.03576,-.01365,0.0*
1,1,.006,.03576,-.01365*
%
%ADD40MACRO40*%
%AMMACRO23*
1,1,.006,-.04217,-.023*
20,1,.006,-.04217,-.023,-.023,.023,0.0*
1,1,.006,-.023,.023*
20,1,.006,-.023,.023,-.00383,-.023,0.0*
1,1,.006,-.00383,-.023*
1,1,.006,-.01073,-.0069*
20,1,.006,-.01073,-.0069,-.03527,-.0069,0.0*
1,1,.006,-.03527,-.0069*
1,1,.006,.02761,0.0*
20,1,.006,.02761,0.0,.04294,0.0,0.0*
1,1,.006,.04294,0.0*
20,1,.006,.04294,0.0,.04294,-.0138,0.0*
1,1,.006,.04294,-.0138*
20,1,.006,.04294,-.0138,.03834,-.0184,0.0*
1,1,.006,.03834,-.0184*
20,1,.006,.03834,-.0184,.03298,-.02147,0.0*
1,1,.006,.03298,-.02147*
20,1,.006,.03298,-.02147,.02531,-.023,0.0*
1,1,.006,.02531,-.023*
20,1,.006,.02531,-.023,.01764,-.02147,0.0*
1,1,.006,.01764,-.02147*
20,1,.006,.01764,-.02147,.01228,-.0184,0.0*
1,1,.006,.01228,-.0184*
20,1,.006,.01228,-.0184,.00768,-.0138,0.0*
1,1,.006,.00768,-.0138*
20,1,.006,.00768,-.0138,.00461,-.00843,0.0*
1,1,.006,.00461,-.00843*
20,1,.006,.00461,-.00843,.00308,-.0023,0.0*
1,1,.006,.00308,-.0023*
20,1,.006,.00308,-.0023,.00308,.00307,0.0*
1,1,.006,.00308,.00307*
20,1,.006,.00308,.00307,.00461,.00767,0.0*
1,1,.006,.00461,.00767*
20,1,.006,.00461,.00767,.00768,.01303,0.0*
1,1,.006,.00768,.01303*
20,1,.006,.00768,.01303,.01228,.01763,0.0*
1,1,.006,.01228,.01763*
20,1,.006,.01228,.01763,.01688,.0207,0.0*
1,1,.006,.01688,.0207*
20,1,.006,.01688,.0207,.02301,.023,0.0*
1,1,.006,.02301,.023*
20,1,.006,.02301,.023,.02838,.023,0.0*
1,1,.006,.02838,.023*
20,1,.006,.02838,.023,.03451,.02147,0.0*
1,1,.006,.03451,.02147*
20,1,.006,.03451,.02147,.03911,.0184,0.0*
1,1,.006,.03911,.0184*
%
%ADD23MACRO23*%
%AMMACRO50*
1,1,.006,-.0495,-.027*
20,1,.006,-.0495,-.027,-.027,.027,0.0*
1,1,.006,-.027,.027*
20,1,.006,-.027,.027,-.0045,-.027,0.0*
1,1,.006,-.0045,-.027*
1,1,.006,-.0126,-.0081*
20,1,.006,-.0126,-.0081,-.0414,-.0081,0.0*
1,1,.006,-.0414,-.0081*
1,1,.006,.00721,-.027*
20,1,.006,.00721,-.027,.00721,.027,0.0*
1,1,.006,.00721,.027*
1,1,.006,.04141,.027*
20,1,.006,.04141,.027,.00721,-.0063,0.0*
1,1,.006,.00721,-.0063*
1,1,.006,.04681,-.027*
20,1,.006,.04681,-.027,.02251,.009,0.0*
1,1,.006,.02251,.009*
%
%ADD50MACRO50*%
%AMMACRO31*
1,1,.006,-.11459,-.0625*
20,1,.006,-.11459,-.0625,-.0625,.0625,0.0*
1,1,.006,-.0625,.0625*
20,1,.006,-.0625,.0625,-.01041,-.0625,0.0*
1,1,.006,-.01041,-.0625*
1,1,.006,-.02917,-.01875*
20,1,.006,-.02917,-.01875,-.09584,-.01875,0.0*
1,1,.006,-.09584,-.01875*
1,1,.006,.02084,-.0625*
20,1,.006,.02084,-.0625,.02084,.0625,0.0*
1,1,.006,.02084,.0625*
20,1,.006,.02084,.0625,.07293,.0625,0.0*
1,1,.006,.07293,.0625*
20,1,.006,.07293,.0625,.08959,.05625,0.0*
1,1,.006,.08959,.05625*
20,1,.006,.08959,.05625,.10001,.04792,0.0*
1,1,.006,.10001,.04792*
20,1,.006,.10001,.04792,.10418,.03125,0.0*
1,1,.006,.10418,.03125*
20,1,.006,.10418,.03125,.10001,.01458,0.0*
1,1,.006,.10001,.01458*
20,1,.006,.10001,.01458,.08751,.00417,0.0*
1,1,.006,.08751,.00417*
20,1,.006,.08751,.00417,.07293,-.00208,0.0*
1,1,.006,.07293,-.00208*
20,1,.006,.07293,-.00208,.02084,-.00208,0.0*
1,1,.006,.02084,-.00208*
1,1,.006,.07293,-.00208*
20,1,.006,.07293,-.00208,.10418,-.0625,0.0*
1,1,.006,.10418,-.0625*
%
%ADD31MACRO31*%
%AMMACRO54*
1,1,.006,-.04308,-.0235*
20,1,.006,-.04308,-.0235,-.0235,.0235,0.0*
1,1,.006,-.0235,.0235*
20,1,.006,-.0235,.0235,-.00392,-.0235,0.0*
1,1,.006,-.00392,-.0235*
1,1,.006,-.01097,-.00705*
20,1,.006,-.01097,-.00705,-.03603,-.00705,0.0*
1,1,.006,-.03603,-.00705*
1,1,.006,.00706,-.0235*
20,1,.006,.00706,-.0235,.00706,.0235,0.0*
1,1,.006,.00706,.0235*
1,1,.006,.03996,.0235*
20,1,.006,.03996,.0235,.03996,-.0235,0.0*
1,1,.006,.03996,-.0235*
1,1,.006,.03996,0.0*
20,1,.006,.03996,0.0,.00706,0.0,0.0*
1,1,.006,.00706,0.0*
%
%ADD54MACRO54*%
%AMMACRO43*
1,1,.006,-.05775,-.0315*
20,1,.006,-.05775,-.0315,-.0315,.0315,0.0*
1,1,.006,-.0315,.0315*
20,1,.006,-.0315,.0315,-.00525,-.0315,0.0*
1,1,.006,-.00525,-.0315*
1,1,.006,-.0147,-.00945*
20,1,.006,-.0147,-.00945,-.0483,-.00945,0.0*
1,1,.006,-.0483,-.00945*
1,1,.006,.00421,-.0315*
20,1,.006,.00421,-.0315,.00421,.0315,0.0*
1,1,.006,.00421,.0315*
20,1,.006,.00421,.0315,.03151,-.021,0.0*
1,1,.006,.03151,-.021*
20,1,.006,.03151,-.021,.05881,.0315,0.0*
1,1,.006,.05881,.0315*
20,1,.006,.05881,.0315,.05881,-.0315,0.0*
1,1,.006,.05881,-.0315*
%
%ADD43MACRO43*%
%AMMACRO68*
1,1,.006,.0005,0.0*
20,1,.006,.0005,0.0,-.0005,0.0,0.0*
1,1,.006,-.0005,0.0*
1,1,.006,0.0,.0005*
20,1,.006,0.0,.0005,0.0,-.0005,0.0*
1,1,.006,0.0,-.0005*
1,1,.006,.00025,0.0*
20,1,.006,.00025,0.0,.00025,.0005,0.0*
1,1,.006,.00025,.0005*
20,1,.006,.00025,.0005,.00015,.0004,0.0*
1,1,.006,.00015,.0004*
1,1,.006,.00015,0.0*
20,1,.006,.00015,0.0,.00035,0.0,0.0*
1,1,.006,.00035,0.0*
%
%ADD68MACRO68*%
%AMMACRO10*
1,1,.006,.002485,-.006*
20,1,.006,.002485,-.006,-.002485,-.006,0.0*
1,1,.006,-.002485,-.006*
20,1,.006,-.002485,-.006,-.006,-.002485,0.0*
1,1,.006,-.006,-.002485*
20,1,.006,-.006,-.002485,-.006,.002485,0.0*
1,1,.006,-.006,.002485*
20,1,.006,-.006,.002485,-.002485,.006,0.0*
1,1,.006,-.002485,.006*
20,1,.006,-.002485,.006,.002485,.006,0.0*
1,1,.006,.002485,.006*
20,1,.006,.002485,.006,.006,.002485,0.0*
1,1,.006,.006,.002485*
20,1,.006,.006,.002485,.006,-.002485,0.0*
1,1,.006,.006,-.002485*
20,1,.006,.006,-.002485,.002485,-.006,0.0*
1,1,.006,.002485,-.006*
1,1,.006,-.0022,-.0021*
20,1,.006,-.0022,-.0021,-.0016,-.0026,0.0*
1,1,.006,-.0016,-.0026*
20,1,.006,-.0016,-.0026,-.0009,-.0029,0.0*
1,1,.006,-.0009,-.0029*
20,1,.006,-.0009,-.0029,0.0,-.003,0.0*
1,1,.006,0.0,-.003*
20,1,.006,0.0,-.003,.0009,-.0028,0.0*
1,1,.006,.0009,-.0028*
20,1,.006,.0009,-.0028,.0016,-.0024,0.0*
1,1,.006,.0016,-.0024*
20,1,.006,.0016,-.0024,.0021,-.0017,0.0*
1,1,.006,.0021,-.0017*
20,1,.006,.0021,-.0017,.0022,-.0009,0.0*
1,1,.006,.0022,-.0009*
20,1,.006,.0022,-.0009,.002,-.0001,0.0*
1,1,.006,.002,-.0001*
20,1,.006,.002,-.0001,.0015,.0004,0.0*
1,1,.006,.0015,.0004*
20,1,.006,.0015,.0004,.0008,.0008,0.0*
1,1,.006,.0008,.0008*
20,1,.006,.0008,.0008,.0001,.0009,0.0*
1,1,.006,.0001,.0009*
20,1,.006,.0001,.0009,-.0006,.0008,0.0*
1,1,.006,-.0006,.0008*
20,1,.006,-.0006,.0008,-.0015,.0004,0.0*
1,1,.006,-.0015,.0004*
20,1,.006,-.0015,.0004,-.0012,.003,0.0*
1,1,.006,-.0012,.003*
20,1,.006,-.0012,.003,.0015,.003,0.0*
1,1,.006,.0015,.003*
%
%ADD10MACRO10*%
%AMMACRO52*
1,1,.006,-.05958,-.0325*
20,1,.006,-.05958,-.0325,-.0325,.0325,0.0*
1,1,.006,-.0325,.0325*
20,1,.006,-.0325,.0325,-.00542,-.0325,0.0*
1,1,.006,-.00542,-.0325*
1,1,.006,-.01517,-.00975*
20,1,.006,-.01517,-.00975,-.04983,-.00975,0.0*
1,1,.006,-.04983,-.00975*
1,1,.006,.00759,-.0325*
20,1,.006,.00759,-.0325,.00759,.0325,0.0*
1,1,.006,.00759,.0325*
20,1,.006,.00759,.0325,.05743,-.0325,0.0*
1,1,.006,.05743,-.0325*
20,1,.006,.05743,-.0325,.05743,.0325,0.0*
1,1,.006,.05743,.0325*
%
%ADD52MACRO52*%
%AMMACRO26*
1,1,.006,.006,0.0*
20,1,.006,.006,0.0,0.0,-.006,0.0*
1,1,.006,0.0,-.006*
20,1,.006,0.0,-.006,-.006,0.0,0.0*
1,1,.006,-.006,0.0*
20,1,.006,-.006,0.0,0.0,.006,0.0*
1,1,.006,0.0,.006*
20,1,.006,0.0,.006,.006,0.0,0.0*
1,1,.006,.006,0.0*
1,1,.006,-.0019,-.0005*
20,1,.006,-.0019,-.0005,-.0012,.0002,0.0*
1,1,.006,-.0012,.0002*
20,1,.006,-.0012,.0002,-.0006,.0006,0.0*
1,1,.006,-.0006,.0006*
20,1,.006,-.0006,.0006,.0002,.0008,0.0*
1,1,.006,.0002,.0008*
20,1,.006,.0002,.0008,.0009,.0006,0.0*
1,1,.006,.0009,.0006*
20,1,.006,.0009,.0006,.0014,.0002,0.0*
1,1,.006,.0014,.0002*
20,1,.006,.0014,.0002,.0018,-.0004,0.0*
1,1,.006,.0018,-.0004*
20,1,.006,.0018,-.0004,.0019,-.0011,0.0*
1,1,.006,.0019,-.0011*
20,1,.006,.0019,-.0011,.0018,-.0017,0.0*
1,1,.006,.0018,-.0017*
20,1,.006,.0018,-.0017,.0014,-.0023,0.0*
1,1,.006,.0014,-.0023*
20,1,.006,.0014,-.0023,.0008,-.0028,0.0*
1,1,.006,.0008,-.0028*
20,1,.006,.0008,-.0028,.0001,-.003,0.0*
1,1,.006,.0001,-.003*
20,1,.006,.0001,-.003,-.0007,-.0028,0.0*
1,1,.006,-.0007,-.0028*
20,1,.006,-.0007,-.0028,-.0014,-.0022,0.0*
1,1,.006,-.0014,-.0022*
20,1,.006,-.0014,-.0022,-.0018,-.0013,0.0*
1,1,.006,-.0018,-.0013*
20,1,.006,-.0018,-.0013,-.0019,-.0003,0.0*
1,1,.006,-.0019,-.0003*
20,1,.006,-.0019,-.0003,-.0017,.001,0.0*
1,1,.006,-.0017,.001*
20,1,.006,-.0017,.001,-.0014,.0017,0.0*
1,1,.006,-.0014,.0017*
20,1,.006,-.0014,.0017,-.0009,.0024,0.0*
1,1,.006,-.0009,.0024*
20,1,.006,-.0009,.0024,-.0002,.0029,0.0*
1,1,.006,-.0002,.0029*
20,1,.006,-.0002,.0029,.0005,.003,0.0*
1,1,.006,.0005,.003*
20,1,.006,.0005,.003,.0012,.0028,0.0*
1,1,.006,.0012,.0028*
20,1,.006,.0012,.0028,.0017,.0023,0.0*
1,1,.006,.0017,.0023*
%
%ADD26MACRO26*%
%AMMACRO18*
1,1,.006,-.077,-.042*
20,1,.006,-.077,-.042,-.042,.042,0.0*
1,1,.006,-.042,.042*
20,1,.006,-.042,.042,-.007,-.042,0.0*
1,1,.006,-.007,-.042*
1,1,.006,-.0196,-.0126*
20,1,.006,-.0196,-.0126,-.0644,-.0126,0.0*
1,1,.006,-.0644,-.0126*
1,1,.006,.04201,-.042*
20,1,.006,.04201,-.042,.03081,-.0406,0.0*
1,1,.006,.03081,-.0406*
20,1,.006,.03081,-.0406,.02101,-.035,0.0*
1,1,.006,.02101,-.035*
20,1,.006,.02101,-.035,.01261,-.0266,0.0*
1,1,.006,.01261,-.0266*
20,1,.006,.01261,-.0266,.00701,-.0168,0.0*
1,1,.006,.00701,-.0168*
20,1,.006,.00701,-.0168,.00421,-.0056,0.0*
1,1,.006,.00421,-.0056*
20,1,.006,.00421,-.0056,.00421,.0056,0.0*
1,1,.006,.00421,.0056*
20,1,.006,.00421,.0056,.00701,.0168,0.0*
1,1,.006,.00701,.0168*
20,1,.006,.00701,.0168,.01261,.0266,0.0*
1,1,.006,.01261,.0266*
20,1,.006,.01261,.0266,.02101,.035,0.0*
1,1,.006,.02101,.035*
20,1,.006,.02101,.035,.03081,.0406,0.0*
1,1,.006,.03081,.0406*
20,1,.006,.03081,.0406,.04201,.042,0.0*
1,1,.006,.04201,.042*
20,1,.006,.04201,.042,.05321,.0406,0.0*
1,1,.006,.05321,.0406*
20,1,.006,.05321,.0406,.06301,.035,0.0*
1,1,.006,.06301,.035*
20,1,.006,.06301,.035,.07141,.0266,0.0*
1,1,.006,.07141,.0266*
20,1,.006,.07141,.0266,.07701,.0168,0.0*
1,1,.006,.07701,.0168*
20,1,.006,.07701,.0168,.07981,.0056,0.0*
1,1,.006,.07981,.0056*
20,1,.006,.07981,.0056,.07981,-.0056,0.0*
1,1,.006,.07981,-.0056*
20,1,.006,.07981,-.0056,.07701,-.0168,0.0*
1,1,.006,.07701,-.0168*
20,1,.006,.07701,-.0168,.07141,-.0266,0.0*
1,1,.006,.07141,-.0266*
20,1,.006,.07141,-.0266,.06301,-.035,0.0*
1,1,.006,.06301,-.035*
20,1,.006,.06301,-.035,.05321,-.0406,0.0*
1,1,.006,.05321,-.0406*
20,1,.006,.05321,-.0406,.04201,-.042,0.0*
1,1,.006,.04201,-.042*
%
%ADD18MACRO18*%
%AMMACRO22*
1,1,.006,-.05408,-.0295*
20,1,.006,-.05408,-.0295,-.0295,.0295,0.0*
1,1,.006,-.0295,.0295*
20,1,.006,-.0295,.0295,-.00492,-.0295,0.0*
1,1,.006,-.00492,-.0295*
1,1,.006,-.01377,-.00885*
20,1,.006,-.01377,-.00885,-.04523,-.00885,0.0*
1,1,.006,-.04523,-.00885*
1,1,.006,.00984,.0295*
20,1,.006,.00984,.0295,.00984,-.0295,0.0*
1,1,.006,.00984,-.0295*
20,1,.006,.00984,-.0295,.04918,-.0295,0.0*
1,1,.006,.04918,-.0295*
%
%ADD22MACRO22*%
%AMMACRO16*
1,1,.006,-.07883,-.043*
20,1,.006,-.07883,-.043,-.043,.043,0.0*
1,1,.006,-.043,.043*
20,1,.006,-.043,.043,-.00717,-.043,0.0*
1,1,.006,-.00717,-.043*
1,1,.006,-.02007,-.0129*
20,1,.006,-.02007,-.0129,-.06593,-.0129,0.0*
1,1,.006,-.06593,-.0129*
1,1,.006,.01434,-.043*
20,1,.006,.01434,-.043,.01434,.043,0.0*
1,1,.006,.01434,.043*
20,1,.006,.01434,.043,.04874,.043,0.0*
1,1,.006,.04874,.043*
20,1,.006,.04874,.043,.06021,.0387,0.0*
1,1,.006,.06021,.0387*
20,1,.006,.06021,.0387,.06881,.02867,0.0*
1,1,.006,.06881,.02867*
20,1,.006,.06881,.02867,.07168,.0172,0.0*
1,1,.006,.07168,.0172*
20,1,.006,.07168,.0172,.06881,.00573,0.0*
1,1,.006,.06881,.00573*
20,1,.006,.06881,.00573,.06164,-.00287,0.0*
1,1,.006,.06164,-.00287*
20,1,.006,.06164,-.00287,.04874,-.00717,0.0*
1,1,.006,.04874,-.00717*
20,1,.006,.04874,-.00717,.01434,-.00717,0.0*
1,1,.006,.01434,-.00717*
%
%ADD16MACRO16*%
%AMMACRO56*
1,1,.006,-.00917,-.011*
20,1,.006,-.00917,-.011,0.0,.011,0.0*
1,1,.006,0.0,.011*
20,1,.006,0.0,.011,.00917,-.011,0.0*
1,1,.006,.00917,-.011*
1,1,.006,.00587,-.0033*
20,1,.006,.00587,-.0033,-.00587,-.0033,0.0*
1,1,.006,-.00587,-.0033*
%
%ADD56MACRO56*%
%AMMACRO62*
1,1,.006,.01,-.015*
20,1,.006,.01,-.015,-.01,-.015,0.0*
1,1,.006,-.01,-.015*
20,1,.006,-.01,-.015,-.01,.015,0.0*
1,1,.006,-.01,.015*
20,1,.006,-.01,.015,.01,.015,0.0*
1,1,.006,.01,.015*
1,1,.006,.002,.0005*
20,1,.006,.002,.0005,-.01,.0005,0.0*
1,1,.006,-.01,.0005*
%
%ADD62MACRO62*%
%AMMACRO48*
1,1,.006,-.07975,-.0435*
20,1,.006,-.07975,-.0435,-.0435,.0435,0.0*
1,1,.006,-.0435,.0435*
20,1,.006,-.0435,.0435,-.00725,-.0435,0.0*
1,1,.006,-.00725,-.0435*
1,1,.006,-.0203,-.01305*
20,1,.006,-.0203,-.01305,-.0667,-.01305,0.0*
1,1,.006,-.0667,-.01305*
1,1,.006,.04351,-.0435*
20,1,.006,.04351,-.0435,.03191,-.04205,0.0*
1,1,.006,.03191,-.04205*
20,1,.006,.03191,-.04205,.02176,-.03625,0.0*
1,1,.006,.02176,-.03625*
20,1,.006,.02176,-.03625,.01306,-.02755,0.0*
1,1,.006,.01306,-.02755*
20,1,.006,.01306,-.02755,.00726,-.0174,0.0*
1,1,.006,.00726,-.0174*
20,1,.006,.00726,-.0174,.00436,-.0058,0.0*
1,1,.006,.00436,-.0058*
20,1,.006,.00436,-.0058,.00436,.0058,0.0*
1,1,.006,.00436,.0058*
20,1,.006,.00436,.0058,.00726,.0174,0.0*
1,1,.006,.00726,.0174*
20,1,.006,.00726,.0174,.01306,.02755,0.0*
1,1,.006,.01306,.02755*
20,1,.006,.01306,.02755,.02176,.03625,0.0*
1,1,.006,.02176,.03625*
20,1,.006,.02176,.03625,.03191,.04205,0.0*
1,1,.006,.03191,.04205*
20,1,.006,.03191,.04205,.04351,.0435,0.0*
1,1,.006,.04351,.0435*
20,1,.006,.04351,.0435,.05511,.04205,0.0*
1,1,.006,.05511,.04205*
20,1,.006,.05511,.04205,.06526,.03625,0.0*
1,1,.006,.06526,.03625*
20,1,.006,.06526,.03625,.07396,.02755,0.0*
1,1,.006,.07396,.02755*
20,1,.006,.07396,.02755,.07976,.0174,0.0*
1,1,.006,.07976,.0174*
20,1,.006,.07976,.0174,.08266,.0058,0.0*
1,1,.006,.08266,.0058*
20,1,.006,.08266,.0058,.08266,-.0058,0.0*
1,1,.006,.08266,-.0058*
20,1,.006,.08266,-.0058,.07976,-.0174,0.0*
1,1,.006,.07976,-.0174*
20,1,.006,.07976,-.0174,.07396,-.02755,0.0*
1,1,.006,.07396,-.02755*
20,1,.006,.07396,-.02755,.06526,-.03625,0.0*
1,1,.006,.06526,-.03625*
20,1,.006,.06526,-.03625,.05511,-.04205,0.0*
1,1,.006,.05511,-.04205*
20,1,.006,.05511,-.04205,.04351,-.0435,0.0*
1,1,.006,.04351,-.0435*
1,1,.006,.05511,-.0203*
20,1,.006,.05511,-.0203,.07251,-.0435,0.0*
1,1,.006,.07251,-.0435*
%
%ADD48MACRO48*%
%AMMACRO34*
1,1,.006,.004,.004*
20,1,.006,.004,.004,.004,-.004,0.0*
1,1,.006,.004,-.004*
20,1,.006,.004,-.004,-.004,-.004,0.0*
1,1,.006,-.004,-.004*
20,1,.006,-.004,-.004,-.004,.004,0.0*
1,1,.006,-.004,.004*
20,1,.006,-.004,.004,.004,.004,0.0*
1,1,.006,.004,.004*
1,1,.006,-.00127,.00133*
20,1,.006,-.00127,.00133,-.00087,.00173,0.0*
1,1,.006,-.00087,.00173*
20,1,.006,-.00087,.00173,-.0004,.00193,0.0*
1,1,.006,-.0004,.00193*
20,1,.006,-.0004,.00193,.00013,.002,0.0*
1,1,.006,.00013,.002*
20,1,.006,.00013,.002,.0008,.00187,0.0*
1,1,.006,.0008,.00187*
20,1,.006,.0008,.00187,.00127,.00153,0.0*
1,1,.006,.00127,.00153*
20,1,.006,.00127,.00153,.0014,.00113,0.0*
1,1,.006,.0014,.00113*
20,1,.006,.0014,.00113,.00133,.00073,0.0*
1,1,.006,.00133,.00073*
20,1,.006,.00133,.00073,.00107,.0004,0.0*
1,1,.006,.00107,.0004*
20,1,.006,.00107,.0004,-.00027,-.00027,0.0*
1,1,.006,-.00027,-.00027*
20,1,.006,-.00027,-.00027,-.00087,-.00073,0.0*
1,1,.006,-.00087,-.00073*
20,1,.006,-.00087,-.00073,-.00127,-.0014,0.0*
1,1,.006,-.00127,-.0014*
20,1,.006,-.00127,-.0014,-.0014,-.002,0.0*
1,1,.006,-.0014,-.002*
20,1,.006,-.0014,-.002,.0014,-.002,0.0*
1,1,.006,.0014,-.002*
%
%ADD34MACRO34*%
%AMMACRO21*
1,1,.006,-.0095,-.015*
20,1,.006,-.0095,-.015,-.0095,.015,0.0*
1,1,.006,-.0095,.015*
20,1,.006,-.0095,.015,.0095,.015,0.0*
1,1,.006,.0095,.015*
1,1,.006,.0025,.0005*
20,1,.006,.0025,.0005,-.0095,.0005,0.0*
1,1,.006,-.0095,.0005*
%
%ADD21MACRO21*%
%AMMACRO28*
1,1,.006,.0032,.0008*
20,1,.006,.0032,.0008,.0048,.002,0.0*
1,1,.006,.0048,.002*
20,1,.006,.0048,.002,.006,.004,0.0*
1,1,.006,.006,.004*
20,1,.006,.006,.004,.0068,.0068,0.0*
1,1,.006,.0068,.0068*
20,1,.006,.0068,.0068,.006,.0092,0.0*
1,1,.006,.006,.0092*
20,1,.006,.006,.0092,.0044,.0108,0.0*
1,1,.006,.0044,.0108*
20,1,.006,.0044,.0108,.0016,.012,0.0*
1,1,.006,.0016,.012*
20,1,.006,.0016,.012,-.0092,.012,0.0*
1,1,.006,-.0092,.012*
20,1,.006,-.0092,.012,-.0092,-.012,0.0*
1,1,.006,-.0092,-.012*
20,1,.006,-.0092,-.012,.004,-.012,0.0*
1,1,.006,.004,-.012*
20,1,.006,.004,-.012,.0068,-.0104,0.0*
1,1,.006,.0068,-.0104*
20,1,.006,.0068,-.0104,.0084,-.008,0.0*
1,1,.006,.0084,-.008*
20,1,.006,.0084,-.008,.0092,-.0052,0.0*
1,1,.006,.0092,-.0052*
20,1,.006,.0092,-.0052,.0084,-.0024,0.0*
1,1,.006,.0084,-.0024*
20,1,.006,.0084,-.0024,.006,0.0,0.0*
1,1,.006,.006,0.0*
20,1,.006,.006,0.0,.0032,.0008,0.0*
1,1,.006,.0032,.0008*
20,1,.006,.0032,.0008,-.0092,.0008,0.0*
1,1,.006,-.0092,.0008*
%
%ADD28MACRO28*%
%AMMACRO29*
1,1,.006,.0031,0.0*
20,1,.006,.0031,0.0,.01343,0.0,0.0*
1,1,.006,.01343,0.0*
20,1,.006,.01343,0.0,.01343,-.0093,0.0*
1,1,.006,.01343,-.0093*
20,1,.006,.01343,-.0093,.01033,-.0124,0.0*
1,1,.006,.01033,-.0124*
20,1,.006,.01033,-.0124,.00672,-.01447,0.0*
1,1,.006,.00672,-.01447*
20,1,.006,.00672,-.01447,.00155,-.0155,0.0*
1,1,.006,.00155,-.0155*
20,1,.006,.00155,-.0155,-.00362,-.01447,0.0*
1,1,.006,-.00362,-.01447*
20,1,.006,-.00362,-.01447,-.00723,-.0124,0.0*
1,1,.006,-.00723,-.0124*
20,1,.006,-.00723,-.0124,-.01033,-.0093,0.0*
1,1,.006,-.01033,-.0093*
20,1,.006,-.01033,-.0093,-.0124,-.00568,0.0*
1,1,.006,-.0124,-.00568*
20,1,.006,-.0124,-.00568,-.01343,-.00155,0.0*
1,1,.006,-.01343,-.00155*
20,1,.006,-.01343,-.00155,-.01343,.00207,0.0*
1,1,.006,-.01343,.00207*
20,1,.006,-.01343,.00207,-.0124,.00517,0.0*
1,1,.006,-.0124,.00517*
20,1,.006,-.0124,.00517,-.01033,.00878,0.0*
1,1,.006,-.01033,.00878*
20,1,.006,-.01033,.00878,-.00723,.01188,0.0*
1,1,.006,-.00723,.01188*
20,1,.006,-.00723,.01188,-.00413,.01395,0.0*
1,1,.006,-.00413,.01395*
20,1,.006,-.00413,.01395,0.0,.0155,0.0*
1,1,.006,0.0,.0155*
20,1,.006,0.0,.0155,.00362,.0155,0.0*
1,1,.006,.00362,.0155*
20,1,.006,.00362,.0155,.00775,.01447,0.0*
1,1,.006,.00775,.01447*
20,1,.006,.00775,.01447,.01085,.0124,0.0*
1,1,.006,.01085,.0124*
%
%ADD29MACRO29*%
%AMMACRO64*
1,1,.006,-.0112,-.016*
20,1,.006,-.0112,-.016,-.0112,.016,0.0*
1,1,.006,-.0112,.016*
1,1,.006,.0112,.016*
20,1,.006,.0112,.016,.0112,-.016,0.0*
1,1,.006,.0112,-.016*
1,1,.006,.0112,0.0*
20,1,.006,.0112,0.0,-.0112,0.0,0.0*
1,1,.006,-.0112,0.0*
%
%ADD64MACRO64*%
%AMMACRO53*
1,1,.006,.00953,.01083*
20,1,.006,.00953,.01083,.00693,.01213,0.0*
1,1,.006,.00693,.01213*
20,1,.006,.00693,.01213,.0039,.013,0.0*
1,1,.006,.0039,.013*
20,1,.006,.0039,.013,.00043,.013,0.0*
1,1,.006,.00043,.013*
20,1,.006,.00043,.013,-.00347,.0117,0.0*
1,1,.006,-.00347,.0117*
20,1,.006,-.00347,.0117,-.0065,.00953,0.0*
1,1,.006,-.0065,.00953*
20,1,.006,-.0065,.00953,-.00867,.00693,0.0*
1,1,.006,-.00867,.00693*
20,1,.006,-.00867,.00693,-.0104,.0026,0.0*
1,1,.006,-.0104,.0026*
20,1,.006,-.0104,.0026,-.01083,-.0013,0.0*
1,1,.006,-.01083,-.0013*
20,1,.006,-.01083,-.0013,-.00997,-.0052,0.0*
1,1,.006,-.00997,-.0052*
20,1,.006,-.00997,-.0052,-.00867,-.0078,0.0*
1,1,.006,-.00867,-.0078*
20,1,.006,-.00867,-.0078,-.00607,-.0104,0.0*
1,1,.006,-.00607,-.0104*
20,1,.006,-.00607,-.0104,-.00303,-.01213,0.0*
1,1,.006,-.00303,-.01213*
20,1,.006,-.00303,-.01213,0.0,-.013,0.0*
1,1,.006,0.0,-.013*
20,1,.006,0.0,-.013,.00303,-.013,0.0*
1,1,.006,.00303,-.013*
20,1,.006,.00303,-.013,.00607,-.01213,0.0*
1,1,.006,.00607,-.01213*
20,1,.006,.00607,-.01213,.00867,-.01083,0.0*
1,1,.006,.00867,-.01083*
20,1,.006,.00867,-.01083,.01083,-.0091,0.0*
1,1,.006,.01083,-.0091*
%
%ADD53MACRO53*%
%AMMACRO59*
1,1,.006,-.01333,.02*
20,1,.006,-.01333,.02,-.01333,-.02,0.0*
1,1,.006,-.01333,-.02*
20,1,.006,-.01333,-.02,.01333,-.02,0.0*
1,1,.006,.01333,-.02*
%
%ADD59MACRO59*%
%AMMACRO70*
1,1,.006,-.01733,-.02*
20,1,.006,-.01733,-.02,-.01733,.02,0.0*
1,1,.006,-.01733,.02*
20,1,.006,-.01733,.02,0.0,-.01333,0.0*
1,1,.006,0.0,-.01333*
20,1,.006,0.0,-.01333,.01733,.02,0.0*
1,1,.006,.01733,.02*
20,1,.006,.01733,.02,.01733,-.02,0.0*
1,1,.006,.01733,-.02*
%
%ADD70MACRO70*%
%AMMACRO38*
1,1,.006,-.0068,.017*
20,1,.006,-.0068,.017,.0068,.017,0.0*
1,1,.006,.0068,.017*
1,1,.006,0.0,.017*
20,1,.006,0.0,.017,0.0,-.017,0.0*
1,1,.006,0.0,-.017*
1,1,.006,-.0068,-.017*
20,1,.006,-.0068,-.017,.0068,-.017,0.0*
1,1,.006,.0068,-.017*
%
%ADD38MACRO38*%
%AMMACRO41*
1,1,.006,-.01572,-.0205*
20,1,.006,-.01572,-.0205,-.01572,.0205,0.0*
1,1,.006,-.01572,.0205*
20,1,.006,-.01572,.0205,.01572,-.0205,0.0*
1,1,.006,.01572,-.0205*
20,1,.006,.01572,-.0205,.01572,.0205,0.0*
1,1,.006,.01572,.0205*
%
%ADD41MACRO41*%
%AMMACRO25*
1,1,.006,0.0,-.0205*
20,1,.006,0.0,-.0205,-.00547,-.01982,0.0*
1,1,.006,-.00547,-.01982*
20,1,.006,-.00547,-.01982,-.01025,-.01708,0.0*
1,1,.006,-.01025,-.01708*
20,1,.006,-.01025,-.01708,-.01435,-.01298,0.0*
1,1,.006,-.01435,-.01298*
20,1,.006,-.01435,-.01298,-.01708,-.0082,0.0*
1,1,.006,-.01708,-.0082*
20,1,.006,-.01708,-.0082,-.01845,-.00273,0.0*
1,1,.006,-.01845,-.00273*
20,1,.006,-.01845,-.00273,-.01845,.00273,0.0*
1,1,.006,-.01845,.00273*
20,1,.006,-.01845,.00273,-.01708,.0082,0.0*
1,1,.006,-.01708,.0082*
20,1,.006,-.01708,.0082,-.01435,.01298,0.0*
1,1,.006,-.01435,.01298*
20,1,.006,-.01435,.01298,-.01025,.01708,0.0*
1,1,.006,-.01025,.01708*
20,1,.006,-.01025,.01708,-.00547,.01982,0.0*
1,1,.006,-.00547,.01982*
20,1,.006,-.00547,.01982,0.0,.0205,0.0*
1,1,.006,0.0,.0205*
20,1,.006,0.0,.0205,.00547,.01982,0.0*
1,1,.006,.00547,.01982*
20,1,.006,.00547,.01982,.01025,.01708,0.0*
1,1,.006,.01025,.01708*
20,1,.006,.01025,.01708,.01435,.01298,0.0*
1,1,.006,.01435,.01298*
20,1,.006,.01435,.01298,.01708,.0082,0.0*
1,1,.006,.01708,.0082*
20,1,.006,.01708,.0082,.01845,.00273,0.0*
1,1,.006,.01845,.00273*
20,1,.006,.01845,.00273,.01845,-.00273,0.0*
1,1,.006,.01845,-.00273*
20,1,.006,.01845,-.00273,.01708,-.0082,0.0*
1,1,.006,.01708,-.0082*
20,1,.006,.01708,-.0082,.01435,-.01298,0.0*
1,1,.006,.01435,-.01298*
20,1,.006,.01435,-.01298,.01025,-.01708,0.0*
1,1,.006,.01025,-.01708*
20,1,.006,.01025,-.01708,.00547,-.01982,0.0*
1,1,.006,.00547,-.01982*
20,1,.006,.00547,-.01982,0.0,-.0205,0.0*
1,1,.006,0.0,-.0205*
%
%ADD25MACRO25*%
%AMMACRO17*
1,1,.006,-.012,-.0108*
20,1,.006,-.012,-.0108,-.009,-.0144,0.0*
1,1,.006,-.009,-.0144*
20,1,.006,-.009,-.0144,-.0054,-.0168,0.0*
1,1,.006,-.0054,-.0168*
20,1,.006,-.0054,-.0168,-.0012,-.018,0.0*
1,1,.006,-.0012,-.018*
20,1,.006,-.0012,-.018,.0036,-.0168,0.0*
1,1,.006,.0036,-.0168*
20,1,.006,.0036,-.0168,.0072,-.0144,0.0*
1,1,.006,.0072,-.0144*
20,1,.006,.0072,-.0144,.0108,-.0108,0.0*
1,1,.006,.0108,-.0108*
20,1,.006,.0108,-.0108,.012,-.006,0.0*
1,1,.006,.012,-.006*
20,1,.006,.012,-.006,.012,.018,0.0*
1,1,.006,.012,.018*
%
%ADD17MACRO17*%
%AMMACRO67*
1,1,.006,0.0,-.015*
20,1,.006,0.0,-.015,0.0,-.0015,0.0*
1,1,.006,0.0,-.0015*
20,1,.006,0.0,-.0015,-.01,.015,0.0*
1,1,.006,-.01,.015*
1,1,.006,.01,.015*
20,1,.006,.01,.015,0.0,-.0015,0.0*
1,1,.006,0.0,-.0015*
%
%ADD67MACRO67*%
%AMMACRO47*
1,1,.006,-.011,.011*
20,1,.006,-.011,.011,-.00587,-.011,0.0*
1,1,.006,-.00587,-.011*
20,1,.006,-.00587,-.011,0.0,.011,0.0*
1,1,.006,0.0,.011*
20,1,.006,0.0,.011,.00587,-.011,0.0*
1,1,.006,.00587,-.011*
20,1,.006,.00587,-.011,.011,.011,0.0*
1,1,.006,.011,.011*
%
%ADD47MACRO47*%
%AMMACRO19*
1,1,.006,0.0,.0625*
20,1,.006,0.0,.0625,0.0,-.0625,0.0*
1,1,.006,0.0,-.0625*
1,1,.006,-.04792,.0625*
20,1,.006,-.04792,.0625,.04792,.0625,0.0*
1,1,.006,.04792,.0625*
%
%ADD19MACRO19*%
%AMMACRO45*
1,1,.006,-.0095,.015*
20,1,.006,-.0095,.015,.0095,.015,0.0*
1,1,.006,.0095,.015*
20,1,.006,.0095,.015,-.0095,-.015,0.0*
1,1,.006,-.0095,-.015*
20,1,.006,-.0095,-.015,.0095,-.015,0.0*
1,1,.006,.0095,-.015*
%
%ADD45MACRO45*%
%AMMACRO11*
1,1,.006,-.09334,.112*
20,1,.006,-.09334,.112,0.0,-.112,0.0*
1,1,.006,0.0,-.112*
20,1,.006,0.0,-.112,.09334,.112,0.0*
1,1,.006,.09334,.112*
%
%ADD11MACRO11*%
%AMMACRO24*
1,1,.006,-.015,-.0225*
20,1,.006,-.015,-.0225,-.015,.0225,0.0*
1,1,.006,-.015,.0225*
20,1,.006,-.015,.0225,.003,.0225,0.0*
1,1,.006,.003,.0225*
20,1,.006,.003,.0225,.009,.02025,0.0*
1,1,.006,.009,.02025*
20,1,.006,.009,.02025,.0135,.015,0.0*
1,1,.006,.0135,.015*
20,1,.006,.0135,.015,.015,.009,0.0*
1,1,.006,.015,.009*
20,1,.006,.015,.009,.0135,.003,0.0*
1,1,.006,.0135,.003*
20,1,.006,.0135,.003,.00975,-.0015,0.0*
1,1,.006,.00975,-.0015*
20,1,.006,.00975,-.0015,.003,-.00375,0.0*
1,1,.006,.003,-.00375*
20,1,.006,.003,-.00375,-.015,-.00375,0.0*
1,1,.006,-.015,-.00375*
%
%ADD24MACRO24*%
%AMMACRO44*
1,1,.006,-.0143,-.0195*
20,1,.006,-.0143,-.0195,-.0143,.0195,0.0*
1,1,.006,-.0143,.0195*
1,1,.006,.0104,.0195*
20,1,.006,.0104,.0195,-.0143,-.00455,0.0*
1,1,.006,-.0143,-.00455*
1,1,.006,.0143,-.0195*
20,1,.006,.0143,-.0195,-.00325,.0065,0.0*
1,1,.006,-.00325,.0065*
%
%ADD44MACRO44*%
%AMMACRO71*
1,1,.006,-.02,.01*
20,1,.006,-.02,.01,.02,.01,0.0*
1,1,.006,.02,.01*
20,1,.006,.02,.01,.021736,.009848,0.0*
1,1,.006,.021736,.009848*
20,1,.006,.021736,.009848,.02342,.009397,0.0*
1,1,.006,.02342,.009397*
20,1,.006,.02342,.009397,.025,.00866,0.0*
1,1,.006,.025,.00866*
20,1,.006,.025,.00866,.026428,.00766,0.0*
1,1,.006,.026428,.00766*
20,1,.006,.026428,.00766,.02766,.006428,0.0*
1,1,.006,.02766,.006428*
20,1,.006,.02766,.006428,.02866,.005,0.0*
1,1,.006,.02866,.005*
20,1,.006,.02866,.005,.029397,.00342,0.0*
1,1,.006,.029397,.00342*
20,1,.006,.029397,.00342,.029848,.001736,0.0*
1,1,.006,.029848,.001736*
20,1,.006,.029848,.001736,.03,0.0,0.0*
1,1,.006,.03,0.0*
20,1,.006,.03,0.0,.029848,-.001736,0.0*
1,1,.006,.029848,-.001736*
20,1,.006,.029848,-.001736,.029397,-.00342,0.0*
1,1,.006,.029397,-.00342*
20,1,.006,.029397,-.00342,.02866,-.005,0.0*
1,1,.006,.02866,-.005*
20,1,.006,.02866,-.005,.02766,-.006428,0.0*
1,1,.006,.02766,-.006428*
20,1,.006,.02766,-.006428,.026428,-.00766,0.0*
1,1,.006,.026428,-.00766*
20,1,.006,.026428,-.00766,.025,-.00866,0.0*
1,1,.006,.025,-.00866*
20,1,.006,.025,-.00866,.02342,-.009397,0.0*
1,1,.006,.02342,-.009397*
20,1,.006,.02342,-.009397,.021736,-.009848,0.0*
1,1,.006,.021736,-.009848*
20,1,.006,.021736,-.009848,.02,-.01,0.0*
1,1,.006,.02,-.01*
20,1,.006,.02,-.01,-.02,-.01,0.0*
1,1,.006,-.02,-.01*
20,1,.006,-.02,-.01,-.021736,-.009848,0.0*
1,1,.006,-.021736,-.009848*
20,1,.006,-.021736,-.009848,-.02342,-.009397,0.0*
1,1,.006,-.02342,-.009397*
20,1,.006,-.02342,-.009397,-.025,-.00866,0.0*
1,1,.006,-.025,-.00866*
20,1,.006,-.025,-.00866,-.026428,-.00766,0.0*
1,1,.006,-.026428,-.00766*
20,1,.006,-.026428,-.00766,-.02766,-.006428,0.0*
1,1,.006,-.02766,-.006428*
20,1,.006,-.02766,-.006428,-.02866,-.005,0.0*
1,1,.006,-.02866,-.005*
20,1,.006,-.02866,-.005,-.029397,-.00342,0.0*
1,1,.006,-.029397,-.00342*
20,1,.006,-.029397,-.00342,-.029848,-.001736,0.0*
1,1,.006,-.029848,-.001736*
20,1,.006,-.029848,-.001736,-.03,0.0,0.0*
1,1,.006,-.03,0.0*
20,1,.006,-.03,0.0,-.029848,.001736,0.0*
1,1,.006,-.029848,.001736*
20,1,.006,-.029848,.001736,-.029397,.00342,0.0*
1,1,.006,-.029397,.00342*
20,1,.006,-.029397,.00342,-.02866,.005,0.0*
1,1,.006,-.02866,.005*
20,1,.006,-.02866,.005,-.02766,.006428,0.0*
1,1,.006,-.02766,.006428*
20,1,.006,-.02766,.006428,-.026428,.00766,0.0*
1,1,.006,-.026428,.00766*
20,1,.006,-.026428,.00766,-.025,.00866,0.0*
1,1,.006,-.025,.00866*
20,1,.006,-.025,.00866,-.02342,.009397,0.0*
1,1,.006,-.02342,.009397*
20,1,.006,-.02342,.009397,-.021736,.009848,0.0*
1,1,.006,-.021736,.009848*
20,1,.006,-.021736,.009848,-.02,.01,0.0*
1,1,.006,-.02,.01*
1,1,.006,-.005,-.005*
20,1,.006,-.005,-.005,-.00633,-.00483,0.0*
1,1,.006,-.00633,-.00483*
20,1,.006,-.00633,-.00483,-.0075,-.00417,0.0*
1,1,.006,-.0075,-.00417*
20,1,.006,-.0075,-.00417,-.0085,-.00317,0.0*
1,1,.006,-.0085,-.00317*
20,1,.006,-.0085,-.00317,-.00917,-.002,0.0*
1,1,.006,-.00917,-.002*
20,1,.006,-.00917,-.002,-.0095,-.00067,0.0*
1,1,.006,-.0095,-.00067*
20,1,.006,-.0095,-.00067,-.0095,.00067,0.0*
1,1,.006,-.0095,.00067*
20,1,.006,-.0095,.00067,-.00917,.002,0.0*
1,1,.006,-.00917,.002*
20,1,.006,-.00917,.002,-.0085,.00317,0.0*
1,1,.006,-.0085,.00317*
20,1,.006,-.0085,.00317,-.0075,.00417,0.0*
1,1,.006,-.0075,.00417*
20,1,.006,-.0075,.00417,-.00633,.00483,0.0*
1,1,.006,-.00633,.00483*
20,1,.006,-.00633,.00483,-.005,.005,0.0*
1,1,.006,-.005,.005*
20,1,.006,-.005,.005,-.00367,.00483,0.0*
1,1,.006,-.00367,.00483*
20,1,.006,-.00367,.00483,-.0025,.00417,0.0*
1,1,.006,-.0025,.00417*
20,1,.006,-.0025,.00417,-.0015,.00317,0.0*
1,1,.006,-.0015,.00317*
20,1,.006,-.0015,.00317,-.00083,.002,0.0*
1,1,.006,-.00083,.002*
20,1,.006,-.00083,.002,-.0005,.00067,0.0*
1,1,.006,-.0005,.00067*
20,1,.006,-.0005,.00067,-.0005,-.00067,0.0*
1,1,.006,-.0005,-.00067*
20,1,.006,-.0005,-.00067,-.00083,-.002,0.0*
1,1,.006,-.00083,-.002*
20,1,.006,-.00083,-.002,-.0015,-.00317,0.0*
1,1,.006,-.0015,-.00317*
20,1,.006,-.0015,-.00317,-.0025,-.00417,0.0*
1,1,.006,-.0025,-.00417*
20,1,.006,-.0025,-.00417,-.00367,-.00483,0.0*
1,1,.006,-.00367,-.00483*
20,1,.006,-.00367,-.00483,-.005,-.005,0.0*
1,1,.006,-.005,-.005*
1,1,.006,.00084,-.005*
20,1,.006,.00084,-.005,.00501,.005,0.0*
1,1,.006,.00501,.005*
20,1,.006,.00501,.005,.00918,-.005,0.0*
1,1,.006,.00918,-.005*
1,1,.006,.00768,-.0015*
20,1,.006,.00768,-.0015,.00234,-.0015,0.0*
1,1,.006,.00234,-.0015*
%
%ADD71MACRO71*%
%AMMACRO15*
1,1,.006,0.0,-.023*
20,1,.006,0.0,-.023,-.00613,-.02223,0.0*
1,1,.006,-.00613,-.02223*
20,1,.006,-.00613,-.02223,-.0115,-.01917,0.0*
1,1,.006,-.0115,-.01917*
20,1,.006,-.0115,-.01917,-.0161,-.01457,0.0*
1,1,.006,-.0161,-.01457*
20,1,.006,-.0161,-.01457,-.01917,-.0092,0.0*
1,1,.006,-.01917,-.0092*
20,1,.006,-.01917,-.0092,-.0207,-.00307,0.0*
1,1,.006,-.0207,-.00307*
20,1,.006,-.0207,-.00307,-.0207,.00307,0.0*
1,1,.006,-.0207,.00307*
20,1,.006,-.0207,.00307,-.01917,.0092,0.0*
1,1,.006,-.01917,.0092*
20,1,.006,-.01917,.0092,-.0161,.01457,0.0*
1,1,.006,-.0161,.01457*
20,1,.006,-.0161,.01457,-.0115,.01917,0.0*
1,1,.006,-.0115,.01917*
20,1,.006,-.0115,.01917,-.00613,.02223,0.0*
1,1,.006,-.00613,.02223*
20,1,.006,-.00613,.02223,0.0,.023,0.0*
1,1,.006,0.0,.023*
20,1,.006,0.0,.023,.00613,.02223,0.0*
1,1,.006,.00613,.02223*
20,1,.006,.00613,.02223,.0115,.01917,0.0*
1,1,.006,.0115,.01917*
20,1,.006,.0115,.01917,.0161,.01457,0.0*
1,1,.006,.0161,.01457*
20,1,.006,.0161,.01457,.01917,.0092,0.0*
1,1,.006,.01917,.0092*
20,1,.006,.01917,.0092,.0207,.00307,0.0*
1,1,.006,.0207,.00307*
20,1,.006,.0207,.00307,.0207,-.00307,0.0*
1,1,.006,.0207,-.00307*
20,1,.006,.0207,-.00307,.01917,-.0092,0.0*
1,1,.006,.01917,-.0092*
20,1,.006,.01917,-.0092,.0161,-.01457,0.0*
1,1,.006,.0161,-.01457*
20,1,.006,.0161,-.01457,.0115,-.01917,0.0*
1,1,.006,.0115,-.01917*
20,1,.006,.0115,-.01917,.00613,-.02223,0.0*
1,1,.006,.00613,-.02223*
20,1,.006,.00613,-.02223,0.0,-.023,0.0*
1,1,.006,0.0,-.023*
1,1,.006,.00613,-.01073*
20,1,.006,.00613,-.01073,.01533,-.023,0.0*
1,1,.006,.01533,-.023*
%
%ADD15MACRO15*%
%AMMACRO66*
1,1,.006,-.01,-.006*
20,1,.006,-.01,-.006,-.01,.006,0.0*
1,1,.006,-.01,.006*
20,1,.006,-.01,.006,-.009848,.007736,0.0*
1,1,.006,-.009848,.007736*
20,1,.006,-.009848,.007736,-.009397,.00942,0.0*
1,1,.006,-.009397,.00942*
20,1,.006,-.009397,.00942,-.00866,.011,0.0*
1,1,.006,-.00866,.011*
20,1,.006,-.00866,.011,-.00766,.012428,0.0*
1,1,.006,-.00766,.012428*
20,1,.006,-.00766,.012428,-.006428,.01366,0.0*
1,1,.006,-.006428,.01366*
20,1,.006,-.006428,.01366,-.005,.01466,0.0*
1,1,.006,-.005,.01466*
20,1,.006,-.005,.01466,-.00342,.015397,0.0*
1,1,.006,-.00342,.015397*
20,1,.006,-.00342,.015397,-.001736,.015848,0.0*
1,1,.006,-.001736,.015848*
20,1,.006,-.001736,.015848,0.0,.016,0.0*
1,1,.006,0.0,.016*
20,1,.006,0.0,.016,.001736,.015848,0.0*
1,1,.006,.001736,.015848*
20,1,.006,.001736,.015848,.00342,.015397,0.0*
1,1,.006,.00342,.015397*
20,1,.006,.00342,.015397,.005,.01466,0.0*
1,1,.006,.005,.01466*
20,1,.006,.005,.01466,.006428,.01366,0.0*
1,1,.006,.006428,.01366*
20,1,.006,.006428,.01366,.00766,.012428,0.0*
1,1,.006,.00766,.012428*
20,1,.006,.00766,.012428,.00866,.011,0.0*
1,1,.006,.00866,.011*
20,1,.006,.00866,.011,.009397,.00942,0.0*
1,1,.006,.009397,.00942*
20,1,.006,.009397,.00942,.009848,.007736,0.0*
1,1,.006,.009848,.007736*
20,1,.006,.009848,.007736,.01,.006,0.0*
1,1,.006,.01,.006*
20,1,.006,.01,.006,.01,-.006,0.0*
1,1,.006,.01,-.006*
20,1,.006,.01,-.006,.009848,-.007736,0.0*
1,1,.006,.009848,-.007736*
20,1,.006,.009848,-.007736,.009397,-.00942,0.0*
1,1,.006,.009397,-.00942*
20,1,.006,.009397,-.00942,.00866,-.011,0.0*
1,1,.006,.00866,-.011*
20,1,.006,.00866,-.011,.00766,-.012428,0.0*
1,1,.006,.00766,-.012428*
20,1,.006,.00766,-.012428,.006428,-.01366,0.0*
1,1,.006,.006428,-.01366*
20,1,.006,.006428,-.01366,.005,-.01466,0.0*
1,1,.006,.005,-.01466*
20,1,.006,.005,-.01466,.00342,-.015397,0.0*
1,1,.006,.00342,-.015397*
20,1,.006,.00342,-.015397,.001736,-.015848,0.0*
1,1,.006,.001736,-.015848*
20,1,.006,.001736,-.015848,0.0,-.016,0.0*
1,1,.006,0.0,-.016*
20,1,.006,0.0,-.016,-.001736,-.015848,0.0*
1,1,.006,-.001736,-.015848*
20,1,.006,-.001736,-.015848,-.00342,-.015397,0.0*
1,1,.006,-.00342,-.015397*
20,1,.006,-.00342,-.015397,-.005,-.01466,0.0*
1,1,.006,-.005,-.01466*
20,1,.006,-.005,-.01466,-.006428,-.01366,0.0*
1,1,.006,-.006428,-.01366*
20,1,.006,-.006428,-.01366,-.00766,-.012428,0.0*
1,1,.006,-.00766,-.012428*
20,1,.006,-.00766,-.012428,-.00866,-.011,0.0*
1,1,.006,-.00866,-.011*
20,1,.006,-.00866,-.011,-.009397,-.00942,0.0*
1,1,.006,-.009397,-.00942*
20,1,.006,-.009397,-.00942,-.009848,-.007736,0.0*
1,1,.006,-.009848,-.007736*
20,1,.006,-.009848,-.007736,-.01,-.006,0.0*
1,1,.006,-.01,-.006*
1,1,.006,-.005,-.005*
20,1,.006,-.005,-.005,-.00633,-.00483,0.0*
1,1,.006,-.00633,-.00483*
20,1,.006,-.00633,-.00483,-.0075,-.00417,0.0*
1,1,.006,-.0075,-.00417*
20,1,.006,-.0075,-.00417,-.0085,-.00317,0.0*
1,1,.006,-.0085,-.00317*
20,1,.006,-.0085,-.00317,-.00917,-.002,0.0*
1,1,.006,-.00917,-.002*
20,1,.006,-.00917,-.002,-.0095,-.00067,0.0*
1,1,.006,-.0095,-.00067*
20,1,.006,-.0095,-.00067,-.0095,.00067,0.0*
1,1,.006,-.0095,.00067*
20,1,.006,-.0095,.00067,-.00917,.002,0.0*
1,1,.006,-.00917,.002*
20,1,.006,-.00917,.002,-.0085,.00317,0.0*
1,1,.006,-.0085,.00317*
20,1,.006,-.0085,.00317,-.0075,.00417,0.0*
1,1,.006,-.0075,.00417*
20,1,.006,-.0075,.00417,-.00633,.00483,0.0*
1,1,.006,-.00633,.00483*
20,1,.006,-.00633,.00483,-.005,.005,0.0*
1,1,.006,-.005,.005*
20,1,.006,-.005,.005,-.00367,.00483,0.0*
1,1,.006,-.00367,.00483*
20,1,.006,-.00367,.00483,-.0025,.00417,0.0*
1,1,.006,-.0025,.00417*
20,1,.006,-.0025,.00417,-.0015,.00317,0.0*
1,1,.006,-.0015,.00317*
20,1,.006,-.0015,.00317,-.00083,.002,0.0*
1,1,.006,-.00083,.002*
20,1,.006,-.00083,.002,-.0005,.00067,0.0*
1,1,.006,-.0005,.00067*
20,1,.006,-.0005,.00067,-.0005,-.00067,0.0*
1,1,.006,-.0005,-.00067*
20,1,.006,-.0005,-.00067,-.00083,-.002,0.0*
1,1,.006,-.00083,-.002*
20,1,.006,-.00083,-.002,-.0015,-.00317,0.0*
1,1,.006,-.0015,-.00317*
20,1,.006,-.0015,-.00317,-.0025,-.00417,0.0*
1,1,.006,-.0025,-.00417*
20,1,.006,-.0025,-.00417,-.00367,-.00483,0.0*
1,1,.006,-.00367,-.00483*
20,1,.006,-.00367,-.00483,-.005,-.005,0.0*
1,1,.006,-.005,-.005*
1,1,.006,.00834,-.005*
20,1,.006,.00834,-.005,.00168,-.005,0.0*
1,1,.006,.00168,-.005*
20,1,.006,.00168,-.005,.00168,.005,0.0*
1,1,.006,.00168,.005*
20,1,.006,.00168,.005,.00834,.005,0.0*
1,1,.006,.00834,.005*
1,1,.006,.00568,.00017*
20,1,.006,.00568,.00017,.00168,.00017,0.0*
1,1,.006,.00168,.00017*
%
%ADD66MACRO66*%
%AMMACRO69*
1,1,.006,-.0091,-.013*
20,1,.006,-.0091,-.013,.0091,.013,0.0*
1,1,.006,.0091,.013*
1,1,.006,-.0091,.013*
20,1,.006,-.0091,.013,.0091,-.013,0.0*
1,1,.006,.0091,-.013*
%
%ADD69MACRO69*%
%AMMACRO65*
1,1,.006,-.0255,.01*
20,1,.006,-.0255,.01,.0255,.01,0.0*
1,1,.006,.0255,.01*
20,1,.006,.0255,.01,.027236,.009848,0.0*
1,1,.006,.027236,.009848*
20,1,.006,.027236,.009848,.02892,.009397,0.0*
1,1,.006,.02892,.009397*
20,1,.006,.02892,.009397,.0305,.00866,0.0*
1,1,.006,.0305,.00866*
20,1,.006,.0305,.00866,.031928,.00766,0.0*
1,1,.006,.031928,.00766*
20,1,.006,.031928,.00766,.03316,.006428,0.0*
1,1,.006,.03316,.006428*
20,1,.006,.03316,.006428,.03416,.005,0.0*
1,1,.006,.03416,.005*
20,1,.006,.03416,.005,.034897,.00342,0.0*
1,1,.006,.034897,.00342*
20,1,.006,.034897,.00342,.035348,.001736,0.0*
1,1,.006,.035348,.001736*
20,1,.006,.035348,.001736,.0355,0.0,0.0*
1,1,.006,.0355,0.0*
20,1,.006,.0355,0.0,.035348,-.001736,0.0*
1,1,.006,.035348,-.001736*
20,1,.006,.035348,-.001736,.034897,-.00342,0.0*
1,1,.006,.034897,-.00342*
20,1,.006,.034897,-.00342,.03416,-.005,0.0*
1,1,.006,.03416,-.005*
20,1,.006,.03416,-.005,.03316,-.006428,0.0*
1,1,.006,.03316,-.006428*
20,1,.006,.03316,-.006428,.031928,-.00766,0.0*
1,1,.006,.031928,-.00766*
20,1,.006,.031928,-.00766,.0305,-.00866,0.0*
1,1,.006,.0305,-.00866*
20,1,.006,.0305,-.00866,.02892,-.009397,0.0*
1,1,.006,.02892,-.009397*
20,1,.006,.02892,-.009397,.027236,-.009848,0.0*
1,1,.006,.027236,-.009848*
20,1,.006,.027236,-.009848,.0255,-.01,0.0*
1,1,.006,.0255,-.01*
20,1,.006,.0255,-.01,-.0255,-.01,0.0*
1,1,.006,-.0255,-.01*
20,1,.006,-.0255,-.01,-.027236,-.009848,0.0*
1,1,.006,-.027236,-.009848*
20,1,.006,-.027236,-.009848,-.02892,-.009397,0.0*
1,1,.006,-.02892,-.009397*
20,1,.006,-.02892,-.009397,-.0305,-.00866,0.0*
1,1,.006,-.0305,-.00866*
20,1,.006,-.0305,-.00866,-.031928,-.00766,0.0*
1,1,.006,-.031928,-.00766*
20,1,.006,-.031928,-.00766,-.03316,-.006428,0.0*
1,1,.006,-.03316,-.006428*
20,1,.006,-.03316,-.006428,-.03416,-.005,0.0*
1,1,.006,-.03416,-.005*
20,1,.006,-.03416,-.005,-.034897,-.00342,0.0*
1,1,.006,-.034897,-.00342*
20,1,.006,-.034897,-.00342,-.035348,-.001736,0.0*
1,1,.006,-.035348,-.001736*
20,1,.006,-.035348,-.001736,-.0355,0.0,0.0*
1,1,.006,-.0355,0.0*
20,1,.006,-.0355,0.0,-.035348,.001736,0.0*
1,1,.006,-.035348,.001736*
20,1,.006,-.035348,.001736,-.034897,.00342,0.0*
1,1,.006,-.034897,.00342*
20,1,.006,-.034897,.00342,-.03416,.005,0.0*
1,1,.006,-.03416,.005*
20,1,.006,-.03416,.005,-.03316,.006428,0.0*
1,1,.006,-.03316,.006428*
20,1,.006,-.03316,.006428,-.031928,.00766,0.0*
1,1,.006,-.031928,.00766*
20,1,.006,-.031928,.00766,-.0305,.00866,0.0*
1,1,.006,-.0305,.00866*
20,1,.006,-.0305,.00866,-.02892,.009397,0.0*
1,1,.006,-.02892,.009397*
20,1,.006,-.02892,.009397,-.027236,.009848,0.0*
1,1,.006,-.027236,.009848*
20,1,.006,-.027236,.009848,-.0255,.01,0.0*
1,1,.006,-.0255,.01*
1,1,.006,-.005,-.005*
20,1,.006,-.005,-.005,-.00633,-.00483,0.0*
1,1,.006,-.00633,-.00483*
20,1,.006,-.00633,-.00483,-.0075,-.00417,0.0*
1,1,.006,-.0075,-.00417*
20,1,.006,-.0075,-.00417,-.0085,-.00317,0.0*
1,1,.006,-.0085,-.00317*
20,1,.006,-.0085,-.00317,-.00917,-.002,0.0*
1,1,.006,-.00917,-.002*
20,1,.006,-.00917,-.002,-.0095,-.00067,0.0*
1,1,.006,-.0095,-.00067*
20,1,.006,-.0095,-.00067,-.0095,.00067,0.0*
1,1,.006,-.0095,.00067*
20,1,.006,-.0095,.00067,-.00917,.002,0.0*
1,1,.006,-.00917,.002*
20,1,.006,-.00917,.002,-.0085,.00317,0.0*
1,1,.006,-.0085,.00317*
20,1,.006,-.0085,.00317,-.0075,.00417,0.0*
1,1,.006,-.0075,.00417*
20,1,.006,-.0075,.00417,-.00633,.00483,0.0*
1,1,.006,-.00633,.00483*
20,1,.006,-.00633,.00483,-.005,.005,0.0*
1,1,.006,-.005,.005*
20,1,.006,-.005,.005,-.00367,.00483,0.0*
1,1,.006,-.00367,.00483*
20,1,.006,-.00367,.00483,-.0025,.00417,0.0*
1,1,.006,-.0025,.00417*
20,1,.006,-.0025,.00417,-.0015,.00317,0.0*
1,1,.006,-.0015,.00317*
20,1,.006,-.0015,.00317,-.00083,.002,0.0*
1,1,.006,-.00083,.002*
20,1,.006,-.00083,.002,-.0005,.00067,0.0*
1,1,.006,-.0005,.00067*
20,1,.006,-.0005,.00067,-.0005,-.00067,0.0*
1,1,.006,-.0005,-.00067*
20,1,.006,-.0005,-.00067,-.00083,-.002,0.0*
1,1,.006,-.00083,-.002*
20,1,.006,-.00083,-.002,-.0015,-.00317,0.0*
1,1,.006,-.0015,-.00317*
20,1,.006,-.0015,-.00317,-.0025,-.00417,0.0*
1,1,.006,-.0025,-.00417*
20,1,.006,-.0025,-.00417,-.00367,-.00483,0.0*
1,1,.006,-.00367,-.00483*
20,1,.006,-.00367,-.00483,-.005,-.005,0.0*
1,1,.006,-.005,-.005*
1,1,.006,.00634,.00033*
20,1,.006,.00634,.00033,.00701,.00083,0.0*
1,1,.006,.00701,.00083*
20,1,.006,.00701,.00083,.00751,.00167,0.0*
1,1,.006,.00751,.00167*
20,1,.006,.00751,.00167,.00784,.00283,0.0*
1,1,.006,.00784,.00283*
20,1,.006,.00784,.00283,.00751,.00383,0.0*
1,1,.006,.00751,.00383*
20,1,.006,.00751,.00383,.00684,.0045,0.0*
1,1,.006,.00684,.0045*
20,1,.006,.00684,.0045,.00568,.005,0.0*
1,1,.006,.00568,.005*
20,1,.006,.00568,.005,.00118,.005,0.0*
1,1,.006,.00118,.005*
20,1,.006,.00118,.005,.00118,-.005,0.0*
1,1,.006,.00118,-.005*
20,1,.006,.00118,-.005,.00668,-.005,0.0*
1,1,.006,.00668,-.005*
20,1,.006,.00668,-.005,.00784,-.00433,0.0*
1,1,.006,.00784,-.00433*
20,1,.006,.00784,-.00433,.00851,-.00333,0.0*
1,1,.006,.00851,-.00333*
20,1,.006,.00851,-.00333,.00884,-.00217,0.0*
1,1,.006,.00884,-.00217*
20,1,.006,.00884,-.00217,.00851,-.001,0.0*
1,1,.006,.00851,-.001*
20,1,.006,.00851,-.001,.00751,0.0,0.0*
1,1,.006,.00751,0.0*
20,1,.006,.00751,0.0,.00634,.00033,0.0*
1,1,.006,.00634,.00033*
20,1,.006,.00634,.00033,.00118,.00033,0.0*
1,1,.006,.00118,.00033*
%
%ADD65MACRO65*%
%AMMACRO20*
1,1,.006,-.01082,-.01476*
20,1,.006,-.01082,-.01476,-.01082,.01476,0.0*
1,1,.006,-.01082,.01476*
20,1,.006,-.01082,.01476,-.00098,.01476,0.0*
1,1,.006,-.00098,.01476*
20,1,.006,-.00098,.01476,.00295,.01328,0.0*
1,1,.006,.00295,.01328*
20,1,.006,.00295,.01328,.0059,.01132,0.0*
1,1,.006,.0059,.01132*
20,1,.006,.0059,.01132,.00836,.00836,0.0*
1,1,.006,.00836,.00836*
20,1,.006,.00836,.00836,.01033,.00492,0.0*
1,1,.006,.01033,.00492*
20,1,.006,.01033,.00492,.01082,0.0,0.0*
1,1,.006,.01082,0.0*
20,1,.006,.01082,0.0,.01033,-.00492,0.0*
1,1,.006,.01033,-.00492*
20,1,.006,.01033,-.00492,.00836,-.00836,0.0*
1,1,.006,.00836,-.00836*
20,1,.006,.00836,-.00836,.0059,-.01132,0.0*
1,1,.006,.0059,-.01132*
20,1,.006,.0059,-.01132,.00295,-.01328,0.0*
1,1,.006,.00295,-.01328*
20,1,.006,.00295,-.01328,-.00098,-.01476,0.0*
1,1,.006,-.00098,-.01476*
20,1,.006,-.00098,-.01476,-.01082,-.01476,0.0*
1,1,.006,-.01082,-.01476*
%
%ADD20MACRO20*%
%AMMACRO12*
1,1,.006,.005,0.0*
20,1,.006,.005,0.0,.0025,.00433,0.0*
1,1,.006,.0025,.00433*
20,1,.006,.0025,.00433,-.0025,.00433,0.0*
1,1,.006,-.0025,.00433*
20,1,.006,-.0025,.00433,-.005,0.0,0.0*
1,1,.006,-.005,0.0*
20,1,.006,-.005,0.0,-.0025,-.00433,0.0*
1,1,.006,-.0025,-.00433*
20,1,.006,-.0025,-.00433,.0025,-.00433,0.0*
1,1,.006,.0025,-.00433*
20,1,.006,.0025,-.00433,.005,0.0,0.0*
1,1,.006,.005,0.0*
1,1,.006,-.00183,-.0015*
20,1,.006,-.00183,-.0015,-.00133,-.00208,0.0*
1,1,.006,-.00133,-.00208*
20,1,.006,-.00133,-.00208,-.00067,-.00242,0.0*
1,1,.006,-.00067,-.00242*
20,1,.006,-.00067,-.00242,.00008,-.0025,0.0*
1,1,.006,.00008,-.0025*
20,1,.006,.00008,-.0025,.00075,-.00242,0.0*
1,1,.006,.00075,-.00242*
20,1,.006,.00075,-.00242,.00142,-.002,0.0*
1,1,.006,.00142,-.002*
20,1,.006,.00142,-.002,.00183,-.0015,0.0*
1,1,.006,.00183,-.0015*
20,1,.006,.00183,-.0015,.00192,-.001,0.0*
1,1,.006,.00192,-.001*
20,1,.006,.00192,-.001,.00175,-.00042,0.0*
1,1,.006,.00175,-.00042*
20,1,.006,.00175,-.00042,.00117,0.0,0.0*
1,1,.006,.00117,0.0*
20,1,.006,.00117,0.0,.00058,.00017,0.0*
1,1,.006,.00058,.00017*
20,1,.006,.00058,.00017,-.00017,.00017,0.0*
1,1,.006,-.00017,.00017*
1,1,.006,.00058,.00017*
20,1,.006,.00058,.00017,.00108,.00042,0.0*
1,1,.006,.00108,.00042*
20,1,.006,.00108,.00042,.0015,.00083,0.0*
1,1,.006,.0015,.00083*
20,1,.006,.0015,.00083,.00167,.00133,0.0*
1,1,.006,.00167,.00133*
20,1,.006,.00167,.00133,.0015,.00183,0.0*
1,1,.006,.0015,.00183*
20,1,.006,.0015,.00183,.00108,.00225,0.0*
1,1,.006,.00108,.00225*
20,1,.006,.00108,.00225,.00033,.0025,0.0*
1,1,.006,.00033,.0025*
20,1,.006,.00033,.0025,-.00042,.00242,0.0*
1,1,.006,-.00042,.00242*
20,1,.006,-.00042,.00242,-.00117,.00208,0.0*
1,1,.006,-.00117,.00208*
%
%ADD12MACRO12*%
%AMMACRO39*
1,1,.006,-.01633,-.0245*
20,1,.006,-.01633,-.0245,-.01633,.0245,0.0*
1,1,.006,-.01633,.0245*
20,1,.006,-.01633,.0245,.00408,.0245,0.0*
1,1,.006,.00408,.0245*
20,1,.006,.00408,.0245,.01062,.02205,0.0*
1,1,.006,.01062,.02205*
20,1,.006,.01062,.02205,.0147,.01878,0.0*
1,1,.006,.0147,.01878*
20,1,.006,.0147,.01878,.01633,.01225,0.0*
1,1,.006,.01633,.01225*
20,1,.006,.01633,.01225,.0147,.00572,0.0*
1,1,.006,.0147,.00572*
20,1,.006,.0147,.00572,.0098,.00163,0.0*
1,1,.006,.0098,.00163*
20,1,.006,.0098,.00163,.00408,-.00082,0.0*
1,1,.006,.00408,-.00082*
20,1,.006,.00408,-.00082,-.01633,-.00082,0.0*
1,1,.006,-.01633,-.00082*
1,1,.006,.00408,-.00082*
20,1,.006,.00408,-.00082,.01633,-.0245,0.0*
1,1,.006,.01633,-.0245*
%
%ADD39MACRO39*%
%AMMACRO61*
1,1,.006,-.012,.0155*
20,1,.006,-.012,.0155,.012,.0155,0.0*
1,1,.006,.012,.0155*
20,1,.006,.012,.0155,.014692,.015265,0.0*
1,1,.006,.014692,.015265*
20,1,.006,.014692,.015265,.017301,.014565,0.0*
1,1,.006,.017301,.014565*
20,1,.006,.017301,.014565,.01975,.013423,0.0*
1,1,.006,.01975,.013423*
20,1,.006,.01975,.013423,.021963,.011874,0.0*
1,1,.006,.021963,.011874*
20,1,.006,.021963,.011874,.023874,.009963,0.0*
1,1,.006,.023874,.009963*
20,1,.006,.023874,.009963,.025423,.00775,0.0*
1,1,.006,.025423,.00775*
20,1,.006,.025423,.00775,.026565,.005301,0.0*
1,1,.006,.026565,.005301*
20,1,.006,.026565,.005301,.027265,.002692,0.0*
1,1,.006,.027265,.002692*
20,1,.006,.027265,.002692,.0275,0.0,0.0*
1,1,.006,.0275,0.0*
20,1,.006,.0275,0.0,.027265,-.002692,0.0*
1,1,.006,.027265,-.002692*
20,1,.006,.027265,-.002692,.026565,-.005301,0.0*
1,1,.006,.026565,-.005301*
20,1,.006,.026565,-.005301,.025423,-.00775,0.0*
1,1,.006,.025423,-.00775*
20,1,.006,.025423,-.00775,.023874,-.009963,0.0*
1,1,.006,.023874,-.009963*
20,1,.006,.023874,-.009963,.021963,-.011874,0.0*
1,1,.006,.021963,-.011874*
20,1,.006,.021963,-.011874,.01975,-.013423,0.0*
1,1,.006,.01975,-.013423*
20,1,.006,.01975,-.013423,.017301,-.014565,0.0*
1,1,.006,.017301,-.014565*
20,1,.006,.017301,-.014565,.014692,-.015265,0.0*
1,1,.006,.014692,-.015265*
20,1,.006,.014692,-.015265,.012,-.0155,0.0*
1,1,.006,.012,-.0155*
20,1,.006,.012,-.0155,-.012,-.0155,0.0*
1,1,.006,-.012,-.0155*
20,1,.006,-.012,-.0155,-.014692,-.015265,0.0*
1,1,.006,-.014692,-.015265*
20,1,.006,-.014692,-.015265,-.017301,-.014565,0.0*
1,1,.006,-.017301,-.014565*
20,1,.006,-.017301,-.014565,-.01975,-.013423,0.0*
1,1,.006,-.01975,-.013423*
20,1,.006,-.01975,-.013423,-.021963,-.011874,0.0*
1,1,.006,-.021963,-.011874*
20,1,.006,-.021963,-.011874,-.023874,-.009963,0.0*
1,1,.006,-.023874,-.009963*
20,1,.006,-.023874,-.009963,-.025423,-.00775,0.0*
1,1,.006,-.025423,-.00775*
20,1,.006,-.025423,-.00775,-.026565,-.005301,0.0*
1,1,.006,-.026565,-.005301*
20,1,.006,-.026565,-.005301,-.027265,-.002692,0.0*
1,1,.006,-.027265,-.002692*
20,1,.006,-.027265,-.002692,-.0275,0.0,0.0*
1,1,.006,-.0275,0.0*
20,1,.006,-.0275,0.0,-.027265,.002692,0.0*
1,1,.006,-.027265,.002692*
20,1,.006,-.027265,.002692,-.026565,.005301,0.0*
1,1,.006,-.026565,.005301*
20,1,.006,-.026565,.005301,-.025423,.00775,0.0*
1,1,.006,-.025423,.00775*
20,1,.006,-.025423,.00775,-.023874,.009963,0.0*
1,1,.006,-.023874,.009963*
20,1,.006,-.023874,.009963,-.021963,.011874,0.0*
1,1,.006,-.021963,.011874*
20,1,.006,-.021963,.011874,-.01975,.013423,0.0*
1,1,.006,-.01975,.013423*
20,1,.006,-.01975,.013423,-.017301,.014565,0.0*
1,1,.006,-.017301,.014565*
20,1,.006,-.017301,.014565,-.014692,.015265,0.0*
1,1,.006,-.014692,.015265*
20,1,.006,-.014692,.015265,-.012,.0155,0.0*
1,1,.006,-.012,.0155*
1,1,.006,-.00775,-.00775*
20,1,.006,-.00775,-.00775,-.00982,-.00749,0.0*
1,1,.006,-.00982,-.00749*
20,1,.006,-.00982,-.00749,-.01162,-.00646,0.0*
1,1,.006,-.01162,-.00646*
20,1,.006,-.01162,-.00646,-.01318,-.00491,0.0*
1,1,.006,-.01318,-.00491*
20,1,.006,-.01318,-.00491,-.01421,-.0031,0.0*
1,1,.006,-.01421,-.0031*
20,1,.006,-.01421,-.0031,-.01473,-.00103,0.0*
1,1,.006,-.01473,-.00103*
20,1,.006,-.01473,-.00103,-.01473,.00103,0.0*
1,1,.006,-.01473,.00103*
20,1,.006,-.01473,.00103,-.01421,.0031,0.0*
1,1,.006,-.01421,.0031*
20,1,.006,-.01421,.0031,-.01318,.00491,0.0*
1,1,.006,-.01318,.00491*
20,1,.006,-.01318,.00491,-.01162,.00646,0.0*
1,1,.006,-.01162,.00646*
20,1,.006,-.01162,.00646,-.00982,.00749,0.0*
1,1,.006,-.00982,.00749*
20,1,.006,-.00982,.00749,-.00775,.00775,0.0*
1,1,.006,-.00775,.00775*
20,1,.006,-.00775,.00775,-.00568,.00749,0.0*
1,1,.006,-.00568,.00749*
20,1,.006,-.00568,.00749,-.00388,.00646,0.0*
1,1,.006,-.00388,.00646*
20,1,.006,-.00388,.00646,-.00232,.00491,0.0*
1,1,.006,-.00232,.00491*
20,1,.006,-.00232,.00491,-.00129,.0031,0.0*
1,1,.006,-.00129,.0031*
20,1,.006,-.00129,.0031,-.00077,.00103,0.0*
1,1,.006,-.00077,.00103*
20,1,.006,-.00077,.00103,-.00077,-.00103,0.0*
1,1,.006,-.00077,-.00103*
20,1,.006,-.00077,-.00103,-.00129,-.0031,0.0*
1,1,.006,-.00129,-.0031*
20,1,.006,-.00129,-.0031,-.00232,-.00491,0.0*
1,1,.006,-.00232,-.00491*
20,1,.006,-.00232,-.00491,-.00388,-.00646,0.0*
1,1,.006,-.00388,-.00646*
20,1,.006,-.00388,-.00646,-.00568,-.00749,0.0*
1,1,.006,-.00568,-.00749*
20,1,.006,-.00568,-.00749,-.00775,-.00775,0.0*
1,1,.006,-.00775,-.00775*
1,1,.006,.01344,.00646*
20,1,.006,.01344,.00646,.01189,.00723,0.0*
1,1,.006,.01189,.00723*
20,1,.006,.01189,.00723,.01009,.00775,0.0*
1,1,.006,.01009,.00775*
20,1,.006,.01009,.00775,.00802,.00775,0.0*
1,1,.006,.00802,.00775*
20,1,.006,.00802,.00775,.00569,.00697,0.0*
1,1,.006,.00569,.00697*
20,1,.006,.00569,.00697,.00389,.00568,0.0*
1,1,.006,.00389,.00568*
20,1,.006,.00389,.00568,.00259,.00413,0.0*
1,1,.006,.00259,.00413*
20,1,.006,.00259,.00413,.00156,.00155,0.0*
1,1,.006,.00156,.00155*
20,1,.006,.00156,.00155,.0013,-.00078,0.0*
1,1,.006,.0013,-.00078*
20,1,.006,.0013,-.00078,.00182,-.0031,0.0*
1,1,.006,.00182,-.0031*
20,1,.006,.00182,-.0031,.00259,-.00465,0.0*
1,1,.006,.00259,-.00465*
20,1,.006,.00259,-.00465,.00414,-.0062,0.0*
1,1,.006,.00414,-.0062*
20,1,.006,.00414,-.0062,.00595,-.00723,0.0*
1,1,.006,.00595,-.00723*
20,1,.006,.00595,-.00723,.00776,-.00775,0.0*
1,1,.006,.00776,-.00775*
20,1,.006,.00776,-.00775,.00957,-.00775,0.0*
1,1,.006,.00957,-.00775*
20,1,.006,.00957,-.00775,.01138,-.00723,0.0*
1,1,.006,.01138,-.00723*
20,1,.006,.01138,-.00723,.01293,-.00646,0.0*
1,1,.006,.01293,-.00646*
20,1,.006,.01293,-.00646,.01422,-.00543,0.0*
1,1,.006,.01422,-.00543*
%
%ADD61MACRO61*%
%AMMACRO33*
1,1,.006,0.0,.005*
20,1,.006,0.0,.005,-.00433,.0025,0.0*
1,1,.006,-.00433,.0025*
20,1,.006,-.00433,.0025,-.00433,-.0025,0.0*
1,1,.006,-.00433,-.0025*
20,1,.006,-.00433,-.0025,0.0,-.005,0.0*
1,1,.006,0.0,-.005*
20,1,.006,0.0,-.005,.00433,-.0025,0.0*
1,1,.006,.00433,-.0025*
20,1,.006,.00433,-.0025,.00433,.0025,0.0*
1,1,.006,.00433,.0025*
20,1,.006,.00433,.0025,0.0,.005,0.0*
1,1,.006,0.0,.005*
1,1,.006,.001,-.0025*
20,1,.006,.001,-.0025,.001,.0025,0.0*
1,1,.006,.001,.0025*
20,1,.006,.001,.0025,-.00208,-.00108,0.0*
1,1,.006,-.00208,-.00108*
20,1,.006,-.00208,-.00108,.00208,-.00108,0.0*
1,1,.006,.00208,-.00108*
%
%ADD33MACRO33*%
%AMMACRO46*
1,1,.006,-.0649,.0885*
20,1,.006,-.0649,.0885,-.0649,-.03835,0.0*
1,1,.006,-.0649,-.03835*
20,1,.006,-.0649,-.03835,-.0531,-.06491,0.0*
1,1,.006,-.0531,-.06491*
20,1,.006,-.0531,-.06491,-.0295,-.0826,0.0*
1,1,.006,-.0295,-.0826*
20,1,.006,-.0295,-.0826,0.0,-.0885,0.0*
1,1,.006,0.0,-.0885*
20,1,.006,0.0,-.0885,.0295,-.0826,0.0*
1,1,.006,.0295,-.0826*
20,1,.006,.0295,-.0826,.0531,-.06491,0.0*
1,1,.006,.0531,-.06491*
20,1,.006,.0531,-.06491,.0649,-.03835,0.0*
1,1,.006,.0649,-.03835*
20,1,.006,.0649,-.03835,.0649,.0885,0.0*
1,1,.006,.0649,.0885*
%
%ADD46MACRO46*%
%AMMACRO63*
1,1,.006,-.026,.0155*
20,1,.006,-.026,.0155,.026,.0155,0.0*
1,1,.006,.026,.0155*
20,1,.006,.026,.0155,.028692,.015265,0.0*
1,1,.006,.028692,.015265*
20,1,.006,.028692,.015265,.031301,.014565,0.0*
1,1,.006,.031301,.014565*
20,1,.006,.031301,.014565,.03375,.013423,0.0*
1,1,.006,.03375,.013423*
20,1,.006,.03375,.013423,.035963,.011874,0.0*
1,1,.006,.035963,.011874*
20,1,.006,.035963,.011874,.037874,.009963,0.0*
1,1,.006,.037874,.009963*
20,1,.006,.037874,.009963,.039423,.00775,0.0*
1,1,.006,.039423,.00775*
20,1,.006,.039423,.00775,.040565,.005301,0.0*
1,1,.006,.040565,.005301*
20,1,.006,.040565,.005301,.041265,.002692,0.0*
1,1,.006,.041265,.002692*
20,1,.006,.041265,.002692,.0415,0.0,0.0*
1,1,.006,.0415,0.0*
20,1,.006,.0415,0.0,.041265,-.002692,0.0*
1,1,.006,.041265,-.002692*
20,1,.006,.041265,-.002692,.040565,-.005301,0.0*
1,1,.006,.040565,-.005301*
20,1,.006,.040565,-.005301,.039423,-.00775,0.0*
1,1,.006,.039423,-.00775*
20,1,.006,.039423,-.00775,.037874,-.009963,0.0*
1,1,.006,.037874,-.009963*
20,1,.006,.037874,-.009963,.035963,-.011874,0.0*
1,1,.006,.035963,-.011874*
20,1,.006,.035963,-.011874,.03375,-.013423,0.0*
1,1,.006,.03375,-.013423*
20,1,.006,.03375,-.013423,.031301,-.014565,0.0*
1,1,.006,.031301,-.014565*
20,1,.006,.031301,-.014565,.028692,-.015265,0.0*
1,1,.006,.028692,-.015265*
20,1,.006,.028692,-.015265,.026,-.0155,0.0*
1,1,.006,.026,-.0155*
20,1,.006,.026,-.0155,-.026,-.0155,0.0*
1,1,.006,-.026,-.0155*
20,1,.006,-.026,-.0155,-.028692,-.015265,0.0*
1,1,.006,-.028692,-.015265*
20,1,.006,-.028692,-.015265,-.031301,-.014565,0.0*
1,1,.006,-.031301,-.014565*
20,1,.006,-.031301,-.014565,-.03375,-.013423,0.0*
1,1,.006,-.03375,-.013423*
20,1,.006,-.03375,-.013423,-.035963,-.011874,0.0*
1,1,.006,-.035963,-.011874*
20,1,.006,-.035963,-.011874,-.037874,-.009963,0.0*
1,1,.006,-.037874,-.009963*
20,1,.006,-.037874,-.009963,-.039423,-.00775,0.0*
1,1,.006,-.039423,-.00775*
20,1,.006,-.039423,-.00775,-.040565,-.005301,0.0*
1,1,.006,-.040565,-.005301*
20,1,.006,-.040565,-.005301,-.041265,-.002692,0.0*
1,1,.006,-.041265,-.002692*
20,1,.006,-.041265,-.002692,-.0415,0.0,0.0*
1,1,.006,-.0415,0.0*
20,1,.006,-.0415,0.0,-.041265,.002692,0.0*
1,1,.006,-.041265,.002692*
20,1,.006,-.041265,.002692,-.040565,.005301,0.0*
1,1,.006,-.040565,.005301*
20,1,.006,-.040565,.005301,-.039423,.00775,0.0*
1,1,.006,-.039423,.00775*
20,1,.006,-.039423,.00775,-.037874,.009963,0.0*
1,1,.006,-.037874,.009963*
20,1,.006,-.037874,.009963,-.035963,.011874,0.0*
1,1,.006,-.035963,.011874*
20,1,.006,-.035963,.011874,-.03375,.013423,0.0*
1,1,.006,-.03375,.013423*
20,1,.006,-.03375,.013423,-.031301,.014565,0.0*
1,1,.006,-.031301,.014565*
20,1,.006,-.031301,.014565,-.028692,.015265,0.0*
1,1,.006,-.028692,.015265*
20,1,.006,-.028692,.015265,-.026,.0155,0.0*
1,1,.006,-.026,.0155*
1,1,.006,-.00775,-.00775*
20,1,.006,-.00775,-.00775,-.00982,-.00749,0.0*
1,1,.006,-.00982,-.00749*
20,1,.006,-.00982,-.00749,-.01162,-.00646,0.0*
1,1,.006,-.01162,-.00646*
20,1,.006,-.01162,-.00646,-.01318,-.00491,0.0*
1,1,.006,-.01318,-.00491*
20,1,.006,-.01318,-.00491,-.01421,-.0031,0.0*
1,1,.006,-.01421,-.0031*
20,1,.006,-.01421,-.0031,-.01473,-.00103,0.0*
1,1,.006,-.01473,-.00103*
20,1,.006,-.01473,-.00103,-.01473,.00103,0.0*
1,1,.006,-.01473,.00103*
20,1,.006,-.01473,.00103,-.01421,.0031,0.0*
1,1,.006,-.01421,.0031*
20,1,.006,-.01421,.0031,-.01318,.00491,0.0*
1,1,.006,-.01318,.00491*
20,1,.006,-.01318,.00491,-.01162,.00646,0.0*
1,1,.006,-.01162,.00646*
20,1,.006,-.01162,.00646,-.00982,.00749,0.0*
1,1,.006,-.00982,.00749*
20,1,.006,-.00982,.00749,-.00775,.00775,0.0*
1,1,.006,-.00775,.00775*
20,1,.006,-.00775,.00775,-.00568,.00749,0.0*
1,1,.006,-.00568,.00749*
20,1,.006,-.00568,.00749,-.00388,.00646,0.0*
1,1,.006,-.00388,.00646*
20,1,.006,-.00388,.00646,-.00232,.00491,0.0*
1,1,.006,-.00232,.00491*
20,1,.006,-.00232,.00491,-.00129,.0031,0.0*
1,1,.006,-.00129,.0031*
20,1,.006,-.00129,.0031,-.00077,.00103,0.0*
1,1,.006,-.00077,.00103*
20,1,.006,-.00077,.00103,-.00077,-.00103,0.0*
1,1,.006,-.00077,-.00103*
20,1,.006,-.00077,-.00103,-.00129,-.0031,0.0*
1,1,.006,-.00129,-.0031*
20,1,.006,-.00129,-.0031,-.00232,-.00491,0.0*
1,1,.006,-.00232,-.00491*
20,1,.006,-.00232,-.00491,-.00388,-.00646,0.0*
1,1,.006,-.00388,-.00646*
20,1,.006,-.00388,-.00646,-.00568,-.00749,0.0*
1,1,.006,-.00568,-.00749*
20,1,.006,-.00568,-.00749,-.00775,-.00775,0.0*
1,1,.006,-.00775,-.00775*
1,1,.006,.00208,-.00775*
20,1,.006,.00208,-.00775,.00208,.00775,0.0*
1,1,.006,.00208,.00775*
20,1,.006,.00208,.00775,.00724,.00775,0.0*
1,1,.006,.00724,.00775*
20,1,.006,.00724,.00775,.00931,.00697,0.0*
1,1,.006,.00931,.00697*
20,1,.006,.00931,.00697,.01086,.00594,0.0*
1,1,.006,.01086,.00594*
20,1,.006,.01086,.00594,.01215,.00439,0.0*
1,1,.006,.01215,.00439*
20,1,.006,.01215,.00439,.01319,.00258,0.0*
1,1,.006,.01319,.00258*
20,1,.006,.01319,.00258,.01344,0.0,0.0*
1,1,.006,.01344,0.0*
20,1,.006,.01344,0.0,.01319,-.00258,0.0*
1,1,.006,.01319,-.00258*
20,1,.006,.01319,-.00258,.01215,-.00439,0.0*
1,1,.006,.01215,-.00439*
20,1,.006,.01215,-.00439,.01086,-.00594,0.0*
1,1,.006,.01086,-.00594*
20,1,.006,.01086,-.00594,.00931,-.00698,0.0*
1,1,.006,.00931,-.00698*
20,1,.006,.00931,-.00698,.00724,-.00775,0.0*
1,1,.006,.00724,-.00775*
20,1,.006,.00724,-.00775,.00208,-.00775,0.0*
1,1,.006,.00208,-.00775*
%
%ADD63MACRO63*%
%AMMACRO51*
1,1,.006,-.063,-.0325*
20,1,.006,-.063,-.0325,-.063,.0325,0.0*
1,1,.006,-.063,.0325*
20,1,.006,-.063,.0325,-.062043,.04344,0.0*
1,1,.006,-.062043,.04344*
20,1,.006,-.062043,.04344,-.059201,.054047,0.0*
1,1,.006,-.059201,.054047*
20,1,.006,-.059201,.054047,-.05456,.064,0.0*
1,1,.006,-.05456,.064*
20,1,.006,-.05456,.064,-.048261,.072996,0.0*
1,1,.006,-.048261,.072996*
20,1,.006,-.048261,.072996,-.040496,.080761,0.0*
1,1,.006,-.040496,.080761*
20,1,.006,-.040496,.080761,-.0315,.08706,0.0*
1,1,.006,-.0315,.08706*
20,1,.006,-.0315,.08706,-.021547,.091701,0.0*
1,1,.006,-.021547,.091701*
20,1,.006,-.021547,.091701,-.01094,.094543,0.0*
1,1,.006,-.01094,.094543*
20,1,.006,-.01094,.094543,0.0,.0955,0.0*
1,1,.006,0.0,.0955*
20,1,.006,0.0,.0955,.01094,.094543,0.0*
1,1,.006,.01094,.094543*
20,1,.006,.01094,.094543,.021547,.091701,0.0*
1,1,.006,.021547,.091701*
20,1,.006,.021547,.091701,.0315,.08706,0.0*
1,1,.006,.0315,.08706*
20,1,.006,.0315,.08706,.040496,.080761,0.0*
1,1,.006,.040496,.080761*
20,1,.006,.040496,.080761,.048261,.072996,0.0*
1,1,.006,.048261,.072996*
20,1,.006,.048261,.072996,.05456,.064,0.0*
1,1,.006,.05456,.064*
20,1,.006,.05456,.064,.059201,.054047,0.0*
1,1,.006,.059201,.054047*
20,1,.006,.059201,.054047,.062043,.04344,0.0*
1,1,.006,.062043,.04344*
20,1,.006,.062043,.04344,.063,.0325,0.0*
1,1,.006,.063,.0325*
20,1,.006,.063,.0325,.063,-.0325,0.0*
1,1,.006,.063,-.0325*
20,1,.006,.063,-.0325,.062043,-.04344,0.0*
1,1,.006,.062043,-.04344*
20,1,.006,.062043,-.04344,.059201,-.054047,0.0*
1,1,.006,.059201,-.054047*
20,1,.006,.059201,-.054047,.05456,-.064,0.0*
1,1,.006,.05456,-.064*
20,1,.006,.05456,-.064,.048261,-.072996,0.0*
1,1,.006,.048261,-.072996*
20,1,.006,.048261,-.072996,.040496,-.080761,0.0*
1,1,.006,.040496,-.080761*
20,1,.006,.040496,-.080761,.0315,-.08706,0.0*
1,1,.006,.0315,-.08706*
20,1,.006,.0315,-.08706,.021547,-.091701,0.0*
1,1,.006,.021547,-.091701*
20,1,.006,.021547,-.091701,.01094,-.094543,0.0*
1,1,.006,.01094,-.094543*
20,1,.006,.01094,-.094543,0.0,-.0955,0.0*
1,1,.006,0.0,-.0955*
20,1,.006,0.0,-.0955,-.01094,-.094543,0.0*
1,1,.006,-.01094,-.094543*
20,1,.006,-.01094,-.094543,-.021547,-.091701,0.0*
1,1,.006,-.021547,-.091701*
20,1,.006,-.021547,-.091701,-.0315,-.08706,0.0*
1,1,.006,-.0315,-.08706*
20,1,.006,-.0315,-.08706,-.040496,-.080761,0.0*
1,1,.006,-.040496,-.080761*
20,1,.006,-.040496,-.080761,-.048261,-.072996,0.0*
1,1,.006,-.048261,-.072996*
20,1,.006,-.048261,-.072996,-.05456,-.064,0.0*
1,1,.006,-.05456,-.064*
20,1,.006,-.05456,-.064,-.059201,-.054047,0.0*
1,1,.006,-.059201,-.054047*
20,1,.006,-.059201,-.054047,-.062043,-.04344,0.0*
1,1,.006,-.062043,-.04344*
20,1,.006,-.062043,-.04344,-.063,-.0325,0.0*
1,1,.006,-.063,-.0325*
1,1,.006,-.0315,-.0315*
20,1,.006,-.0315,-.0315,-.0399,-.03045,0.0*
1,1,.006,-.0399,-.03045*
20,1,.006,-.0399,-.03045,-.04725,-.02625,0.0*
1,1,.006,-.04725,-.02625*
20,1,.006,-.04725,-.02625,-.05355,-.01995,0.0*
1,1,.006,-.05355,-.01995*
20,1,.006,-.05355,-.01995,-.05775,-.0126,0.0*
1,1,.006,-.05775,-.0126*
20,1,.006,-.05775,-.0126,-.05985,-.0042,0.0*
1,1,.006,-.05985,-.0042*
20,1,.006,-.05985,-.0042,-.05985,.0042,0.0*
1,1,.006,-.05985,.0042*
20,1,.006,-.05985,.0042,-.05775,.0126,0.0*
1,1,.006,-.05775,.0126*
20,1,.006,-.05775,.0126,-.05355,.01995,0.0*
1,1,.006,-.05355,.01995*
20,1,.006,-.05355,.01995,-.04725,.02625,0.0*
1,1,.006,-.04725,.02625*
20,1,.006,-.04725,.02625,-.0399,.03045,0.0*
1,1,.006,-.0399,.03045*
20,1,.006,-.0399,.03045,-.0315,.0315,0.0*
1,1,.006,-.0315,.0315*
20,1,.006,-.0315,.0315,-.0231,.03045,0.0*
1,1,.006,-.0231,.03045*
20,1,.006,-.0231,.03045,-.01575,.02625,0.0*
1,1,.006,-.01575,.02625*
20,1,.006,-.01575,.02625,-.00945,.01995,0.0*
1,1,.006,-.00945,.01995*
20,1,.006,-.00945,.01995,-.00525,.0126,0.0*
1,1,.006,-.00525,.0126*
20,1,.006,-.00525,.0126,-.00315,.0042,0.0*
1,1,.006,-.00315,.0042*
20,1,.006,-.00315,.0042,-.00315,-.0042,0.0*
1,1,.006,-.00315,-.0042*
20,1,.006,-.00315,-.0042,-.00525,-.0126,0.0*
1,1,.006,-.00525,-.0126*
20,1,.006,-.00525,-.0126,-.00945,-.01995,0.0*
1,1,.006,-.00945,-.01995*
20,1,.006,-.00945,-.01995,-.01575,-.02625,0.0*
1,1,.006,-.01575,-.02625*
20,1,.006,-.01575,-.02625,-.0231,-.03045,0.0*
1,1,.006,-.0231,-.03045*
20,1,.006,-.0231,-.03045,-.0315,-.0315,0.0*
1,1,.006,-.0315,-.0315*
1,1,.006,.03781,0.0*
20,1,.006,.03781,0.0,.05881,0.0,0.0*
1,1,.006,.05881,0.0*
20,1,.006,.05881,0.0,.05881,-.0189,0.0*
1,1,.006,.05881,-.0189*
20,1,.006,.05881,-.0189,.05251,-.0252,0.0*
1,1,.006,.05251,-.0252*
20,1,.006,.05251,-.0252,.04516,-.0294,0.0*
1,1,.006,.04516,-.0294*
20,1,.006,.04516,-.0294,.03466,-.0315,0.0*
1,1,.006,.03466,-.0315*
20,1,.006,.03466,-.0315,.02416,-.0294,0.0*
1,1,.006,.02416,-.0294*
20,1,.006,.02416,-.0294,.01681,-.0252,0.0*
1,1,.006,.01681,-.0252*
20,1,.006,.01681,-.0252,.01051,-.0189,0.0*
1,1,.006,.01051,-.0189*
20,1,.006,.01051,-.0189,.00631,-.01155,0.0*
1,1,.006,.00631,-.01155*
20,1,.006,.00631,-.01155,.00421,-.00315,0.0*
1,1,.006,.00421,-.00315*
20,1,.006,.00421,-.00315,.00421,.0042,0.0*
1,1,.006,.00421,.0042*
20,1,.006,.00421,.0042,.00631,.0105,0.0*
1,1,.006,.00631,.0105*
20,1,.006,.00631,.0105,.01051,.01785,0.0*
1,1,.006,.01051,.01785*
20,1,.006,.01051,.01785,.01681,.02415,0.0*
1,1,.006,.01681,.02415*
20,1,.006,.01681,.02415,.02311,.02835,0.0*
1,1,.006,.02311,.02835*
20,1,.006,.02311,.02835,.03151,.0315,0.0*
1,1,.006,.03151,.0315*
20,1,.006,.03151,.0315,.03886,.0315,0.0*
1,1,.006,.03886,.0315*
20,1,.006,.03886,.0315,.04726,.0294,0.0*
1,1,.006,.04726,.0294*
20,1,.006,.04726,.0294,.05356,.0252,0.0*
1,1,.006,.05356,.0252*
%
%ADD51MACRO51*%
%AMMACRO27*
1,1,.006,-.0336,-.0352*
20,1,.006,-.0336,-.0352,-.0208,-.0432,0.0*
1,1,.006,-.0208,-.0432*
20,1,.006,-.0208,-.0432,-.0064,-.048,0.0*
1,1,.006,-.0064,-.048*
20,1,.006,-.0064,-.048,.0064,-.048,0.0*
1,1,.006,.0064,-.048*
20,1,.006,.0064,-.048,.0192,-.0432,0.0*
1,1,.006,.0192,-.0432*
20,1,.006,.0192,-.0432,.0288,-.0352,0.0*
1,1,.006,.0288,-.0352*
20,1,.006,.0288,-.0352,.0336,-.024,0.0*
1,1,.006,.0336,-.024*
20,1,.006,.0336,-.024,.0304,-.0128,0.0*
1,1,.006,.0304,-.0128*
20,1,.006,.0304,-.0128,.0224,-.0032,0.0*
1,1,.006,.0224,-.0032*
20,1,.006,.0224,-.0032,.008,.0032,0.0*
1,1,.006,.008,.0032*
20,1,.006,.008,.0032,-.0112,.0064,0.0*
1,1,.006,-.0112,.0064*
20,1,.006,-.0112,.0064,-.0224,.0128,0.0*
1,1,.006,-.0224,.0128*
20,1,.006,-.0224,.0128,-.0272,.024,0.0*
1,1,.006,-.0272,.024*
20,1,.006,-.0272,.024,-.024,.0352,0.0*
1,1,.006,-.024,.0352*
20,1,.006,-.024,.0352,-.016,.0432,0.0*
1,1,.006,-.016,.0432*
20,1,.006,-.016,.0432,-.0048,.048,0.0*
1,1,.006,-.0048,.048*
20,1,.006,-.0048,.048,.0064,.048,0.0*
1,1,.006,.0064,.048*
20,1,.006,.0064,.048,.0176,.0448,0.0*
1,1,.006,.0176,.0448*
20,1,.006,.0176,.0448,.0272,.0368,0.0*
1,1,.006,.0272,.0368*
%
%ADD27MACRO27*%
%AMMACRO57*
1,1,.006,-.0325,.063*
20,1,.006,-.0325,.063,.0325,.063,0.0*
1,1,.006,.0325,.063*
20,1,.006,.0325,.063,.04344,.062043,0.0*
1,1,.006,.04344,.062043*
20,1,.006,.04344,.062043,.054047,.059201,0.0*
1,1,.006,.054047,.059201*
20,1,.006,.054047,.059201,.064,.05456,0.0*
1,1,.006,.064,.05456*
20,1,.006,.064,.05456,.072996,.048261,0.0*
1,1,.006,.072996,.048261*
20,1,.006,.072996,.048261,.080761,.040496,0.0*
1,1,.006,.080761,.040496*
20,1,.006,.080761,.040496,.08706,.0315,0.0*
1,1,.006,.08706,.0315*
20,1,.006,.08706,.0315,.091701,.021547,0.0*
1,1,.006,.091701,.021547*
20,1,.006,.091701,.021547,.094543,.01094,0.0*
1,1,.006,.094543,.01094*
20,1,.006,.094543,.01094,.0955,0.0,0.0*
1,1,.006,.0955,0.0*
20,1,.006,.0955,0.0,.094543,-.01094,0.0*
1,1,.006,.094543,-.01094*
20,1,.006,.094543,-.01094,.091701,-.021547,0.0*
1,1,.006,.091701,-.021547*
20,1,.006,.091701,-.021547,.08706,-.0315,0.0*
1,1,.006,.08706,-.0315*
20,1,.006,.08706,-.0315,.080761,-.040496,0.0*
1,1,.006,.080761,-.040496*
20,1,.006,.080761,-.040496,.072996,-.048261,0.0*
1,1,.006,.072996,-.048261*
20,1,.006,.072996,-.048261,.064,-.05456,0.0*
1,1,.006,.064,-.05456*
20,1,.006,.064,-.05456,.054047,-.059201,0.0*
1,1,.006,.054047,-.059201*
20,1,.006,.054047,-.059201,.04344,-.062043,0.0*
1,1,.006,.04344,-.062043*
20,1,.006,.04344,-.062043,.0325,-.063,0.0*
1,1,.006,.0325,-.063*
20,1,.006,.0325,-.063,-.0325,-.063,0.0*
1,1,.006,-.0325,-.063*
20,1,.006,-.0325,-.063,-.04344,-.062043,0.0*
1,1,.006,-.04344,-.062043*
20,1,.006,-.04344,-.062043,-.054047,-.059201,0.0*
1,1,.006,-.054047,-.059201*
20,1,.006,-.054047,-.059201,-.064,-.05456,0.0*
1,1,.006,-.064,-.05456*
20,1,.006,-.064,-.05456,-.072996,-.048261,0.0*
1,1,.006,-.072996,-.048261*
20,1,.006,-.072996,-.048261,-.080761,-.040496,0.0*
1,1,.006,-.080761,-.040496*
20,1,.006,-.080761,-.040496,-.08706,-.0315,0.0*
1,1,.006,-.08706,-.0315*
20,1,.006,-.08706,-.0315,-.091701,-.021547,0.0*
1,1,.006,-.091701,-.021547*
20,1,.006,-.091701,-.021547,-.094543,-.01094,0.0*
1,1,.006,-.094543,-.01094*
20,1,.006,-.094543,-.01094,-.0955,0.0,0.0*
1,1,.006,-.0955,0.0*
20,1,.006,-.0955,0.0,-.094543,.01094,0.0*
1,1,.006,-.094543,.01094*
20,1,.006,-.094543,.01094,-.091701,.021547,0.0*
1,1,.006,-.091701,.021547*
20,1,.006,-.091701,.021547,-.08706,.0315,0.0*
1,1,.006,-.08706,.0315*
20,1,.006,-.08706,.0315,-.080761,.040496,0.0*
1,1,.006,-.080761,.040496*
20,1,.006,-.080761,.040496,-.072996,.048261,0.0*
1,1,.006,-.072996,.048261*
20,1,.006,-.072996,.048261,-.064,.05456,0.0*
1,1,.006,-.064,.05456*
20,1,.006,-.064,.05456,-.054047,.059201,0.0*
1,1,.006,-.054047,.059201*
20,1,.006,-.054047,.059201,-.04344,.062043,0.0*
1,1,.006,-.04344,.062043*
20,1,.006,-.04344,.062043,-.0325,.063,0.0*
1,1,.006,-.0325,.063*
1,1,.006,-.0315,-.0315*
20,1,.006,-.0315,-.0315,-.0399,-.03045,0.0*
1,1,.006,-.0399,-.03045*
20,1,.006,-.0399,-.03045,-.04725,-.02625,0.0*
1,1,.006,-.04725,-.02625*
20,1,.006,-.04725,-.02625,-.05355,-.01995,0.0*
1,1,.006,-.05355,-.01995*
20,1,.006,-.05355,-.01995,-.05775,-.0126,0.0*
1,1,.006,-.05775,-.0126*
20,1,.006,-.05775,-.0126,-.05985,-.0042,0.0*
1,1,.006,-.05985,-.0042*
20,1,.006,-.05985,-.0042,-.05985,.0042,0.0*
1,1,.006,-.05985,.0042*
20,1,.006,-.05985,.0042,-.05775,.0126,0.0*
1,1,.006,-.05775,.0126*
20,1,.006,-.05775,.0126,-.05355,.01995,0.0*
1,1,.006,-.05355,.01995*
20,1,.006,-.05355,.01995,-.04725,.02625,0.0*
1,1,.006,-.04725,.02625*
20,1,.006,-.04725,.02625,-.0399,.03045,0.0*
1,1,.006,-.0399,.03045*
20,1,.006,-.0399,.03045,-.0315,.0315,0.0*
1,1,.006,-.0315,.0315*
20,1,.006,-.0315,.0315,-.0231,.03045,0.0*
1,1,.006,-.0231,.03045*
20,1,.006,-.0231,.03045,-.01575,.02625,0.0*
1,1,.006,-.01575,.02625*
20,1,.006,-.01575,.02625,-.00945,.01995,0.0*
1,1,.006,-.00945,.01995*
20,1,.006,-.00945,.01995,-.00525,.0126,0.0*
1,1,.006,-.00525,.0126*
20,1,.006,-.00525,.0126,-.00315,.0042,0.0*
1,1,.006,-.00315,.0042*
20,1,.006,-.00315,.0042,-.00315,-.0042,0.0*
1,1,.006,-.00315,-.0042*
20,1,.006,-.00315,-.0042,-.00525,-.0126,0.0*
1,1,.006,-.00525,-.0126*
20,1,.006,-.00525,-.0126,-.00945,-.01995,0.0*
1,1,.006,-.00945,-.01995*
20,1,.006,-.00945,-.01995,-.01575,-.02625,0.0*
1,1,.006,-.01575,-.02625*
20,1,.006,-.01575,-.02625,-.0231,-.03045,0.0*
1,1,.006,-.0231,-.03045*
20,1,.006,-.0231,-.03045,-.0315,-.0315,0.0*
1,1,.006,-.0315,-.0315*
1,1,.006,.03781,0.0*
20,1,.006,.03781,0.0,.05881,0.0,0.0*
1,1,.006,.05881,0.0*
20,1,.006,.05881,0.0,.05881,-.0189,0.0*
1,1,.006,.05881,-.0189*
20,1,.006,.05881,-.0189,.05251,-.0252,0.0*
1,1,.006,.05251,-.0252*
20,1,.006,.05251,-.0252,.04516,-.0294,0.0*
1,1,.006,.04516,-.0294*
20,1,.006,.04516,-.0294,.03466,-.0315,0.0*
1,1,.006,.03466,-.0315*
20,1,.006,.03466,-.0315,.02416,-.0294,0.0*
1,1,.006,.02416,-.0294*
20,1,.006,.02416,-.0294,.01681,-.0252,0.0*
1,1,.006,.01681,-.0252*
20,1,.006,.01681,-.0252,.01051,-.0189,0.0*
1,1,.006,.01051,-.0189*
20,1,.006,.01051,-.0189,.00631,-.01155,0.0*
1,1,.006,.00631,-.01155*
20,1,.006,.00631,-.01155,.00421,-.00315,0.0*
1,1,.006,.00421,-.00315*
20,1,.006,.00421,-.00315,.00421,.0042,0.0*
1,1,.006,.00421,.0042*
20,1,.006,.00421,.0042,.00631,.0105,0.0*
1,1,.006,.00631,.0105*
20,1,.006,.00631,.0105,.01051,.01785,0.0*
1,1,.006,.01051,.01785*
20,1,.006,.01051,.01785,.01681,.02415,0.0*
1,1,.006,.01681,.02415*
20,1,.006,.01681,.02415,.02311,.02835,0.0*
1,1,.006,.02311,.02835*
20,1,.006,.02311,.02835,.03151,.0315,0.0*
1,1,.006,.03151,.0315*
20,1,.006,.03151,.0315,.03886,.0315,0.0*
1,1,.006,.03886,.0315*
20,1,.006,.03886,.0315,.04726,.0294,0.0*
1,1,.006,.04726,.0294*
20,1,.006,.04726,.0294,.05356,.0252,0.0*
1,1,.006,.05356,.0252*
%
%ADD57MACRO57*%
%AMMACRO30*
1,1,.006,-.006,.002*
20,1,.006,-.006,.002,-.005909,.003042,0.0*
1,1,.006,-.005909,.003042*
20,1,.006,-.005909,.003042,-.005638,.004052,0.0*
1,1,.006,-.005638,.004052*
20,1,.006,-.005638,.004052,-.005196,.005,0.0*
1,1,.006,-.005196,.005*
20,1,.006,-.005196,.005,-.004596,.005857,0.0*
1,1,.006,-.004596,.005857*
20,1,.006,-.004596,.005857,-.003857,.006596,0.0*
1,1,.006,-.003857,.006596*
20,1,.006,-.003857,.006596,-.003,.007196,0.0*
1,1,.006,-.003,.007196*
20,1,.006,-.003,.007196,-.002052,.007638,0.0*
1,1,.006,-.002052,.007638*
20,1,.006,-.002052,.007638,-.001042,.007909,0.0*
1,1,.006,-.001042,.007909*
20,1,.006,-.001042,.007909,0.0,.008,0.0*
1,1,.006,0.0,.008*
20,1,.006,0.0,.008,.001042,.007909,0.0*
1,1,.006,.001042,.007909*
20,1,.006,.001042,.007909,.002052,.007638,0.0*
1,1,.006,.002052,.007638*
20,1,.006,.002052,.007638,.003,.007196,0.0*
1,1,.006,.003,.007196*
20,1,.006,.003,.007196,.003857,.006596,0.0*
1,1,.006,.003857,.006596*
20,1,.006,.003857,.006596,.004596,.005857,0.0*
1,1,.006,.004596,.005857*
20,1,.006,.004596,.005857,.005196,.005,0.0*
1,1,.006,.005196,.005*
20,1,.006,.005196,.005,.005638,.004052,0.0*
1,1,.006,.005638,.004052*
20,1,.006,.005638,.004052,.005909,.003042,0.0*
1,1,.006,.005909,.003042*
20,1,.006,.005909,.003042,.006,.002,0.0*
1,1,.006,.006,.002*
20,1,.006,.006,.002,.006,-.002,0.0*
1,1,.006,.006,-.002*
20,1,.006,.006,-.002,.005909,-.003042,0.0*
1,1,.006,.005909,-.003042*
20,1,.006,.005909,-.003042,.005638,-.004052,0.0*
1,1,.006,.005638,-.004052*
20,1,.006,.005638,-.004052,.005196,-.005,0.0*
1,1,.006,.005196,-.005*
20,1,.006,.005196,-.005,.004596,-.005857,0.0*
1,1,.006,.004596,-.005857*
20,1,.006,.004596,-.005857,.003857,-.006596,0.0*
1,1,.006,.003857,-.006596*
20,1,.006,.003857,-.006596,.003,-.007196,0.0*
1,1,.006,.003,-.007196*
20,1,.006,.003,-.007196,.002052,-.007638,0.0*
1,1,.006,.002052,-.007638*
20,1,.006,.002052,-.007638,.001042,-.007909,0.0*
1,1,.006,.001042,-.007909*
20,1,.006,.001042,-.007909,0.0,-.008,0.0*
1,1,.006,0.0,-.008*
20,1,.006,0.0,-.008,-.001042,-.007909,0.0*
1,1,.006,-.001042,-.007909*
20,1,.006,-.001042,-.007909,-.002052,-.007638,0.0*
1,1,.006,-.002052,-.007638*
20,1,.006,-.002052,-.007638,-.003,-.007196,0.0*
1,1,.006,-.003,-.007196*
20,1,.006,-.003,-.007196,-.003857,-.006596,0.0*
1,1,.006,-.003857,-.006596*
20,1,.006,-.003857,-.006596,-.004596,-.005857,0.0*
1,1,.006,-.004596,-.005857*
20,1,.006,-.004596,-.005857,-.005196,-.005,0.0*
1,1,.006,-.005196,-.005*
20,1,.006,-.005196,-.005,-.005638,-.004052,0.0*
1,1,.006,-.005638,-.004052*
20,1,.006,-.005638,-.004052,-.005909,-.003042,0.0*
1,1,.006,-.005909,-.003042*
20,1,.006,-.005909,-.003042,-.006,-.002,0.0*
1,1,.006,-.006,-.002*
20,1,.006,-.006,-.002,-.006,.002,0.0*
1,1,.006,-.006,.002*
1,1,.006,-.0017,-.0023*
20,1,.006,-.0017,-.0023,-.001,-.0028,0.0*
1,1,.006,-.001,-.0028*
20,1,.006,-.001,-.0028,-.0002,-.003,0.0*
1,1,.006,-.0002,-.003*
20,1,.006,-.0002,-.003,.0006,-.0028,0.0*
1,1,.006,.0006,-.0028*
20,1,.006,.0006,-.0028,.0013,-.0022,0.0*
1,1,.006,.0013,-.0022*
20,1,.006,.0013,-.0022,.0018,-.0013,0.0*
1,1,.006,.0018,-.0013*
20,1,.006,.0018,-.0013,.002,-.0004,0.0*
1,1,.006,.002,-.0004*
20,1,.006,.002,-.0004,.002,.0007,0.0*
1,1,.006,.002,.0007*
20,1,.006,.002,.0007,.0018,.0016,0.0*
1,1,.006,.0018,.0016*
20,1,.006,.0018,.0016,.0013,.0024,0.0*
1,1,.006,.0013,.0024*
20,1,.006,.0013,.0024,.0007,.0028,0.0*
1,1,.006,.0007,.0028*
20,1,.006,.0007,.0028,0.0,.003,0.0*
1,1,.006,0.0,.003*
20,1,.006,0.0,.003,-.0008,.0028,0.0*
1,1,.006,-.0008,.0028*
20,1,.006,-.0008,.0028,-.0014,.0024,0.0*
1,1,.006,-.0014,.0024*
20,1,.006,-.0014,.0024,-.0018,.0018,0.0*
1,1,.006,-.0018,.0018*
20,1,.006,-.0018,.0018,-.002,.001,0.0*
1,1,.006,-.002,.001*
20,1,.006,-.002,.001,-.0018,.0003,0.0*
1,1,.006,-.0018,.0003*
20,1,.006,-.0018,.0003,-.0013,-.0004,0.0*
1,1,.006,-.0013,-.0004*
20,1,.006,-.0013,-.0004,-.0007,-.0008,0.0*
1,1,.006,-.0007,-.0008*
20,1,.006,-.0007,-.0008,0.0,-.0009,0.0*
1,1,.006,0.0,-.0009*
20,1,.006,0.0,-.0009,.0008,-.0007,0.0*
1,1,.006,.0008,-.0007*
20,1,.006,.0008,-.0007,.0014,-.0002,0.0*
1,1,.006,.0014,-.0002*
20,1,.006,.0014,-.0002,.002,.0007,0.0*
1,1,.006,.002,.0007*
%
%ADD30MACRO30*%
%AMMACRO72*
1,1,.006,.009,.00675*
20,1,.006,.009,.00675,.009,-.00675,0.0*
1,1,.006,.009,-.00675*
20,1,.006,.009,-.00675,-.009,-.00675,0.0*
1,1,.006,-.009,-.00675*
20,1,.006,-.009,-.00675,-.009,.00675,0.0*
1,1,.006,-.009,.00675*
20,1,.006,-.009,.00675,.009,.00675,0.0*
1,1,.006,.009,.00675*
1,1,.006,-.00338,-.00337*
20,1,.006,-.00338,-.00337,-.00338,.00338,0.0*
1,1,.006,-.00338,.00338*
20,1,.006,-.00338,.00338,-.00473,.00203,0.0*
1,1,.006,-.00473,.00203*
1,1,.006,-.00473,-.00337*
20,1,.006,-.00473,-.00337,-.00203,-.00337,0.0*
1,1,.006,-.00203,-.00337*
1,1,.006,.00338,.00338*
20,1,.006,.00338,.00338,.00248,.00316,0.0*
1,1,.006,.00248,.00316*
20,1,.006,.00248,.00316,.00181,.00259,0.0*
1,1,.006,.00181,.00259*
20,1,.006,.00181,.00259,.00136,.00192,0.0*
1,1,.006,.00136,.00192*
20,1,.006,.00136,.00192,.00102,.00102,0.0*
1,1,.006,.00102,.00102*
20,1,.006,.00102,.00102,.00091,0.0,0.0*
1,1,.006,.00091,0.0*
20,1,.006,.00091,0.0,.00102,-.00101,0.0*
1,1,.006,.00102,-.00101*
20,1,.006,.00102,-.00101,.00136,-.00191,0.0*
1,1,.006,.00136,-.00191*
20,1,.006,.00136,-.00191,.00181,-.00258,0.0*
1,1,.006,.00181,-.00258*
20,1,.006,.00181,-.00258,.00248,-.00315,0.0*
1,1,.006,.00248,-.00315*
20,1,.006,.00248,-.00315,.00338,-.00337,0.0*
1,1,.006,.00338,-.00337*
20,1,.006,.00338,-.00337,.00428,-.00315,0.0*
1,1,.006,.00428,-.00315*
20,1,.006,.00428,-.00315,.00496,-.00258,0.0*
1,1,.006,.00496,-.00258*
20,1,.006,.00496,-.00258,.00541,-.00191,0.0*
1,1,.006,.00541,-.00191*
20,1,.006,.00541,-.00191,.00575,-.00101,0.0*
1,1,.006,.00575,-.00101*
20,1,.006,.00575,-.00101,.00586,0.0,0.0*
1,1,.006,.00586,0.0*
20,1,.006,.00586,0.0,.00575,.00102,0.0*
1,1,.006,.00575,.00102*
20,1,.006,.00575,.00102,.00541,.00192,0.0*
1,1,.006,.00541,.00192*
20,1,.006,.00541,.00192,.00496,.00259,0.0*
1,1,.006,.00496,.00259*
20,1,.006,.00496,.00259,.00428,.00316,0.0*
1,1,.006,.00428,.00316*
20,1,.006,.00428,.00316,.00338,.00338,0.0*
1,1,.006,.00338,.00338*
%
%ADD72MACRO72*%
%AMMACRO35*
1,1,.006,-.0235,-.0245*
20,1,.006,-.0235,-.0245,-.0235,.0245,0.0*
1,1,.006,-.0235,.0245*
20,1,.006,-.0235,.0245,-.023143,.028581,0.0*
1,1,.006,-.023143,.028581*
20,1,.006,-.023143,.028581,-.022083,.032537,0.0*
1,1,.006,-.022083,.032537*
20,1,.006,-.022083,.032537,-.020352,.03625,0.0*
1,1,.006,-.020352,.03625*
20,1,.006,-.020352,.03625,-.018002,.039606,0.0*
1,1,.006,-.018002,.039606*
20,1,.006,-.018002,.039606,-.015106,.042502,0.0*
1,1,.006,-.015106,.042502*
20,1,.006,-.015106,.042502,-.01175,.044852,0.0*
1,1,.006,-.01175,.044852*
20,1,.006,-.01175,.044852,-.008037,.046583,0.0*
1,1,.006,-.008037,.046583*
20,1,.006,-.008037,.046583,-.004081,.047643,0.0*
1,1,.006,-.004081,.047643*
20,1,.006,-.004081,.047643,0.0,.048,0.0*
1,1,.006,0.0,.048*
20,1,.006,0.0,.048,.004081,.047643,0.0*
1,1,.006,.004081,.047643*
20,1,.006,.004081,.047643,.008037,.046583,0.0*
1,1,.006,.008037,.046583*
20,1,.006,.008037,.046583,.01175,.044852,0.0*
1,1,.006,.01175,.044852*
20,1,.006,.01175,.044852,.015106,.042502,0.0*
1,1,.006,.015106,.042502*
20,1,.006,.015106,.042502,.018002,.039606,0.0*
1,1,.006,.018002,.039606*
20,1,.006,.018002,.039606,.020352,.03625,0.0*
1,1,.006,.020352,.03625*
20,1,.006,.020352,.03625,.022083,.032537,0.0*
1,1,.006,.022083,.032537*
20,1,.006,.022083,.032537,.023143,.028581,0.0*
1,1,.006,.023143,.028581*
20,1,.006,.023143,.028581,.0235,.0245,0.0*
1,1,.006,.0235,.0245*
20,1,.006,.0235,.0245,.0235,-.0245,0.0*
1,1,.006,.0235,-.0245*
20,1,.006,.0235,-.0245,.023143,-.028581,0.0*
1,1,.006,.023143,-.028581*
20,1,.006,.023143,-.028581,.022083,-.032537,0.0*
1,1,.006,.022083,-.032537*
20,1,.006,.022083,-.032537,.020352,-.03625,0.0*
1,1,.006,.020352,-.03625*
20,1,.006,.020352,-.03625,.018002,-.039606,0.0*
1,1,.006,.018002,-.039606*
20,1,.006,.018002,-.039606,.015106,-.042502,0.0*
1,1,.006,.015106,-.042502*
20,1,.006,.015106,-.042502,.01175,-.044852,0.0*
1,1,.006,.01175,-.044852*
20,1,.006,.01175,-.044852,.008037,-.046583,0.0*
1,1,.006,.008037,-.046583*
20,1,.006,.008037,-.046583,.004081,-.047643,0.0*
1,1,.006,.004081,-.047643*
20,1,.006,.004081,-.047643,0.0,-.048,0.0*
1,1,.006,0.0,-.048*
20,1,.006,0.0,-.048,-.004081,-.047643,0.0*
1,1,.006,-.004081,-.047643*
20,1,.006,-.004081,-.047643,-.008037,-.046583,0.0*
1,1,.006,-.008037,-.046583*
20,1,.006,-.008037,-.046583,-.01175,-.044852,0.0*
1,1,.006,-.01175,-.044852*
20,1,.006,-.01175,-.044852,-.015106,-.042502,0.0*
1,1,.006,-.015106,-.042502*
20,1,.006,-.015106,-.042502,-.018002,-.039606,0.0*
1,1,.006,-.018002,-.039606*
20,1,.006,-.018002,-.039606,-.020352,-.03625,0.0*
1,1,.006,-.020352,-.03625*
20,1,.006,-.020352,-.03625,-.022083,-.032537,0.0*
1,1,.006,-.022083,-.032537*
20,1,.006,-.022083,-.032537,-.023143,-.028581,0.0*
1,1,.006,-.023143,-.028581*
20,1,.006,-.023143,-.028581,-.0235,-.0245,0.0*
1,1,.006,-.0235,-.0245*
1,1,.006,-.01175,-.01175*
20,1,.006,-.01175,-.01175,-.01488,-.01136,0.0*
1,1,.006,-.01488,-.01136*
20,1,.006,-.01488,-.01136,-.01762,-.00979,0.0*
1,1,.006,-.01762,-.00979*
20,1,.006,-.01762,-.00979,-.01998,-.00744,0.0*
1,1,.006,-.01998,-.00744*
20,1,.006,-.01998,-.00744,-.02154,-.0047,0.0*
1,1,.006,-.02154,-.0047*
20,1,.006,-.02154,-.0047,-.02233,-.00157,0.0*
1,1,.006,-.02233,-.00157*
20,1,.006,-.02233,-.00157,-.02233,.00157,0.0*
1,1,.006,-.02233,.00157*
20,1,.006,-.02233,.00157,-.02154,.0047,0.0*
1,1,.006,-.02154,.0047*
20,1,.006,-.02154,.0047,-.01998,.00744,0.0*
1,1,.006,-.01998,.00744*
20,1,.006,-.01998,.00744,-.01762,.00979,0.0*
1,1,.006,-.01762,.00979*
20,1,.006,-.01762,.00979,-.01488,.01136,0.0*
1,1,.006,-.01488,.01136*
20,1,.006,-.01488,.01136,-.01175,.01175,0.0*
1,1,.006,-.01175,.01175*
20,1,.006,-.01175,.01175,-.00862,.01136,0.0*
1,1,.006,-.00862,.01136*
20,1,.006,-.00862,.01136,-.00588,.00979,0.0*
1,1,.006,-.00588,.00979*
20,1,.006,-.00588,.00979,-.00352,.00744,0.0*
1,1,.006,-.00352,.00744*
20,1,.006,-.00352,.00744,-.00196,.0047,0.0*
1,1,.006,-.00196,.0047*
20,1,.006,-.00196,.0047,-.00117,.00157,0.0*
1,1,.006,-.00117,.00157*
20,1,.006,-.00117,.00157,-.00117,-.00157,0.0*
1,1,.006,-.00117,-.00157*
20,1,.006,-.00117,-.00157,-.00196,-.0047,0.0*
1,1,.006,-.00196,-.0047*
20,1,.006,-.00196,-.0047,-.00352,-.00744,0.0*
1,1,.006,-.00352,-.00744*
20,1,.006,-.00352,-.00744,-.00588,-.00979,0.0*
1,1,.006,-.00588,-.00979*
20,1,.006,-.00588,-.00979,-.00862,-.01136,0.0*
1,1,.006,-.00862,-.01136*
20,1,.006,-.00862,-.01136,-.01175,-.01175,0.0*
1,1,.006,-.01175,-.01175*
1,1,.006,.00432,-.01175*
20,1,.006,.00432,-.01175,.00432,.01175,0.0*
1,1,.006,.00432,.01175*
20,1,.006,.00432,.01175,.0192,.01175,0.0*
1,1,.006,.0192,.01175*
1,1,.006,.01372,.00039*
20,1,.006,.01372,.00039,.00432,.00039,0.0*
1,1,.006,.00432,.00039*
%
%ADD35MACRO35*%
%AMMACRO49*
1,1,.006,0.0,.0075*
20,1,.006,0.0,.0075,.0075,-.0075,0.0*
1,1,.006,.0075,-.0075*
20,1,.006,.0075,-.0075,-.0075,-.0075,0.0*
1,1,.006,-.0075,-.0075*
20,1,.006,-.0075,-.0075,0.0,.0075,0.0*
1,1,.006,0.0,.0075*
1,1,.006,-.00025,-.00375*
20,1,.006,-.00025,-.00375,0.0,-.00213,0.0*
1,1,.006,0.0,-.00213*
20,1,.006,0.0,-.00213,.00038,-.00075,0.0*
1,1,.006,.00038,-.00075*
20,1,.006,.00038,-.00075,.00087,.0005,0.0*
1,1,.006,.00087,.0005*
20,1,.006,.00087,.0005,.0015,.00187,0.0*
1,1,.006,.0015,.00187*
20,1,.006,.0015,.00187,.0025,.00375,0.0*
1,1,.006,.0025,.00375*
20,1,.006,.0025,.00375,-.0025,.00375,0.0*
1,1,.006,-.0025,.00375*
%
%ADD49MACRO49*%
%AMMACRO14*
1,1,.006,-.001965,.005905*
20,1,.006,-.001965,.005905,.001965,.005905,0.0*
1,1,.006,.001965,.005905*
20,1,.006,.001965,.005905,.00299,.005815,0.0*
1,1,.006,.00299,.005815*
20,1,.006,.00299,.005815,.003985,.005549,0.0*
1,1,.006,.003985,.005549*
20,1,.006,.003985,.005549,.004917,.005114,0.0*
1,1,.006,.004917,.005114*
20,1,.006,.004917,.005114,.005761,.004523,0.0*
1,1,.006,.005761,.004523*
20,1,.006,.005761,.004523,.006488,.003796,0.0*
1,1,.006,.006488,.003796*
20,1,.006,.006488,.003796,.007079,.002953,0.0*
1,1,.006,.007079,.002953*
20,1,.006,.007079,.002953,.007514,.00202,0.0*
1,1,.006,.007514,.00202*
20,1,.006,.007514,.00202,.00778,.001025,0.0*
1,1,.006,.00778,.001025*
20,1,.006,.00778,.001025,.00787,0.0,0.0*
1,1,.006,.00787,0.0*
20,1,.006,.00787,0.0,.00778,-.001025,0.0*
1,1,.006,.00778,-.001025*
20,1,.006,.00778,-.001025,.007514,-.00202,0.0*
1,1,.006,.007514,-.00202*
20,1,.006,.007514,-.00202,.007079,-.002952,0.0*
1,1,.006,.007079,-.002952*
20,1,.006,.007079,-.002952,.006488,-.003796,0.0*
1,1,.006,.006488,-.003796*
20,1,.006,.006488,-.003796,.005761,-.004523,0.0*
1,1,.006,.005761,-.004523*
20,1,.006,.005761,-.004523,.004918,-.005114,0.0*
1,1,.006,.004918,-.005114*
20,1,.006,.004918,-.005114,.003985,-.005549,0.0*
1,1,.006,.003985,-.005549*
20,1,.006,.003985,-.005549,.00299,-.005815,0.0*
1,1,.006,.00299,-.005815*
20,1,.006,.00299,-.005815,.001965,-.005905,0.0*
1,1,.006,.001965,-.005905*
20,1,.006,.001965,-.005905,-.001965,-.005905,0.0*
1,1,.006,-.001965,-.005905*
20,1,.006,-.001965,-.005905,-.00299,-.005815,0.0*
1,1,.006,-.00299,-.005815*
20,1,.006,-.00299,-.005815,-.003985,-.005549,0.0*
1,1,.006,-.003985,-.005549*
20,1,.006,-.003985,-.005549,-.004917,-.005114,0.0*
1,1,.006,-.004917,-.005114*
20,1,.006,-.004917,-.005114,-.005761,-.004523,0.0*
1,1,.006,-.005761,-.004523*
20,1,.006,-.005761,-.004523,-.006488,-.003796,0.0*
1,1,.006,-.006488,-.003796*
20,1,.006,-.006488,-.003796,-.007079,-.002953,0.0*
1,1,.006,-.007079,-.002953*
20,1,.006,-.007079,-.002953,-.007514,-.00202,0.0*
1,1,.006,-.007514,-.00202*
20,1,.006,-.007514,-.00202,-.00778,-.001025,0.0*
1,1,.006,-.00778,-.001025*
20,1,.006,-.00778,-.001025,-.00787,0.0,0.0*
1,1,.006,-.00787,0.0*
20,1,.006,-.00787,0.0,-.00778,.001025,0.0*
1,1,.006,-.00778,.001025*
20,1,.006,-.00778,.001025,-.007514,.00202,0.0*
1,1,.006,-.007514,.00202*
20,1,.006,-.007514,.00202,-.007079,.002952,0.0*
1,1,.006,-.007079,.002952*
20,1,.006,-.007079,.002952,-.006488,.003796,0.0*
1,1,.006,-.006488,.003796*
20,1,.006,-.006488,.003796,-.005761,.004523,0.0*
1,1,.006,-.005761,.004523*
20,1,.006,-.005761,.004523,-.004918,.005114,0.0*
1,1,.006,-.004918,.005114*
20,1,.006,-.004918,.005114,-.003985,.005549,0.0*
1,1,.006,-.003985,.005549*
20,1,.006,-.003985,.005549,-.00299,.005815,0.0*
1,1,.006,-.00299,.005815*
20,1,.006,-.00299,.005815,-.001965,.005905,0.0*
1,1,.006,-.001965,.005905*
1,1,.006,0.0,-.00295*
20,1,.006,0.0,-.00295,.00069,-.00285,0.0*
1,1,.006,.00069,-.00285*
20,1,.006,.00069,-.00285,.00147,-.00256,0.0*
1,1,.006,.00147,-.00256*
20,1,.006,.00147,-.00256,.00197,-.00207,0.0*
1,1,.006,.00197,-.00207*
20,1,.006,.00197,-.00207,.00216,-.00138,0.0*
1,1,.006,.00216,-.00138*
20,1,.006,.00216,-.00138,.00197,-.00069,0.0*
1,1,.006,.00197,-.00069*
20,1,.006,.00197,-.00069,.00138,-.0001,0.0*
1,1,.006,.00138,-.0001*
20,1,.006,.00138,-.0001,.00049,.0002,0.0*
1,1,.006,.00049,.0002*
20,1,.006,.00049,.0002,-.00049,.0002,0.0*
1,1,.006,-.00049,.0002*
20,1,.006,-.00049,.0002,-.00108,.00039,0.0*
1,1,.006,-.00108,.00039*
20,1,.006,-.00108,.00039,-.00157,.00088,0.0*
1,1,.006,-.00157,.00088*
20,1,.006,-.00157,.00088,-.00177,.00157,0.0*
1,1,.006,-.00177,.00157*
20,1,.006,-.00177,.00157,-.00147,.00226,0.0*
1,1,.006,-.00147,.00226*
20,1,.006,-.00147,.00226,-.00079,.00275,0.0*
1,1,.006,-.00079,.00275*
20,1,.006,-.00079,.00275,0.0,.00295,0.0*
1,1,.006,0.0,.00295*
20,1,.006,0.0,.00295,.00079,.00275,0.0*
1,1,.006,.00079,.00275*
20,1,.006,.00079,.00275,.00147,.00226,0.0*
1,1,.006,.00147,.00226*
20,1,.006,.00147,.00226,.00177,.00157,0.0*
1,1,.006,.00177,.00157*
20,1,.006,.00177,.00157,.00157,.00088,0.0*
1,1,.006,.00157,.00088*
20,1,.006,.00157,.00088,.00108,.00039,0.0*
1,1,.006,.00108,.00039*
20,1,.006,.00108,.00039,.00049,.0002,0.0*
1,1,.006,.00049,.0002*
20,1,.006,.00049,.0002,-.00049,.0002,0.0*
1,1,.006,-.00049,.0002*
20,1,.006,-.00049,.0002,-.00138,-.0001,0.0*
1,1,.006,-.00138,-.0001*
20,1,.006,-.00138,-.0001,-.00197,-.00069,0.0*
1,1,.006,-.00197,-.00069*
20,1,.006,-.00197,-.00069,-.00216,-.00138,0.0*
1,1,.006,-.00216,-.00138*
20,1,.006,-.00216,-.00138,-.00197,-.00207,0.0*
1,1,.006,-.00197,-.00207*
20,1,.006,-.00197,-.00207,-.00147,-.00256,0.0*
1,1,.006,-.00147,-.00256*
20,1,.006,-.00147,-.00256,-.00069,-.00285,0.0*
1,1,.006,-.00069,-.00285*
20,1,.006,-.00069,-.00285,0.0,-.00295,0.0*
1,1,.006,0.0,-.00295*
%
%ADD14MACRO14*%
%ADD74C,.02*%
%ADD75C,.006*%
G75*
%LPD*%
G75*
G54D10*
X-17936Y-49379D03*
Y-53779D03*
Y-44979D03*
Y-40579D03*
X-18079Y-35764D03*
Y-58764D03*
X-14186Y196989D03*
Y199989D03*
X-14839Y445588D03*
X-14753Y448601D03*
X-17179Y643156D03*
X-17194Y638753D03*
X-17179Y647556D03*
Y660756D03*
Y651956D03*
Y656356D03*
X-13636Y-40479D03*
Y-44879D03*
Y-53679D03*
X-9079Y-50164D03*
X-4679D03*
X-279D03*
X-9079Y-54264D03*
X-4679D03*
X-279D03*
X22964Y-40379D03*
Y-44779D03*
Y-53579D03*
Y-49179D03*
X18964Y-53579D03*
Y-49179D03*
X13964Y-53579D03*
Y-49179D03*
X8964Y-40379D03*
Y-44779D03*
Y-53579D03*
Y-49179D03*
X3964Y-40379D03*
Y-44779D03*
Y-53579D03*
Y-49179D03*
X25921Y-35764D03*
X30321D03*
X43521D03*
X39121D03*
X34721D03*
X8321D03*
X12721D03*
X21521D03*
X17121D03*
X-13679D03*
X-9279D03*
X3921D03*
X-4879D03*
X-479D03*
X17121Y-58764D03*
X21521D03*
X12721D03*
X8321D03*
X34721D03*
X39121D03*
X43521D03*
X30321D03*
X25921D03*
X-479D03*
X-13679D03*
X-4879D03*
X3921D03*
X-13636Y-49279D03*
X-9279Y-58764D03*
X875Y211336D03*
X6074Y211293D03*
X3474Y211263D03*
X875Y208352D03*
X36200Y208600D03*
X33200D03*
X20700D03*
X17700Y211600D03*
X20700D03*
X17700Y208600D03*
X23700Y211600D03*
Y208600D03*
X33200Y211600D03*
X30200D03*
Y208600D03*
X36200Y211600D03*
X6074Y208321D03*
X3474Y208263D03*
X5500Y218500D03*
X-5300Y200191D03*
X-7900D03*
X-2700Y200202D03*
X-11586Y196989D03*
Y199989D03*
X-2600Y232300D03*
X-5246Y232351D03*
X-7846D03*
X20500Y221000D03*
Y224000D03*
X17500Y221000D03*
Y224000D03*
X23500D03*
Y221000D03*
X33300Y224000D03*
Y221000D03*
X30300D03*
Y224000D03*
X36300D03*
Y221000D03*
X-14129Y235221D03*
X-11484Y235215D03*
Y232215D03*
X-14084D03*
X2678Y221018D03*
X5277Y221110D03*
X5173Y224042D03*
X2574Y223963D03*
X-26Y223982D03*
X19800Y257900D03*
X28868Y457576D03*
Y454576D03*
X28988Y460876D03*
X23718Y460866D03*
X26318D03*
X21118D03*
X20998Y457566D03*
Y454566D03*
X23598D03*
X26198D03*
Y457566D03*
X23598D03*
X8343Y446875D03*
X1108Y455879D03*
X5743Y446875D03*
Y444275D03*
X-261Y450873D03*
X-11652Y445530D03*
Y448530D03*
X-261Y453473D03*
X2339Y448273D03*
Y450873D03*
Y453473D03*
X-261Y445673D03*
X2339D03*
X-261Y448273D03*
X22421Y647556D03*
X26821D03*
X31221D03*
X18021D03*
Y643156D03*
X31221D03*
X26821D03*
X22421D03*
X18006Y638753D03*
X9221Y647556D03*
X13621D03*
Y643156D03*
X9221D03*
X4821D03*
Y647556D03*
X22406Y638753D03*
X26806D03*
X31206D03*
X-12794D03*
X-12779Y647556D03*
Y643156D03*
X40006Y638753D03*
X44406D03*
X35606D03*
X35621Y647556D03*
Y643156D03*
X-9599Y610630D03*
X-3301Y619643D03*
Y601615D03*
X4549Y620682D03*
X4548Y600577D03*
X13801Y624130D03*
Y597130D03*
X23360Y620172D03*
X23352Y601079D03*
X27301Y610630D03*
X18021Y660756D03*
X35621Y656356D03*
X26821Y660756D03*
X18021Y651956D03*
X31221D03*
X22421Y660756D03*
X26821Y651956D03*
X22421D03*
X4821D03*
X13621D03*
X9221D03*
X-8379Y660756D03*
X4821Y656356D03*
X9221D03*
X13621D03*
X-3979D03*
X421D03*
X13621Y660756D03*
X-3979D03*
X421D03*
X4821D03*
X-12779Y651956D03*
X22421Y656356D03*
X26821D03*
X31221D03*
X18021D03*
X-8379D03*
X-12779D03*
X31221Y660756D03*
X35621Y651956D03*
Y660756D03*
X44421D03*
X40021D03*
X-12779D03*
X9221D03*
X107921Y-58764D03*
X102921D03*
X97921D03*
X92921D03*
X87921D03*
X82921D03*
X77921D03*
X72921D03*
X67921D03*
X62921D03*
X57921D03*
X52921D03*
X47921Y-35764D03*
Y-58764D03*
X107921Y-35764D03*
X102921D03*
X97921D03*
X92921D03*
X87921D03*
X82921D03*
X77921D03*
X72921D03*
X67921D03*
X62921D03*
X57921D03*
X52921D03*
X91536Y78481D03*
X95041Y78451D03*
X98633Y78481D03*
X96249Y204722D03*
X64700Y210100D03*
Y212800D03*
X64778Y218062D03*
X58000Y206500D03*
X50500Y205696D03*
X56900Y197800D03*
X93870Y199131D03*
X97730Y188584D03*
X108174Y164127D03*
X58200Y230400D03*
Y233400D03*
X55600Y230400D03*
X53000Y230300D03*
Y233300D03*
X55600Y233400D03*
X58200Y227400D03*
X53000Y227300D03*
X55600Y227400D03*
X58200Y239400D03*
X99000Y230450D03*
Y227450D03*
Y233450D03*
X93800Y236450D03*
X96400D03*
Y230450D03*
Y227450D03*
X93800D03*
Y230450D03*
X96400Y233450D03*
X93800D03*
X99000Y236450D03*
X91200Y227450D03*
Y230450D03*
Y236450D03*
Y233450D03*
X88600D03*
Y236450D03*
Y230450D03*
Y227450D03*
X53000Y239300D03*
X55600Y239400D03*
X58200Y236400D03*
X55600D03*
X53000Y236300D03*
X71500Y263300D03*
X68800D03*
X53004Y244632D03*
X55275Y245900D03*
X57875D03*
X57457Y248537D03*
Y251237D03*
X88200Y250400D03*
Y247400D03*
Y244400D03*
Y253400D03*
Y256300D03*
Y258900D03*
X57444Y257456D03*
X57600Y262800D03*
X57500Y260200D03*
X62800Y265500D03*
X71500Y266000D03*
X65500Y265500D03*
X68800Y266000D03*
X60000Y265500D03*
X90800Y244400D03*
Y250400D03*
Y247400D03*
X98600Y250400D03*
Y247400D03*
Y244400D03*
X93400Y250400D03*
Y247400D03*
Y244400D03*
X96000D03*
Y250400D03*
Y247400D03*
X90800Y253400D03*
Y256300D03*
Y258900D03*
X93400Y253400D03*
X96000D03*
X98600D03*
X96000Y258900D03*
X93400D03*
Y256300D03*
X96000D03*
X98600D03*
Y258900D03*
X76540Y397355D03*
X81900Y398300D03*
X79140Y397355D03*
X103700Y397200D03*
X106400D03*
X101000D03*
X109100D03*
Y399900D03*
X101000D03*
X106400D03*
X103700D03*
X98149Y399769D03*
X102456Y393756D03*
X76052Y420935D03*
X78000Y423100D03*
X80100Y425000D03*
X81500Y427400D03*
X79700Y409700D03*
X77400Y407800D03*
X81500Y412100D03*
X84913Y434471D03*
X87013Y436371D03*
X104517Y406279D03*
X105761Y409208D03*
X108010Y411479D03*
X107571Y406291D03*
X93040Y496810D03*
X92990Y494210D03*
X93040Y499410D03*
X98240Y496810D03*
X95640D03*
X98240Y499410D03*
X95640D03*
X87790Y494210D03*
X90390D03*
X90440Y496810D03*
X87840D03*
X90390Y491610D03*
X87790D03*
X90440Y499410D03*
X87840D03*
X95777Y494213D03*
X48806Y638753D03*
X75206D03*
X106006D03*
X70806D03*
X53206D03*
X66406D03*
X92806D03*
X97206D03*
X101606D03*
X57606D03*
X62006D03*
X79606D03*
X84006D03*
X88406D03*
X53221Y660756D03*
X101621D03*
X97221D03*
X92821D03*
X106021D03*
X48821D03*
X70821D03*
X66421D03*
X62021D03*
X57621D03*
X75221D03*
X88421D03*
X84021D03*
X79621D03*
X167921Y-58764D03*
X162921D03*
X157921D03*
X152921D03*
X147921D03*
X142921D03*
X137921D03*
X132921D03*
X127921D03*
X122921D03*
X117921D03*
X112921D03*
X162921Y-35764D03*
X157921D03*
X152921D03*
X147921D03*
X142921D03*
X137921D03*
X132921D03*
X127921D03*
X122921D03*
X117921D03*
X112921D03*
X167921D03*
X166000Y212900D03*
X168600D03*
X164300Y207870D03*
X160800Y212900D03*
X163400D03*
X157800Y207300D03*
X161216Y209533D03*
Y206933D03*
X154500Y205500D03*
X150600Y212900D03*
X151000Y205500D03*
X140889Y211972D03*
X137615Y212039D03*
X143900Y204600D03*
X147500Y205500D03*
X137300Y204500D03*
X140200Y204400D03*
X153200Y212900D03*
X122044Y162340D03*
X123624Y164600D03*
X139815Y268974D03*
X137900Y272800D03*
X139800Y237000D03*
X165825Y239543D03*
X168425Y236943D03*
Y239543D03*
X165825Y236943D03*
X163225D03*
X152825D03*
X145025D03*
X147625D03*
X150225D03*
X142425D03*
X122231Y234716D03*
X125564Y237816D03*
X122632D03*
X163225Y239543D03*
X158025Y236943D03*
X155425D03*
X160625D03*
X142371Y244384D03*
X122231Y266716D03*
X122531Y269816D03*
X125463D03*
X142466Y268982D03*
X142700Y276200D03*
X136729Y276386D03*
X139683Y276174D03*
X163225Y242143D03*
X168425Y244743D03*
X165825D03*
X163225D03*
X168425Y242143D03*
X165825D03*
X150700Y276800D03*
X169150Y259470D03*
Y255470D03*
X157633Y268727D03*
X162833D03*
X160233D03*
X165433D03*
X168033Y271327D03*
X162833Y276527D03*
Y273927D03*
Y271327D03*
X165433Y276527D03*
Y273927D03*
Y271327D03*
X159983Y276507D03*
X168033Y276527D03*
Y273927D03*
Y268727D03*
X153300Y276800D03*
X139866Y333016D03*
X160233Y306257D03*
Y308857D03*
Y303657D03*
X157518Y335391D03*
X157745Y332800D03*
X139900Y302400D03*
X142433Y301057D03*
X147633D03*
X150233D03*
X145033D03*
X125500Y333500D03*
X122231Y330716D03*
X122731Y333916D03*
X145200Y341300D03*
X148200D03*
X142465Y332940D03*
X152833Y301057D03*
X163233Y306257D03*
Y308857D03*
X168433Y306257D03*
Y308857D03*
Y301057D03*
X165833D03*
X163233D03*
X160633D03*
X158033D03*
X155433D03*
X169150Y287600D03*
Y291600D03*
X165833Y306257D03*
X163233Y303657D03*
X168433D03*
X165833D03*
Y308857D03*
X151000Y341300D03*
X169150Y323600D03*
Y319600D03*
X160501Y332965D03*
X160274Y335556D03*
X165701Y338165D03*
Y335565D03*
X163101Y332965D03*
X168301D03*
X165701D03*
X163101Y335565D03*
X168301Y340765D03*
Y338165D03*
Y335565D03*
X163101Y338165D03*
Y340765D03*
X165701D03*
X154200Y341100D03*
X125663Y301716D03*
X122231Y298716D03*
X122731Y301716D03*
X139767Y364883D03*
X147833Y364457D03*
X125600Y364900D03*
X122600Y365500D03*
X122331Y362716D03*
X142421Y364908D03*
X145033Y364457D03*
X142863Y402829D03*
X140219Y402894D03*
X137619Y402900D03*
X134992D03*
X142818Y400163D03*
X143073Y397194D03*
X140475Y397310D03*
X140218Y400163D03*
X137529Y400296D03*
X134929D03*
X114084Y399937D03*
X122840Y400827D03*
X111561Y398819D03*
X122000Y397600D03*
X125300Y397700D03*
X122231Y394716D03*
X150633Y364457D03*
X167433Y369657D03*
X169150Y355600D03*
Y351600D03*
X167700Y363900D03*
X161833Y364457D03*
X164633D03*
X159033D03*
X156233D03*
X153433D03*
X164633Y369657D03*
X161833D03*
X161933Y372357D03*
X164733D03*
X167533D03*
X166340Y374785D03*
X167670Y383993D03*
Y387993D03*
X130613Y429647D03*
X123648Y425041D03*
X125328Y427269D03*
X127932Y428571D03*
X110519Y410307D03*
X110199Y413852D03*
X110406Y638753D03*
X145606D03*
X141206D03*
X136806D03*
X132406D03*
X158806D03*
X119206D03*
X123606D03*
X114806D03*
X128006D03*
X163206D03*
X154406D03*
X167606D03*
X150006D03*
X132421Y660756D03*
X145621D03*
X141221D03*
X136821D03*
X123621D03*
X114821D03*
X128021D03*
X110421D03*
X119221D03*
X150021D03*
X167621D03*
X163221D03*
X158821D03*
X154421D03*
X182921Y-58764D03*
X177921D03*
X172921D03*
X227921Y-35764D03*
X222921D03*
X217921D03*
X212921D03*
X207921D03*
X202921D03*
X197921D03*
X192921D03*
X187921D03*
X182921D03*
X177921D03*
X227921Y-58764D03*
X222921D03*
X217921D03*
X212921D03*
X207921D03*
X202921D03*
X197921D03*
X192921D03*
X187921D03*
X172921Y-35764D03*
X176300Y211900D03*
X182300Y216108D03*
X179300D03*
Y213208D03*
X176300Y217308D03*
Y214500D03*
X173300Y217700D03*
Y214800D03*
Y211900D03*
X176400Y234300D03*
X176508Y231609D03*
X179400Y234300D03*
X182400D03*
X176400Y239900D03*
X182400D03*
X179400D03*
X173400D03*
Y231400D03*
Y234300D03*
Y237000D03*
X176400D03*
X182400D03*
X179400D03*
X188200Y236800D03*
X188300Y234000D03*
X185250Y239850D03*
X204200Y249500D03*
X201100Y246500D03*
X198200Y249500D03*
Y246500D03*
X201200Y249500D03*
X203900Y246500D03*
X207200Y249500D03*
X185768Y270065D03*
X173835Y277804D03*
X198082Y277995D03*
X203847Y274933D03*
X203947Y277933D03*
X188510Y272666D03*
X176835Y277804D03*
X182935Y278204D03*
Y275604D03*
X191400Y278400D03*
X188475Y270065D03*
X185735Y275604D03*
X188600Y278300D03*
X188535Y275604D03*
X185735Y278204D03*
X195300Y229250D03*
X188100Y239800D03*
X185250Y234250D03*
Y236950D03*
X176835Y275204D03*
X185754Y272689D03*
X179835Y277804D03*
Y275204D03*
X195100Y252000D03*
X201200Y252500D03*
X198200D03*
X204200D03*
X207200D03*
X200947Y277933D03*
X200847Y274933D03*
X200947Y280933D03*
X173835Y275204D03*
X230800Y265200D03*
X224390Y258920D03*
X219500Y254500D03*
X190800Y295500D03*
X196956Y295583D03*
X193800Y295500D03*
X190665Y306877D03*
X198119Y339710D03*
X191792Y327743D03*
X197792Y327643D03*
X194792D03*
X184800Y295500D03*
X187956Y295583D03*
X181800Y295500D03*
X201177Y330728D03*
Y333728D03*
Y336728D03*
X201163Y339476D03*
Y342476D03*
X204177Y336728D03*
X204060Y342527D03*
X204163Y339476D03*
X188654Y330973D03*
Y327973D03*
X197684Y307227D03*
X200251Y306548D03*
X188630Y333923D03*
X190570Y309539D03*
X185630Y333923D03*
X172800Y295500D03*
Y298400D03*
X198182Y280995D03*
X178956Y295583D03*
X175800Y295500D03*
X187900Y306900D03*
X191300Y339800D03*
X172800Y304000D03*
X175800D03*
X178800D03*
X187800D03*
X181800D03*
X184800D03*
X172800Y301100D03*
X175800D03*
X178800D03*
X181800D03*
X187800D03*
X184800D03*
Y298400D03*
X181800D03*
X175800D03*
X178800D03*
X187800D03*
X185300Y336900D03*
X173300Y337000D03*
Y339900D03*
X188300D03*
Y336900D03*
X179300Y337000D03*
X176300Y339900D03*
X179300D03*
X182300D03*
Y337000D03*
X198223Y342430D03*
X176300Y337000D03*
X185300Y339900D03*
X224000Y330900D03*
X229100Y325900D03*
X219000Y335900D03*
X214000Y340900D03*
X197730Y309959D03*
X204060Y345527D03*
X191300Y343248D03*
X173300Y343448D03*
X188300Y343348D03*
X201045Y345449D03*
X198233Y345402D03*
X195233D03*
X176300Y343448D03*
X201045Y348449D03*
X198233Y348402D03*
Y351402D03*
X195233D03*
X173424Y359621D03*
X188424D03*
X188400Y369787D03*
X176400D03*
X179400Y366787D03*
Y369787D03*
X176400Y366787D03*
X173400Y369787D03*
Y366787D03*
X199900Y370400D03*
X182400Y366787D03*
Y369787D03*
X185400Y366787D03*
Y369787D03*
X188400Y366787D03*
X182424Y359621D03*
X185424D03*
X176424D03*
X179424D03*
X182300Y343448D03*
X173471Y363281D03*
X188471D03*
X182471D03*
X185471D03*
X176471D03*
X179471D03*
X174750Y386308D03*
Y383308D03*
X171158Y382768D03*
Y385768D03*
Y388768D03*
X187100Y394000D03*
X190100Y393000D03*
X197411Y374812D03*
X199754Y376090D03*
X174750Y389308D03*
X199900Y373400D03*
X179300Y343448D03*
X185300Y343348D03*
X211606Y638753D03*
X224806D03*
X220406D03*
X216006D03*
X189606D03*
X198406D03*
X202806D03*
X207206D03*
X176406D03*
X172006D03*
X185206D03*
X180806D03*
X194006D03*
X226500Y649900D03*
X229206Y638753D03*
X224821Y660756D03*
X220421D03*
X198421D03*
X211621D03*
X189621D03*
X202821D03*
X207221D03*
X194021D03*
X185221D03*
X172021D03*
X176421D03*
X180821D03*
X229221D03*
X216021D03*
X292921Y-35764D03*
X287921D03*
X282921D03*
X277921D03*
X272921D03*
X267921D03*
X262921D03*
X257921D03*
X252921D03*
X247921D03*
X242921D03*
X237921D03*
X232921D03*
X292921Y-58764D03*
X287921D03*
X282921D03*
X277921D03*
X272921D03*
X267921D03*
X262921D03*
X257921D03*
X252921D03*
X247921D03*
X242921D03*
X237921D03*
X232921D03*
X234501Y270392D03*
X234000Y320900D03*
X261125Y646784D03*
X251213D03*
X290806Y638753D03*
X268806D03*
X273206D03*
X277606D03*
X282006D03*
X260006D03*
X264406D03*
X255606D03*
X251206D03*
X286406D03*
X242406D03*
X246806D03*
X233606D03*
X238006D03*
X261125Y652784D03*
X251213D03*
X286421Y660756D03*
X268821D03*
X282021D03*
X273221D03*
X277621D03*
X264421D03*
X251221D03*
X255621D03*
X260021D03*
X246821D03*
X242421D03*
X238021D03*
X233621D03*
X290821D03*
X352921Y-58764D03*
Y-35764D03*
X347921Y-58764D03*
Y-35764D03*
X342921Y-58764D03*
Y-35764D03*
X337921Y-58764D03*
Y-35764D03*
X332921Y-58764D03*
Y-35764D03*
X327921Y-58764D03*
Y-35764D03*
X322921Y-58764D03*
Y-35764D03*
X317921Y-58764D03*
Y-35764D03*
X312921Y-58764D03*
X307921D03*
Y-35764D03*
X302921Y-58764D03*
Y-35764D03*
X297921D03*
Y-58764D03*
X312921Y-35764D03*
X330406Y638753D03*
X348006D03*
X326006D03*
X312806D03*
X317206D03*
X321606D03*
X352406D03*
X295206D03*
X299606D03*
X308406D03*
X304006D03*
X334806D03*
X339206D03*
X343606D03*
X312821Y660756D03*
X317221D03*
X308421D03*
X304021D03*
X352421D03*
X295221D03*
X326021D03*
X321621D03*
X339221D03*
X299621D03*
X334821D03*
X330421D03*
X343621D03*
X348021D03*
X392921Y-35764D03*
X387921Y-58764D03*
Y-35764D03*
X382921Y-58764D03*
Y-35764D03*
X377921Y-58764D03*
Y-35764D03*
X372921Y-58764D03*
Y-35764D03*
X367921Y-58764D03*
Y-35764D03*
X362921Y-58764D03*
Y-35764D03*
X357921Y-58764D03*
Y-35764D03*
X392921Y-58764D03*
X402921Y-35764D03*
X397921Y-58764D03*
Y-35764D03*
X412921Y-58764D03*
Y-35764D03*
X407921Y-58764D03*
Y-35764D03*
X402921Y-58764D03*
X404594Y264899D03*
X407594D03*
X411188D03*
X414188D03*
X417190D03*
X380885Y273876D03*
Y270876D03*
X382494Y278904D03*
X371094D03*
X378294D03*
X375294D03*
X368094D03*
X389694D03*
X392694D03*
X385945Y278480D03*
X407094Y278910D03*
X414207D03*
X411288D03*
X404094D03*
X400842Y278914D03*
X368094Y295904D03*
X371094D03*
X385494D03*
X375294D03*
X378294D03*
X382494D03*
X389694D03*
X392694D03*
X365693Y311893D03*
X385494Y309904D03*
X367914Y309910D03*
X371237Y309846D03*
X389502Y309910D03*
X389528Y292910D03*
X392694Y292904D03*
X368116Y293087D03*
X371094Y292904D03*
X373736Y293068D03*
X382625Y293207D03*
X378294Y292904D03*
X385494D03*
X392694Y309904D03*
X374994Y309910D03*
X382497D03*
X378577Y309795D03*
X366822Y324459D03*
X377894Y326777D03*
X378785Y329580D03*
X375223Y326798D03*
X369748Y326902D03*
X367121Y327057D03*
X372391Y326746D03*
X375848Y329512D03*
X391144Y324173D03*
X388394D03*
X385494D03*
X407094Y292904D03*
X396897Y293058D03*
X399894Y292904D03*
X404266Y293030D03*
X407094Y309904D03*
X396709Y309910D03*
X399894Y309904D03*
X404117Y309910D03*
X411294Y295904D03*
X414294D03*
X407094D03*
X404094D03*
X399894D03*
X396894D03*
Y324173D03*
X408894D03*
X411894D03*
X405894D03*
X414894D03*
X393894D03*
X402894D03*
X399894D03*
X389473Y646508D03*
X379561D03*
X383206Y638753D03*
X387606D03*
X392006D03*
X396406D03*
X400806D03*
X405206D03*
X409606D03*
X414006D03*
X370006D03*
X365606D03*
X374406D03*
X378806D03*
X356806D03*
X361206D03*
X379561Y652508D03*
X389473D03*
X374421Y660756D03*
X387621D03*
X383221D03*
X400821D03*
X396421D03*
X392021D03*
X405221D03*
X409621D03*
X414021D03*
X361221D03*
X365621D03*
X356821D03*
X370021D03*
X378821D03*
X477921Y-58764D03*
Y-35764D03*
X472921Y-58764D03*
Y-35764D03*
X467921Y-58764D03*
Y-35764D03*
X462921Y-58764D03*
Y-35764D03*
X457921Y-58764D03*
Y-35764D03*
X452921Y-58764D03*
Y-35764D03*
X447921Y-58764D03*
Y-35764D03*
X442921Y-58764D03*
Y-35764D03*
X437921Y-58764D03*
Y-35764D03*
X432921Y-58764D03*
X422921Y-35764D03*
X417921Y-58764D03*
Y-35764D03*
X432921D03*
X427921Y-58764D03*
Y-35764D03*
X422921Y-58764D03*
X425911Y264710D03*
X420188Y264899D03*
X423092Y264697D03*
X436519Y262232D03*
X436329Y264826D03*
X432643Y264508D03*
X418523Y278910D03*
X428694D03*
X432894D03*
X425694D03*
X435894Y278938D03*
X443094Y278904D03*
X440094D03*
X421523Y278944D03*
X451675Y291739D03*
X449148Y292841D03*
X446209Y292842D03*
X451816Y295904D03*
X435894D03*
X418494D03*
X443094D03*
X440094D03*
X446383Y295841D03*
X428694Y295904D03*
X432894D03*
X425694D03*
X421494D03*
X418494Y324173D03*
X451267Y324476D03*
X448694Y323949D03*
X421494Y324173D03*
X446094Y323904D03*
X425694Y324173D03*
X428694D03*
X432894D03*
X435894D03*
X455226Y291686D03*
X454922Y295841D03*
X438681Y646514D03*
X448593D03*
X466806Y638753D03*
X462406D03*
X475606D03*
X471206D03*
X418406D03*
X422806D03*
X427206D03*
X440406D03*
X436006D03*
X431606D03*
X449206D03*
X458006D03*
X453606D03*
X444806D03*
X448593Y652514D03*
X458021Y660756D03*
X449221D03*
X462421D03*
X466821D03*
X471221D03*
X418421D03*
X438681Y652514D03*
X475621Y660756D03*
X453621D03*
X422821D03*
X427221D03*
X440421D03*
X431621D03*
X436021D03*
X444821D03*
X537921Y-58764D03*
Y-35764D03*
X532921Y-58764D03*
Y-35764D03*
X527921Y-58764D03*
Y-35764D03*
X522921Y-58764D03*
Y-35764D03*
X517921Y-58764D03*
Y-35764D03*
X512921Y-58764D03*
Y-35764D03*
X507921Y-58764D03*
Y-35764D03*
X502921Y-58764D03*
Y-35764D03*
X497921Y-58764D03*
Y-35764D03*
X492921Y-58764D03*
Y-35764D03*
X487921Y-58764D03*
Y-35764D03*
X482921Y-58764D03*
Y-35764D03*
X480006Y638753D03*
X484406D03*
X488806D03*
X493206D03*
X497606D03*
X510806D03*
X537206D03*
X519606D03*
X524006D03*
X532806D03*
X528406D03*
X515206D03*
X502006D03*
X506406D03*
X524021Y660756D03*
X480021D03*
X484421D03*
X497621D03*
X493221D03*
X488821D03*
X519621D03*
X532821D03*
X537221D03*
X528421D03*
X515221D03*
X510821D03*
X506421D03*
X502021D03*
X597921Y-35764D03*
Y-58764D03*
X592921Y-35764D03*
Y-58764D03*
X587921Y-35764D03*
Y-58764D03*
X582921Y-35764D03*
Y-58764D03*
X577921Y-35764D03*
Y-58764D03*
X572921Y-35764D03*
Y-58764D03*
X567921Y-35764D03*
Y-58764D03*
X562921Y-35764D03*
Y-58764D03*
X557921Y-35764D03*
Y-58764D03*
X552921Y-35764D03*
Y-58764D03*
X547921D03*
Y-35764D03*
X542921Y-58764D03*
Y-35764D03*
X576941Y646238D03*
X567029D03*
X590006Y638753D03*
X572406D03*
X559206D03*
X568006D03*
X563606D03*
X550406D03*
X581206D03*
X585606D03*
X576806D03*
X598806D03*
X594406D03*
X601500Y649500D03*
X554806Y638753D03*
X541606D03*
X546006D03*
X576941Y652238D03*
X567029D03*
X559221Y660756D03*
X546021D03*
X554821D03*
X598821D03*
X572421D03*
X568021D03*
X563621D03*
X585621D03*
X541621D03*
X594421D03*
X576821D03*
X590021D03*
X581221D03*
X550421D03*
X637921Y-58764D03*
X632921Y-35764D03*
Y-58764D03*
X627921Y-35764D03*
Y-58764D03*
X622921Y-35764D03*
Y-58764D03*
X617921Y-35764D03*
Y-58764D03*
X612921Y-35764D03*
Y-58764D03*
X607921Y-35764D03*
Y-58764D03*
X602921Y-35764D03*
Y-58764D03*
X652921Y-35764D03*
Y-58764D03*
X647921Y-35764D03*
Y-58764D03*
X642921Y-35764D03*
Y-58764D03*
X637921Y-35764D03*
X662921D03*
Y-58764D03*
X657921Y-35764D03*
Y-58764D03*
X653750Y225500D03*
X641600Y221400D03*
Y226600D03*
Y224000D03*
Y229200D03*
X644500D03*
Y224000D03*
Y226600D03*
X641600Y231800D03*
X644500D03*
X650700Y224000D03*
X647600D03*
X650700Y226600D03*
X647600D03*
X650700Y231800D03*
X647600D03*
Y229200D03*
X650700D03*
X641541Y236028D03*
Y238628D03*
X637001Y227337D03*
Y222137D03*
Y224737D03*
Y229937D03*
X641541Y243828D03*
Y241228D03*
X628589Y463649D03*
X629359Y469583D03*
X632771Y473269D03*
X605176Y487581D03*
X641107Y471989D03*
X634033Y467638D03*
X638406Y638753D03*
X634006D03*
X642806D03*
X629606D03*
X616406D03*
X612006D03*
X603206D03*
X625206D03*
X651606D03*
X647206D03*
X660406D03*
X620806D03*
X656006D03*
X607606D03*
X607621Y660756D03*
X638421D03*
X647221D03*
X616421D03*
X634021D03*
X612021D03*
X620821D03*
X625221D03*
X629621D03*
X642821D03*
X603221D03*
X656021D03*
X660421D03*
X651621D03*
X692921Y-58764D03*
X687921Y-35764D03*
Y-58764D03*
X682921Y-35764D03*
Y-58764D03*
X677921Y-35764D03*
Y-58764D03*
X672921Y-35764D03*
Y-58764D03*
X667921Y-35764D03*
Y-58764D03*
X697921Y-35764D03*
Y-58764D03*
X692921Y-35764D03*
X722921D03*
Y-58764D03*
X717921Y-35764D03*
Y-58764D03*
X712921Y-35764D03*
Y-58764D03*
X707921Y-35764D03*
Y-58764D03*
X702921Y-35764D03*
Y-58764D03*
X704466Y-7874D03*
X690966Y-21374D03*
X700525Y1668D03*
X700517Y-17425D03*
X681713Y-17927D03*
X690966Y5626D03*
X681714Y2178D03*
X673864Y-16889D03*
X667566Y-7874D03*
X673864Y1139D03*
X706164Y390143D03*
X708975Y390174D03*
X711575Y390150D03*
Y393150D03*
X706164Y393143D03*
X708975Y393174D03*
X703160Y392939D03*
X700391Y389737D03*
X703160Y390139D03*
X700291Y392637D03*
X700458Y395503D03*
X703169Y395986D03*
X711575Y396150D03*
X708975Y396174D03*
X706164Y396143D03*
X705673Y387012D03*
Y384412D03*
X711173Y387012D03*
X708373D03*
Y384412D03*
X700204Y386610D03*
X702973Y387012D03*
X700204Y384010D03*
X702973Y384412D03*
X711173Y384312D03*
X695790Y351300D03*
X695606Y638753D03*
X673606D03*
X708806D03*
X704406D03*
X700006D03*
X722006D03*
X717606D03*
X713206D03*
X664806D03*
X669206D03*
X686806D03*
X682406D03*
X678006D03*
X691206D03*
X690966Y624130D03*
Y597130D03*
X700525Y620172D03*
X700517Y601079D03*
X704466Y610630D03*
X667566D03*
X673864Y619643D03*
Y601615D03*
X681714Y620682D03*
X681713Y600577D03*
X664821Y660756D03*
X695621D03*
X708821D03*
X700021D03*
X704421D03*
X669221D03*
X686821D03*
X691221D03*
X678021D03*
X673621D03*
X682421D03*
X722021D03*
X717621D03*
X713221D03*
X777921Y-58764D03*
X772921Y-35764D03*
Y-58764D03*
X767921Y-35764D03*
Y-58764D03*
X762921Y-35764D03*
Y-58764D03*
X757921Y-35764D03*
Y-58764D03*
X752921Y-35764D03*
Y-58764D03*
X787921Y-35764D03*
Y-58764D03*
X782921Y-35764D03*
Y-58764D03*
X777921Y-35764D03*
X747921D03*
Y-58764D03*
X742921Y-35764D03*
Y-58764D03*
X737921Y-35764D03*
Y-58764D03*
X732921Y-35764D03*
Y-58764D03*
X727921Y-35764D03*
Y-58764D03*
X786674Y211463D03*
X785920Y204763D03*
X786300Y207400D03*
X787200Y244200D03*
Y271900D03*
X787100Y241100D03*
X770632Y234833D03*
X770965Y237519D03*
X773800Y237700D03*
X768382Y237861D03*
X769637Y266647D03*
X770485Y269489D03*
X772630Y266810D03*
X773419Y270414D03*
X787200Y276400D03*
X787100Y303900D03*
X775200Y301200D03*
X770900Y301800D03*
X768290Y301780D03*
X753098Y338316D03*
X747498Y335516D03*
X750298Y338316D03*
Y335516D03*
X744698Y338316D03*
Y335516D03*
X747498Y338316D03*
X744698Y332816D03*
X769440Y298735D03*
X772400Y299400D03*
X787000Y308300D03*
X771730Y330665D03*
X775732Y332989D03*
X770278Y333272D03*
X772949Y333009D03*
X787400Y340400D03*
X747000Y386000D03*
X743500D03*
X750500D03*
X754000D03*
X750298Y344833D03*
X744698Y347833D03*
X747498D03*
X750298D03*
X747673Y364009D03*
X745073D03*
X750273D03*
X747573Y366909D03*
X744973D03*
X750173D03*
X744698Y344833D03*
X747498D03*
X747000Y380000D03*
X743500D03*
X753874Y379863D03*
X750500Y380000D03*
Y374000D03*
X754000D03*
X747000D03*
X743500D03*
X741774Y376463D03*
X769380Y366440D03*
X775070Y365070D03*
X772290Y365020D03*
X769440Y363810D03*
X785400Y372400D03*
X757500Y374000D03*
X775420Y397110D03*
X772742Y397209D03*
X766860Y396240D03*
X769770Y396070D03*
X770406Y638753D03*
X779206D03*
X774806D03*
X730806D03*
X726406D03*
X739606D03*
X735206D03*
X748406D03*
X744006D03*
X766006D03*
X761606D03*
X757206D03*
X752806D03*
X783606D03*
X744021Y660756D03*
X735221D03*
X779221D03*
X770421D03*
X774821D03*
X726421D03*
X730821D03*
X739621D03*
X748421D03*
X783621D03*
X757221D03*
X761621D03*
X752821D03*
X766021D03*
X842921Y-35764D03*
X837921Y-58764D03*
Y-35764D03*
X832921Y-58764D03*
X847921D03*
Y-35764D03*
X842921Y-58764D03*
X832921Y-35764D03*
X827921Y-58764D03*
Y-35764D03*
X822921Y-58764D03*
Y-35764D03*
X817921Y-58764D03*
Y-35764D03*
X812921Y-58764D03*
Y-35764D03*
X807921Y-58764D03*
Y-35764D03*
X802921Y-58764D03*
Y-35764D03*
X797921D03*
Y-58764D03*
X792921Y-35764D03*
Y-58764D03*
X816900Y216300D03*
X816874Y212863D03*
X814274D03*
X811674D03*
X808818Y211179D03*
X808618Y208579D03*
X803200Y213100D03*
X800600D03*
X794474Y211463D03*
X791874D03*
X789274D03*
X788522Y204343D03*
X791122Y204339D03*
X829327Y214740D03*
X832276Y214754D03*
X827322Y217430D03*
X826700Y214802D03*
X824072Y214865D03*
X824446Y217476D03*
X821775Y217617D03*
X821466Y214925D03*
X814849Y205001D03*
X792514Y201290D03*
X797717Y201907D03*
X803134Y202969D03*
X808165Y203529D03*
X818960Y202230D03*
X789432Y236947D03*
X789400Y273700D03*
X811983Y244843D03*
Y242243D03*
X814583Y239643D03*
X815432Y237000D03*
X814583Y244843D03*
Y242243D03*
X812832Y237000D03*
X811983Y239643D03*
X802432Y237000D03*
X799832D03*
X792032D03*
X794632D03*
X810232D03*
X797232D03*
X805032D03*
X807632D03*
X791000Y244400D03*
X793600D03*
X816800Y234300D03*
X816900Y230900D03*
X817000Y252500D03*
X789800Y276400D03*
X792400D03*
X801991Y276557D03*
X804591D03*
X792191Y269101D03*
X789591D03*
X814891Y271657D03*
Y274257D03*
Y276857D03*
Y269057D03*
X812291D03*
Y274257D03*
Y276857D03*
Y271657D03*
X817000Y255100D03*
Y257700D03*
X848282Y251727D03*
X828180Y231748D03*
X828682Y237027D03*
X831682D03*
X828682Y234327D03*
X837500Y239500D03*
X845050Y229400D03*
X837500Y234050D03*
Y236650D03*
X834682Y236877D03*
X840155Y234245D03*
X834700Y234200D03*
X831682Y234327D03*
X834682Y239627D03*
X831682D03*
X828682D03*
X848282Y246427D03*
Y249027D03*
X825682Y239627D03*
Y234327D03*
Y237027D03*
X825313Y231753D03*
X848382Y279727D03*
Y277027D03*
Y274427D03*
X825464Y277510D03*
Y274910D03*
Y280110D03*
X822464D03*
Y277510D03*
Y274910D03*
X834464Y280110D03*
X831464D03*
X828464Y277510D03*
Y274910D03*
Y280110D03*
X834464Y277510D03*
X831464D03*
X834464Y274910D03*
X845050Y252250D03*
X817491Y276857D03*
Y274257D03*
Y271657D03*
Y269057D03*
X837264Y274910D03*
Y280110D03*
Y277510D03*
X840064D03*
Y280110D03*
X817183Y242243D03*
Y239643D03*
Y244843D03*
X818032Y237000D03*
X822682Y234327D03*
Y231727D03*
Y237027D03*
Y239627D03*
X831464Y274910D03*
X844400Y280500D03*
X848282Y254327D03*
X788600Y306100D03*
X789500Y301200D03*
X797300D03*
X799900D03*
X810300D03*
X802500D03*
X812900D03*
X807700D03*
X805100D03*
X815500D03*
X811991Y308957D03*
Y306357D03*
Y303757D03*
X814591Y306357D03*
Y308957D03*
Y303757D03*
X792900Y308400D03*
X789900D03*
X794700Y301200D03*
X792100D03*
X793000Y340400D03*
X790300Y340300D03*
X816991Y337357D03*
Y334757D03*
Y339957D03*
X814391D03*
Y337357D03*
Y334757D03*
X811791Y337357D03*
Y339957D03*
Y334757D03*
X791879Y332798D03*
X794600Y332600D03*
X816938Y319888D03*
Y323888D03*
X817100Y317000D03*
X848382Y282327D03*
X834682Y298527D03*
X828682D03*
X825682D03*
Y295527D03*
Y301227D03*
Y303927D03*
X822682D03*
Y301227D03*
Y295527D03*
Y298527D03*
X844300Y312450D03*
X831682Y298527D03*
X837782Y298127D03*
Y301027D03*
Y303927D03*
X818100Y301200D03*
X817191Y303757D03*
Y306357D03*
Y308957D03*
X834682Y301227D03*
X831682D03*
X828682D03*
X831682Y303927D03*
X834682D03*
X822482Y339827D03*
Y337027D03*
X831482D03*
X834482D03*
X828482Y339827D03*
X831482D03*
X834482D03*
X840282Y340227D03*
X840382Y337427D03*
X837382Y339877D03*
Y337077D03*
X847682Y314627D03*
X847982Y338327D03*
Y341327D03*
X828482Y337027D03*
X828682Y303927D03*
X847682Y309327D03*
Y312027D03*
Y306727D03*
X825482Y339827D03*
Y337027D03*
X789860Y364947D03*
X820218Y385950D03*
Y382950D03*
X826097Y385923D03*
X816591Y369857D03*
Y372457D03*
X811391Y369857D03*
X813991D03*
Y372457D03*
X811391D03*
X790900Y372300D03*
X788300Y372400D03*
X802759Y364575D03*
X816672Y358809D03*
X795310Y364721D03*
X816593Y356210D03*
X807959Y364575D03*
X805359D03*
X810559D03*
X815759D03*
X813159D03*
X816900Y361400D03*
X792610Y364821D03*
X816591Y375057D03*
X792238Y396753D03*
X789600Y396809D03*
X811515Y397289D03*
X808915D03*
X813648Y395557D03*
X815472Y390442D03*
X814877Y393138D03*
X792000Y399409D03*
X789400D03*
X822089Y362782D03*
Y359782D03*
X822482Y342827D03*
X828482D03*
X831482D03*
X834482D03*
X828089Y359841D03*
X834089D03*
X831089D03*
X844350Y344000D03*
X840262Y343011D03*
X837382Y342877D03*
X821658Y369463D03*
X832058Y366863D03*
Y369463D03*
X834658D03*
Y366863D03*
X837363Y366829D03*
X826858Y366863D03*
Y369463D03*
X824258Y366863D03*
Y369463D03*
X829458D03*
Y366863D03*
X821658D03*
X847982Y344327D03*
X834089Y362782D03*
X831089D03*
X826216Y383108D03*
X823218Y382950D03*
X848608Y376068D03*
Y378668D03*
X846008Y376068D03*
Y378668D03*
X848932Y373257D03*
X823218Y385950D03*
X828089Y362782D03*
X825482Y342827D03*
X825089Y359841D03*
Y362782D03*
X849606Y638753D03*
X836406D03*
X832006D03*
X796806D03*
X801206D03*
X792406D03*
X827606D03*
X818806D03*
X823206D03*
X810006D03*
X788006D03*
X845206D03*
X814406D03*
X805606D03*
X840806D03*
X849621Y660756D03*
X832021D03*
X810021D03*
X818821D03*
X836421D03*
X788021D03*
X814421D03*
X801221D03*
X805621D03*
X823221D03*
X827621D03*
X840821D03*
X796821D03*
X792421D03*
X845221D03*
X907921Y-58764D03*
Y-35764D03*
X902921Y-58764D03*
Y-35764D03*
X897921Y-58764D03*
Y-35764D03*
X892921Y-58764D03*
Y-35764D03*
X887921Y-58764D03*
Y-35764D03*
X882921Y-58764D03*
Y-35764D03*
X877921Y-58764D03*
Y-35764D03*
X872921Y-58764D03*
Y-35764D03*
X867921Y-58764D03*
Y-35764D03*
X862921Y-58764D03*
Y-35764D03*
X857921Y-58764D03*
Y-35764D03*
X852921Y-58764D03*
Y-35764D03*
X854282Y251727D03*
X857282D03*
X851282D03*
X857282Y249027D03*
Y246427D03*
X851282D03*
Y249027D03*
X854282D03*
Y246427D03*
X851382Y277027D03*
Y274427D03*
X857382Y277027D03*
X854382Y279727D03*
X857382D03*
X854382Y274427D03*
X857382D03*
X854382Y277027D03*
X874586Y259278D03*
X854282Y254327D03*
X857282D03*
X869586Y254278D03*
X851282Y254327D03*
X851382Y279727D03*
X884586Y269278D03*
X879586Y264278D03*
X889586Y274278D03*
X851382Y282327D03*
X854382D03*
X857382D03*
X851075Y335405D03*
X857075D03*
X856982Y338327D03*
X853982D03*
X856682Y314627D03*
X853682D03*
X850682D03*
X856982Y341327D03*
X853982D03*
X862008Y341100D03*
X850982Y338327D03*
Y341327D03*
X872008Y331100D03*
X867008Y336100D03*
X850682Y306727D03*
Y309327D03*
Y312027D03*
X856682Y309327D03*
X853682D03*
X856682Y306727D03*
X853682D03*
X856682Y312027D03*
X853682D03*
X877008Y326100D03*
X854075Y335405D03*
X856982Y344327D03*
X853982D03*
X850982D03*
X851208Y376068D03*
Y378668D03*
X851727Y373197D03*
X858406Y638753D03*
X854006D03*
X884806D03*
X880406D03*
X876006D03*
X871606D03*
X867206D03*
X911206D03*
X906806D03*
X889206D03*
X898006D03*
X902406D03*
X893606D03*
X862806D03*
X854021Y660756D03*
X858421D03*
X862821D03*
X898021D03*
X902421D03*
X871621D03*
X884821D03*
X893621D03*
X867221D03*
X889221D03*
X911221D03*
X906821D03*
X880421D03*
X876021D03*
X937921Y-35764D03*
X932921Y-58764D03*
Y-35764D03*
X927921Y-58764D03*
Y-35764D03*
X922921Y-58764D03*
Y-35764D03*
X917921Y-58764D03*
Y-35764D03*
X912921Y-58764D03*
Y-35764D03*
X942921D03*
X967921D03*
X962921Y-58764D03*
Y-35764D03*
X957921Y-58764D03*
Y-35764D03*
X952921Y-58764D03*
Y-35764D03*
X947921Y-58764D03*
Y-35764D03*
X942921Y-58764D03*
X972921D03*
Y-35764D03*
X967921Y-58764D03*
X937921D03*
X941883Y646234D03*
X951795D03*
X924406Y638753D03*
X920006D03*
X915606D03*
X972806D03*
X968406D03*
X964006D03*
X917100Y649300D03*
X942006Y638753D03*
X937606D03*
X933206D03*
X928806D03*
X959606D03*
X955206D03*
X950806D03*
X946406D03*
X941883Y652234D03*
X951795D03*
X959621Y660756D03*
X964021D03*
X968421D03*
X972821D03*
X920021D03*
X915621D03*
X924421D03*
X946421D03*
X942021D03*
X937621D03*
X933221D03*
X928821D03*
X955221D03*
X950821D03*
X1002921Y-58764D03*
Y-35764D03*
X997921Y-58764D03*
Y-35764D03*
X992921Y-58764D03*
Y-35764D03*
X987921Y-58764D03*
Y-35764D03*
X982921Y-58764D03*
Y-35764D03*
X977921Y-58764D03*
Y-35764D03*
X1032921Y-58764D03*
Y-35764D03*
X1027921Y-58764D03*
Y-35764D03*
X1022921Y-58764D03*
Y-35764D03*
X1017921Y-58764D03*
Y-35764D03*
X1012921Y-58764D03*
Y-35764D03*
X1007921Y-58764D03*
Y-35764D03*
X1030489Y270889D03*
Y273889D03*
X1027902Y278904D03*
X1020702D03*
X1017702D03*
X1024902D03*
X1032102D03*
X1024994Y292918D03*
X1017630Y292910D03*
X1020702Y292904D03*
X1027902D03*
X1031953Y292910D03*
X1024140Y309910D03*
X1021065Y309759D03*
X1017083Y309910D03*
X1032042D03*
X1028136Y309815D03*
X1017567Y295859D03*
X1024767D03*
X1020567D03*
X1031967D03*
X1027767D03*
X1015293Y311955D03*
X1003606Y638753D03*
X1012406D03*
X977206D03*
X990406D03*
X986006D03*
X994806D03*
X1016806D03*
X1021206D03*
X981606D03*
X999206D03*
X1025606D03*
X1008006D03*
X1030006D03*
X1034406D03*
X999221Y660756D03*
X1034421D03*
X1030021D03*
X1008021D03*
X1012421D03*
X1003621D03*
X1016821D03*
X977221D03*
X981621D03*
X1021221D03*
X1025621D03*
X994821D03*
X986021D03*
X990421D03*
X1067921Y-58764D03*
Y-35764D03*
X1062921Y-58764D03*
Y-35764D03*
X1057921Y-58764D03*
Y-35764D03*
X1052921Y-58764D03*
Y-35764D03*
X1047921Y-58764D03*
Y-35764D03*
X1042921Y-58764D03*
Y-35764D03*
X1037921Y-58764D03*
Y-35764D03*
X1092921Y-58764D03*
Y-35764D03*
X1087921Y-58764D03*
Y-35764D03*
X1082921Y-58764D03*
Y-35764D03*
X1077921Y-58764D03*
Y-35764D03*
X1072921Y-58764D03*
Y-35764D03*
X1075865Y264766D03*
X1070300Y264900D03*
X1073200Y264991D03*
X1057202Y264899D03*
X1060402Y264799D03*
X1066300Y264700D03*
X1063402Y264799D03*
X1054202Y264899D03*
X1042302Y278904D03*
X1039302D03*
X1056602Y278910D03*
X1035814Y278775D03*
X1049867Y278999D03*
X1053459Y278910D03*
X1060958D03*
X1075302D03*
X1078302D03*
X1082330D03*
X1070926D03*
X1063652D03*
X1067783D03*
X1082432Y264620D03*
X1085518Y278910D03*
X1089702Y278904D03*
X1086061Y262300D03*
X1086000Y264900D03*
X1077282Y338533D03*
X1080282D03*
X1056792Y338673D03*
X1063992D03*
X1060992D03*
X1071192D03*
X1068192D03*
X1046276Y292910D03*
X1049502Y292904D03*
X1053684Y292910D03*
X1056702Y292904D03*
X1039182Y292919D03*
X1042302Y292904D03*
X1035102D03*
X1049547Y309904D03*
X1046612Y309910D03*
X1056747Y309904D03*
X1053594Y309910D03*
X1042347Y309904D03*
X1039383Y309910D03*
X1035147Y309904D03*
X1039167Y295859D03*
X1042167D03*
X1034967D03*
X1046367D03*
X1056567D03*
X1049367D03*
X1053567D03*
X1038720Y324174D03*
X1044220D03*
X1035820D03*
X1050220D03*
X1047220D03*
X1053220D03*
X1056220D03*
X1041470D03*
X1059220D03*
X1060767Y295859D03*
X1095756Y292841D03*
X1082367Y295859D03*
X1085367D03*
X1075167D03*
X1078167D03*
X1089567D03*
X1092567D03*
X1095567Y295841D03*
X1070967Y295859D03*
X1063767D03*
X1067967D03*
X1086126Y338758D03*
X1083301Y338841D03*
X1062220Y324174D03*
X1095402Y323904D03*
X1083220Y324174D03*
X1076020D03*
X1079020D03*
X1071820D03*
X1065220D03*
X1068820D03*
X1096006Y638753D03*
X1078406D03*
X1082806D03*
X1074006D03*
X1069606D03*
X1091606D03*
X1052006D03*
X1038806D03*
X1087206D03*
X1060806D03*
X1056406D03*
X1065206D03*
X1043206D03*
X1047606D03*
X1078421Y660756D03*
X1060821D03*
X1087221D03*
X1038821D03*
X1091621D03*
X1052021D03*
X1074021D03*
X1065221D03*
X1096021D03*
X1056421D03*
X1043221D03*
X1047621D03*
X1082821D03*
X1069621D03*
X1157921Y-58764D03*
Y-35764D03*
X1152921Y-58764D03*
Y-35764D03*
X1147921Y-58764D03*
Y-35764D03*
X1142921Y-58764D03*
Y-35764D03*
X1137921Y-58764D03*
Y-35764D03*
X1132921Y-58764D03*
Y-35764D03*
X1127921Y-58764D03*
Y-35764D03*
X1122921Y-58764D03*
Y-35764D03*
X1117921Y-58764D03*
Y-35764D03*
X1112921Y-58764D03*
Y-35764D03*
X1107921Y-58764D03*
Y-35764D03*
X1102921Y-58764D03*
Y-35764D03*
X1097921Y-58764D03*
Y-35764D03*
X1104256Y291841D03*
X1101615Y292447D03*
X1098756Y292841D03*
X1101567Y295859D03*
X1104221Y295696D03*
X1098567Y295841D03*
X1112490Y312723D03*
X1112515Y315369D03*
X1101200Y324013D03*
X1098402Y324017D03*
X1135606Y638753D03*
X1126806D03*
X1144406D03*
X1140006D03*
X1118006D03*
X1122406D03*
X1153206D03*
X1157606D03*
X1104806D03*
X1100406D03*
X1131206D03*
X1148806D03*
X1109206D03*
X1113606D03*
X1157621Y660756D03*
X1148821D03*
X1122421D03*
X1126821D03*
X1100421D03*
X1118021D03*
X1140021D03*
X1113621D03*
X1109221D03*
X1153221D03*
X1144421D03*
X1104821D03*
X1131221D03*
X1135621D03*
X1217921Y-58764D03*
Y-35764D03*
X1212921Y-58764D03*
Y-35764D03*
X1207921Y-58764D03*
Y-35764D03*
X1202921Y-58764D03*
Y-35764D03*
X1197921Y-58764D03*
Y-35764D03*
X1192921Y-58764D03*
Y-35764D03*
X1187921Y-58764D03*
Y-35764D03*
X1182921Y-58764D03*
Y-35764D03*
X1177921Y-58764D03*
Y-35764D03*
X1172921Y-58764D03*
Y-35764D03*
X1167921Y-58764D03*
Y-35764D03*
X1162921Y-58764D03*
Y-35764D03*
X1196198Y646206D03*
X1206110D03*
X1188406Y638753D03*
X1214806D03*
X1197206D03*
X1201606D03*
X1192806D03*
X1170806D03*
X1162006D03*
X1166406D03*
X1206006D03*
X1219206D03*
X1179606D03*
X1175206D03*
X1210406D03*
X1184006D03*
X1196198Y652206D03*
X1206110D03*
X1184021Y660756D03*
X1219221D03*
X1192821D03*
X1188421D03*
X1201621D03*
X1179621D03*
X1214821D03*
X1206021D03*
X1166421D03*
X1210421D03*
X1170821D03*
X1162021D03*
X1175221D03*
X1197221D03*
X1232921Y-58764D03*
Y-35764D03*
X1227921Y-58764D03*
Y-35764D03*
X1222921Y-58764D03*
Y-35764D03*
X1252921Y-58764D03*
Y-35764D03*
X1247921Y-58764D03*
Y-35764D03*
X1242921Y-58764D03*
Y-35764D03*
X1237921Y-58764D03*
Y-35764D03*
X1257921D03*
X1272921Y-58764D03*
Y-35764D03*
X1267921Y-58764D03*
Y-35764D03*
X1262921Y-58764D03*
Y-35764D03*
X1257921Y-58764D03*
X1277921D03*
Y-35764D03*
X1265293Y646264D03*
X1255381D03*
X1263206Y638753D03*
X1223606D03*
X1228006D03*
X1258806D03*
X1241206D03*
X1236806D03*
X1250006D03*
X1245606D03*
X1276406D03*
X1254406D03*
X1280806D03*
X1272006D03*
X1267606D03*
X1232406D03*
X1265293Y652264D03*
X1255381D03*
X1228021Y660756D03*
X1232421D03*
X1280821D03*
X1245621D03*
X1236821D03*
X1223621D03*
X1276421D03*
X1241221D03*
X1272021D03*
X1258821D03*
X1250021D03*
X1254421D03*
X1263221D03*
X1267621D03*
X1342921Y-35764D03*
Y-58764D03*
X1317921D03*
X1312921Y-35764D03*
Y-58764D03*
X1307921Y-35764D03*
Y-58764D03*
X1302921Y-35764D03*
Y-58764D03*
X1297921D03*
Y-35764D03*
X1292921Y-58764D03*
Y-35764D03*
X1287921Y-58764D03*
Y-35764D03*
X1282921Y-58764D03*
Y-35764D03*
X1322921D03*
Y-58764D03*
X1317921Y-35764D03*
X1337921D03*
Y-58764D03*
X1332921Y-35764D03*
Y-58764D03*
X1327921Y-35764D03*
Y-58764D03*
X1324806Y638753D03*
X1298406D03*
X1285206D03*
X1294006D03*
X1302806D03*
X1333606D03*
X1338006D03*
X1320406D03*
X1311606D03*
X1329206D03*
X1307206D03*
X1342406D03*
X1289606D03*
X1316006D03*
X1329221Y660756D03*
X1311621D03*
X1316021D03*
X1333621D03*
X1342421D03*
X1285221D03*
X1324821D03*
X1338021D03*
X1298421D03*
X1289621D03*
X1294021D03*
X1320421D03*
X1302821D03*
X1307221D03*
X1402921Y-58764D03*
X1397921D03*
X1402921Y-35764D03*
X1392921Y-58764D03*
X1397921Y-35764D03*
X1387921Y-58764D03*
X1392921Y-35764D03*
X1382921Y-58764D03*
X1387921Y-35764D03*
X1377921Y-58764D03*
X1382921Y-35764D03*
X1372921Y-58764D03*
X1377921Y-35764D03*
X1367921Y-58764D03*
X1362921Y-35764D03*
Y-58764D03*
X1357921Y-35764D03*
Y-58764D03*
X1352921Y-35764D03*
Y-58764D03*
X1347921Y-35764D03*
Y-58764D03*
X1395913Y-7874D03*
X1402211Y1139D03*
Y-16889D03*
X1351206Y638753D03*
X1360006D03*
X1404506Y638853D03*
X1355606Y638753D03*
X1386906Y638853D03*
X1364406Y638753D03*
X1391306Y638853D03*
X1346806Y638753D03*
X1400106Y638853D03*
X1382006Y638753D03*
X1377606D03*
X1373206D03*
X1395706Y638853D03*
X1368806Y638753D03*
X1402211Y601615D03*
Y619643D03*
X1395913Y610630D03*
X1368821Y660756D03*
X1346821D03*
X1355621D03*
X1360021D03*
X1364421D03*
X1351221D03*
X1404521Y660856D03*
X1400121D03*
X1395721D03*
X1386921D03*
X1377621Y660756D03*
X1382021D03*
X1373221D03*
X1391321Y660856D03*
X1407921Y-58764D03*
X1412921Y-35764D03*
X1407921D03*
X1442921Y-58764D03*
X1447921Y-35764D03*
X1437921Y-58764D03*
X1442921Y-35764D03*
X1432921Y-58764D03*
X1437921Y-35764D03*
X1427921Y-58764D03*
X1432921Y-35764D03*
X1422921Y-58764D03*
X1427921Y-35764D03*
X1417921Y-58764D03*
X1422921Y-35764D03*
X1412921Y-58764D03*
X1417921Y-35764D03*
X1462921Y-58764D03*
X1457921D03*
X1462921Y-35764D03*
X1452921Y-58764D03*
X1457921Y-35764D03*
X1447921Y-58764D03*
X1452921Y-35764D03*
X1410061Y2178D03*
X1410060Y-17927D03*
X1419313Y5626D03*
Y-21374D03*
X1428872Y1668D03*
X1428864Y-17425D03*
X1432813Y-7874D03*
X1431664Y190213D03*
X1456080Y547540D03*
X1463369Y561763D03*
X1446600Y563900D03*
X1449300D03*
X1454600D03*
X1451900D03*
X1457300D03*
X1452392Y544998D03*
X1453166Y547481D03*
X1422106Y638853D03*
X1466106D03*
X1448506D03*
X1457306D03*
X1417706D03*
X1413306D03*
X1461706D03*
X1452906D03*
X1408906D03*
X1444106D03*
X1435306D03*
X1426506D03*
X1430906D03*
X1439706D03*
X1432813Y610630D03*
X1428864Y601079D03*
X1428872Y620172D03*
X1419313Y597130D03*
Y624130D03*
X1410060Y600577D03*
X1410061Y620682D03*
X1457321Y660856D03*
X1417721D03*
X1413321D03*
X1408921D03*
X1422121D03*
X1426521D03*
X1435321D03*
X1444121D03*
X1439721D03*
X1430921D03*
X1448521D03*
X1452921D03*
X1466121D03*
X1461721D03*
X1502921Y-58764D03*
X1507921Y-35764D03*
X1497921Y-58764D03*
X1502921Y-35764D03*
X1492921Y-58764D03*
X1497921Y-35764D03*
X1487921Y-58764D03*
X1492921Y-35764D03*
X1482921Y-58764D03*
X1487921Y-35764D03*
X1477921Y-58764D03*
X1482921Y-35764D03*
X1472921Y-58764D03*
X1477921Y-35764D03*
X1467921Y-58764D03*
X1472921Y-35764D03*
X1467921D03*
X1527921Y-58764D03*
X1522921D03*
X1527921Y-35764D03*
X1517921Y-58764D03*
X1522921Y-35764D03*
X1512921Y-58764D03*
X1517921Y-35764D03*
X1507921Y-58764D03*
X1512921Y-35764D03*
X1514372Y248616D03*
Y243361D03*
X1514370Y246016D03*
X1473018Y562003D03*
X1470314Y561923D03*
X1467714Y561896D03*
X1526586Y559860D03*
X1527285Y562386D03*
X1524538Y562286D03*
X1495187Y561842D03*
X1497918Y561872D03*
X1492187Y561842D03*
X1489316Y561742D03*
X1500530Y561872D03*
X1492130Y545910D03*
X1495130D03*
X1497866Y545797D03*
X1519608Y646236D03*
X1509696D03*
X1496906Y638853D03*
X1492506D03*
X1501706Y638753D03*
X1506106D03*
X1514906D03*
X1483706Y638853D03*
X1523706Y638753D03*
X1510506D03*
X1488106Y638853D03*
X1474906D03*
X1519306Y638753D03*
X1479306Y638853D03*
X1528106Y638753D03*
X1470506Y638853D03*
X1519608Y652236D03*
X1509696D03*
X1496921Y660856D03*
X1483721D03*
X1488121D03*
X1492521D03*
X1479321D03*
X1510521Y660756D03*
X1528121D03*
X1523721D03*
X1501721D03*
X1506121D03*
X1514921D03*
X1519321D03*
X1474921Y660856D03*
X1470521D03*
X1587921Y-58764D03*
X1582921D03*
X1587921Y-35764D03*
X1532921D03*
X1542921D03*
X1532921Y-58764D03*
X1537921Y-35764D03*
X1577921Y-58764D03*
X1582921Y-35764D03*
X1572921Y-58764D03*
X1577921Y-35764D03*
X1567921Y-58764D03*
X1572921Y-35764D03*
X1562921Y-58764D03*
X1567921Y-35764D03*
X1557921Y-58764D03*
X1562921Y-35764D03*
X1552921Y-58764D03*
X1557921Y-35764D03*
X1547921Y-58764D03*
X1552921Y-35764D03*
X1542921Y-58764D03*
X1547921Y-35764D03*
X1537921Y-58764D03*
X1567425Y144373D03*
X1583078Y260122D03*
X1583047Y257171D03*
X1586399Y257099D03*
X1589030Y259807D03*
X1588999Y257104D03*
X1586430Y259824D03*
X1570020Y295340D03*
X1531986Y559860D03*
X1529286D03*
X1529985Y562386D03*
X1532685D03*
X1546795Y563316D03*
X1546685Y568656D03*
X1546825Y565986D03*
X1549395Y563541D03*
X1549285Y568881D03*
X1549425Y566211D03*
X1535385Y562386D03*
X1534897Y559808D03*
X1541267Y563185D03*
X1543967D03*
X1541080Y565859D03*
X1538331Y563913D03*
X1538385Y560978D03*
X1544080Y568859D03*
Y565859D03*
X1580121Y647556D03*
X1555106Y638753D03*
X1555121Y647556D03*
X1590121D03*
X1590106Y638753D03*
X1590121Y643156D03*
X1585121Y647556D03*
X1585106Y638753D03*
X1585121Y643156D03*
X1565121Y647556D03*
X1570121Y643156D03*
X1570106Y638753D03*
X1565106D03*
X1565121Y643156D03*
X1570121Y647556D03*
X1560121D03*
X1560106Y638753D03*
X1560121Y643156D03*
X1575121D03*
X1575106Y638753D03*
X1575121Y647556D03*
X1555121Y643156D03*
X1580106Y638753D03*
X1580121Y643156D03*
X1550121Y647556D03*
X1541306Y638753D03*
X1545706D03*
X1550106D03*
X1550121Y643156D03*
X1536906Y638753D03*
X1532506D03*
X1565121Y651956D03*
X1570121Y660756D03*
Y656356D03*
X1565121Y660756D03*
X1555121Y651956D03*
X1590121Y660756D03*
Y656356D03*
Y651956D03*
X1585121Y660756D03*
Y656356D03*
Y651956D03*
X1580121Y660756D03*
Y656356D03*
Y651956D03*
X1560121Y660756D03*
Y656356D03*
Y651956D03*
X1555121Y660756D03*
Y656356D03*
X1570121Y651956D03*
X1575121D03*
Y656356D03*
Y660756D03*
X1565121Y656356D03*
X1550121Y651956D03*
Y656356D03*
X1541321Y660756D03*
X1550121D03*
X1545721D03*
X1532521D03*
X1536921D03*
X1642921Y-35764D03*
Y-58764D03*
X1637921Y-35764D03*
Y-58764D03*
X1632921Y-35764D03*
Y-58764D03*
X1627921D03*
X1622921D03*
X1627921Y-35764D03*
X1617921Y-58764D03*
X1622921Y-35764D03*
X1612921Y-58764D03*
X1617921Y-35764D03*
X1607921Y-58764D03*
X1612921Y-35764D03*
X1602921Y-58764D03*
X1607921Y-35764D03*
X1597921Y-58764D03*
X1602921Y-35764D03*
X1592921Y-58764D03*
X1597921Y-35764D03*
X1592921D03*
X1647921D03*
Y-58764D03*
X1608099Y197125D03*
X1591598Y257028D03*
X1591628Y259924D03*
X1608280Y249234D03*
X1625106Y638753D03*
X1625121Y647556D03*
X1630121Y643156D03*
X1630106Y638753D03*
X1630121Y647556D03*
X1635121Y643156D03*
X1635106Y638753D03*
X1635121Y647556D03*
X1640121Y643156D03*
Y647556D03*
X1640106Y638753D03*
X1650121Y647556D03*
X1650106Y638753D03*
X1650121Y643156D03*
X1645121Y647556D03*
X1645106Y638753D03*
X1645121Y643156D03*
X1625121D03*
X1620121Y647556D03*
X1620106Y638753D03*
X1620121Y643156D03*
X1615121Y647556D03*
X1615106Y638753D03*
X1615121Y643156D03*
X1610121Y647556D03*
X1610106Y638753D03*
X1610121Y643156D03*
X1605121Y647556D03*
X1605106Y638753D03*
X1605121Y643156D03*
X1600121Y647556D03*
X1600106Y638753D03*
X1600121Y643156D03*
X1595121Y647556D03*
X1595106Y638753D03*
X1595121Y643156D03*
X1625121Y651956D03*
Y660756D03*
X1630121Y651956D03*
Y656356D03*
Y660756D03*
X1635121Y651956D03*
Y656356D03*
Y660756D03*
X1625121Y656356D03*
X1640121D03*
Y651956D03*
X1650121Y660756D03*
Y656356D03*
Y651956D03*
X1645121Y660756D03*
Y656356D03*
Y651956D03*
X1640121Y660756D03*
X1620121D03*
Y656356D03*
Y651956D03*
X1615121Y660756D03*
Y656356D03*
Y651956D03*
X1610121Y660756D03*
Y656356D03*
Y651956D03*
X1605121Y660756D03*
Y656356D03*
Y651956D03*
X1600121Y660756D03*
Y656356D03*
Y651956D03*
X1595121Y660756D03*
Y656356D03*
Y651956D03*
X1692921Y-40764D03*
X1702921Y-54764D03*
X1687921D03*
X1682921D03*
X1677921D03*
X1672921D03*
X1692921D03*
X1697921D03*
X1707921D03*
X1712921D03*
X1697921Y-40764D03*
X1692921Y-50764D03*
X1687921D03*
X1682921D03*
X1677921D03*
X1672921D03*
X1712921D03*
X1707921D03*
X1702921D03*
X1697921Y-45764D03*
X1707921D03*
X1702921D03*
X1712921D03*
X1697921Y-50764D03*
X1667921Y-35764D03*
X1712921D03*
Y-58764D03*
X1707921Y-35764D03*
Y-58764D03*
X1702921Y-35764D03*
Y-58764D03*
X1697921Y-35764D03*
Y-58764D03*
X1687921Y-40764D03*
X1672921Y-45764D03*
X1677921D03*
X1682921D03*
Y-40764D03*
X1687921Y-45764D03*
X1692921D03*
X1667921Y-58764D03*
X1662921Y-35764D03*
Y-58764D03*
X1657921Y-35764D03*
Y-58764D03*
X1652921Y-35764D03*
Y-58764D03*
X1712921Y-40764D03*
X1707921D03*
X1702921D03*
X1677921D03*
X1672921D03*
X1677921Y-35764D03*
Y-58764D03*
X1672921Y-35764D03*
Y-58764D03*
X1682921Y-35764D03*
Y-58764D03*
X1692921Y-35764D03*
Y-58764D03*
X1687921Y-35764D03*
Y-58764D03*
X1702005Y499163D03*
X1704596Y498876D03*
X1704544Y501627D03*
X1701874Y501795D03*
X1690121Y647556D03*
X1710121D03*
X1710106Y638753D03*
X1710121Y643156D03*
X1705121Y647556D03*
X1705106Y638753D03*
X1695121Y643156D03*
X1695106Y638753D03*
X1695121Y647556D03*
X1700121Y643156D03*
X1700106Y638753D03*
X1685121Y647556D03*
X1685106Y638753D03*
X1685121Y643156D03*
X1680121Y647556D03*
X1680106Y638753D03*
X1680121Y643156D03*
X1675121Y647556D03*
X1675106Y638753D03*
X1675121Y643156D03*
X1670121Y647556D03*
X1670106Y638753D03*
X1670121Y643156D03*
X1665121Y647556D03*
X1665106Y638753D03*
X1665121Y643156D03*
X1660121Y647556D03*
X1660106Y638753D03*
X1660121Y643156D03*
X1655121Y647556D03*
X1655106Y638753D03*
X1655121Y643156D03*
X1690121D03*
X1690106Y638753D03*
X1700121Y647556D03*
X1705121Y643156D03*
X1690121Y656356D03*
Y651956D03*
X1710121Y660756D03*
Y656356D03*
Y651956D03*
X1705121Y660756D03*
Y656356D03*
Y651956D03*
X1690121Y660756D03*
X1695121Y651956D03*
Y656356D03*
Y660756D03*
X1685121Y651956D03*
X1680121Y660756D03*
Y656356D03*
Y651956D03*
X1675121Y660756D03*
Y656356D03*
Y651956D03*
X1670121Y660756D03*
Y656356D03*
Y651956D03*
X1665121Y660756D03*
Y656356D03*
Y651956D03*
X1660121Y660756D03*
Y656356D03*
Y651956D03*
X1655121Y660756D03*
Y656356D03*
Y651956D03*
X1685121Y660756D03*
Y656356D03*
X1700121Y651956D03*
Y656356D03*
Y660756D03*
X1737921Y-50764D03*
X1722921Y-45764D03*
X1727921D03*
X1732921D03*
X1747921D03*
X1752921D03*
X1727921Y-54764D03*
X1757921D03*
X1717921D03*
X1722921D03*
X1767921Y-40764D03*
Y-50764D03*
X1762921D03*
X1757921D03*
X1762921Y-54764D03*
X1752921D03*
X1747921D03*
X1742921D03*
X1737921D03*
X1732921D03*
X1772921D03*
X1767921D03*
X1762921Y-40764D03*
X1772921D03*
X1722921Y-50764D03*
X1717921D03*
X1732921D03*
X1757921Y-40764D03*
X1717921Y-45764D03*
Y-58764D03*
X1742921Y-50764D03*
X1747921D03*
X1752921D03*
X1742921Y-58764D03*
X1737921Y-35764D03*
Y-58764D03*
X1732921Y-35764D03*
Y-58764D03*
X1727921Y-35764D03*
Y-58764D03*
X1722921Y-35764D03*
Y-58764D03*
X1717921Y-35764D03*
X1757921Y-45764D03*
X1762921D03*
X1742921D03*
X1752921Y-40764D03*
X1747921D03*
X1742921D03*
X1737921D03*
X1732921D03*
X1727921D03*
X1722921D03*
X1717921D03*
X1727921Y-50764D03*
X1767921Y-45764D03*
X1772921D03*
X1737921D03*
X1772921Y-35764D03*
Y-58764D03*
X1767921Y-35764D03*
Y-58764D03*
X1762921Y-35764D03*
Y-58764D03*
X1757921Y-35764D03*
Y-58764D03*
X1752921Y-35764D03*
Y-58764D03*
X1747921Y-35764D03*
Y-58764D03*
X1742921Y-35764D03*
X1772921Y-50764D03*
X1727600Y211300D03*
X1724800D03*
X1758000Y250000D03*
X1758324Y232657D03*
X1741000Y250000D03*
X1738000D03*
X1735000D03*
X1747227Y237314D03*
X1744308Y237295D03*
X1741668Y237314D03*
X1739044Y237284D03*
X1728139Y496807D03*
X1725566Y497186D03*
X1723591Y499135D03*
X1725600Y501000D03*
X1775121Y643156D03*
Y647556D03*
X1775106Y638753D03*
X1730121Y647556D03*
X1730106Y638753D03*
X1730121Y643156D03*
X1725121Y647556D03*
X1725106Y638753D03*
X1725121Y643156D03*
X1720121Y647556D03*
X1720106Y638753D03*
X1720121Y643156D03*
X1715121Y647556D03*
X1715106Y638753D03*
X1715121Y643156D03*
X1770121Y647556D03*
X1770106Y638753D03*
X1770121Y643156D03*
X1765121Y647556D03*
X1765106Y638753D03*
X1765121Y643156D03*
X1760121Y647556D03*
X1760106Y638753D03*
X1760121Y643156D03*
X1755121Y647556D03*
X1755106Y638753D03*
X1755121Y643156D03*
X1750121Y647556D03*
X1750106Y638753D03*
X1750121Y643156D03*
X1745121Y647556D03*
X1745106Y638753D03*
X1745121Y643156D03*
X1740121Y647556D03*
X1740106Y638753D03*
X1740121Y643156D03*
X1735121Y647556D03*
X1735106Y638753D03*
X1735121Y643156D03*
X1770121Y660756D03*
X1775121D03*
Y656356D03*
Y651956D03*
X1725121Y660756D03*
Y656356D03*
Y651956D03*
X1720121Y660756D03*
Y656356D03*
Y651956D03*
X1715121Y660756D03*
Y656356D03*
Y651956D03*
X1770121D03*
X1765121Y660756D03*
Y656356D03*
Y651956D03*
X1760121Y660756D03*
Y656356D03*
Y651956D03*
X1755121Y660756D03*
Y656356D03*
Y651956D03*
X1750121Y660756D03*
Y656356D03*
Y651956D03*
X1745121Y660756D03*
Y656356D03*
Y651956D03*
X1740121Y660756D03*
Y656356D03*
Y651956D03*
X1735121Y660756D03*
Y656356D03*
Y651956D03*
X1730121Y660756D03*
Y656356D03*
X1770121D03*
X1730121Y651956D03*
X1817921Y-40764D03*
X1832921Y-45764D03*
Y-54764D03*
X1827921D03*
X1822921D03*
X1817921D03*
X1812921D03*
X1807921D03*
X1802921D03*
X1797921D03*
X1792921D03*
X1787921D03*
X1782921D03*
X1777921D03*
X1832921Y-50764D03*
X1827921D03*
X1822921D03*
X1817921D03*
X1812921D03*
X1807921D03*
X1802921D03*
X1797921D03*
X1792921D03*
X1787921D03*
X1782921Y-40764D03*
X1792921D03*
X1802921D03*
X1807921D03*
X1822921D03*
X1827921D03*
X1832921D03*
X1812921D03*
X1797921D03*
X1777921Y-45764D03*
X1782921D03*
X1787921D03*
X1792921D03*
X1797921D03*
X1802921D03*
X1807921D03*
X1812921D03*
X1817921D03*
X1822921D03*
X1787921Y-40764D03*
X1832921Y-35764D03*
Y-58764D03*
X1827921Y-35764D03*
Y-58764D03*
X1822921Y-35764D03*
Y-58764D03*
X1817921Y-35764D03*
Y-58764D03*
X1812921Y-35764D03*
Y-58764D03*
X1807921Y-35764D03*
Y-58764D03*
X1802921Y-35764D03*
Y-58764D03*
X1797921Y-35764D03*
Y-58764D03*
X1792921Y-35764D03*
Y-58764D03*
X1787921Y-35764D03*
Y-58764D03*
X1782921Y-35764D03*
Y-58764D03*
X1777921Y-35764D03*
Y-58764D03*
X1782921Y-50764D03*
X1777921D03*
Y-40764D03*
X1827921Y-45764D03*
X1835121Y21532D03*
X1832071D03*
X1832771Y26818D03*
X1835921D03*
X1811967Y92168D03*
X1809267Y89468D03*
X1811967D03*
X1825930Y52900D03*
X1824410Y58030D03*
X1824350Y55180D03*
X1821270Y69470D03*
X1824180Y69460D03*
X1794992Y61342D03*
X1797664Y61334D03*
X1797645Y64153D03*
X1792382Y61363D03*
X1792363Y64182D03*
X1794973Y64161D03*
X1807891Y62180D03*
X1810563Y62172D03*
X1810693Y59493D03*
X1808021Y59501D03*
X1805411Y59522D03*
X1813393Y59493D03*
X1813363Y62172D03*
X1810578Y56866D03*
X1805282Y56880D03*
X1807916Y56895D03*
X1813278Y56866D03*
X1805281Y62201D03*
X1835714Y75029D03*
X1826900Y56500D03*
X1823830Y60700D03*
X1811967Y86868D03*
X1809267D03*
X1814667D03*
Y89468D03*
Y92168D03*
Y94868D03*
X1811967D03*
X1809267D03*
Y92168D03*
X1834059Y70501D03*
X1831460Y70600D03*
X1824060Y72460D03*
X1821070Y72480D03*
X1831460Y73300D03*
X1823155Y77329D03*
X1823188Y79943D03*
X1820488D03*
X1820455Y77329D03*
X1831148Y144592D03*
X1836200Y153424D03*
X1833000D03*
X1833600Y145900D03*
X1828390Y165600D03*
X1832000Y165800D03*
X1793205Y165531D03*
X1793268Y162774D03*
X1780121Y643156D03*
X1780106Y638753D03*
X1780121Y647556D03*
X1785121Y643156D03*
X1790121D03*
X1835121Y647556D03*
X1835106Y638753D03*
X1835121Y643156D03*
X1830121Y647556D03*
X1830106Y638753D03*
X1830121Y643156D03*
X1825121Y647556D03*
X1825106Y638753D03*
X1825121Y643156D03*
X1820121Y647556D03*
X1820106Y638753D03*
X1820121Y643156D03*
X1815121Y647556D03*
X1815106Y638753D03*
X1815121Y643156D03*
X1810121Y647556D03*
X1810106Y638753D03*
X1810121Y643156D03*
X1805121Y647556D03*
X1805106Y638753D03*
X1805121Y643156D03*
X1800121Y647556D03*
X1800106Y638753D03*
X1800121Y643156D03*
X1795121Y647556D03*
X1795106Y638753D03*
X1795121Y643156D03*
X1790121Y647556D03*
X1790106Y638753D03*
X1785121Y647556D03*
X1785106Y638753D03*
X1800121Y656356D03*
X1780121Y651956D03*
Y656356D03*
Y660756D03*
X1835121D03*
Y656356D03*
Y651956D03*
X1830121Y660756D03*
Y656356D03*
Y651956D03*
X1825121Y660756D03*
Y656356D03*
Y651956D03*
X1820121Y660756D03*
Y656356D03*
Y651956D03*
X1815121Y660756D03*
Y656356D03*
Y651956D03*
X1810121Y660756D03*
Y656356D03*
Y651956D03*
X1805121Y660756D03*
Y656356D03*
Y651956D03*
X1800121Y660756D03*
Y651956D03*
X1795121Y660756D03*
Y656356D03*
Y651956D03*
X1790121Y660756D03*
Y656356D03*
Y651956D03*
X1785121Y660756D03*
Y656356D03*
Y651956D03*
X1857921Y-45764D03*
X1837921D03*
X1897921D03*
X1892921D03*
X1887921D03*
X1882921D03*
X1877921D03*
X1872921D03*
X1867921D03*
X1862921D03*
X1842921Y-54764D03*
X1852921Y-45764D03*
X1847921D03*
X1842921D03*
X1897921Y-54764D03*
X1892921D03*
X1887921D03*
X1882921D03*
X1877921D03*
X1872921D03*
X1867921D03*
X1862921D03*
X1857921D03*
X1852921D03*
X1847921D03*
X1837921D03*
X1897921Y-50764D03*
X1892921D03*
X1887921D03*
X1882921D03*
X1877921D03*
X1872921D03*
X1867921D03*
X1862921D03*
X1857921D03*
X1852921D03*
X1847921D03*
X1842921D03*
X1837921D03*
X1892921Y-40764D03*
X1897921D03*
X1877921D03*
X1882921D03*
X1887921D03*
X1857921D03*
X1862921D03*
X1867921D03*
X1872921D03*
X1837921D03*
X1842921D03*
X1847921D03*
X1852921D03*
Y-35764D03*
Y-58764D03*
X1847921Y-35764D03*
Y-58764D03*
X1842921Y-35764D03*
Y-58764D03*
X1837921Y-35764D03*
Y-58764D03*
X1862921D03*
X1857921Y-35764D03*
Y-58764D03*
X1882921D03*
X1877921Y-35764D03*
Y-58764D03*
X1872921Y-35764D03*
Y-58764D03*
X1867921Y-35764D03*
Y-58764D03*
X1862921Y-35764D03*
X1897921D03*
Y-58764D03*
X1892921Y-35764D03*
Y-58764D03*
X1887921Y-35764D03*
Y-58764D03*
X1882921Y-35764D03*
X1838700Y26638D03*
X1838100Y21500D03*
X1847797Y26331D03*
X1847564Y21636D03*
X1862636Y26780D03*
X1851040Y24130D03*
X1855836Y21118D03*
X1852236D03*
X1859436D03*
X1862936D03*
X1865450Y22000D03*
X1860981Y23894D03*
X1857381D03*
X1853781D03*
X1864020Y24470D03*
X1851936Y26780D03*
X1859036D03*
X1855436D03*
X1844732Y-7874D03*
X1851030Y1139D03*
Y-16889D03*
X1858880Y2178D03*
X1858879Y-17927D03*
X1868132Y5626D03*
Y-21374D03*
X1877691Y1668D03*
X1877683Y-17425D03*
X1881632Y-7874D03*
X1837077Y77429D03*
X1837129Y72526D03*
X1837161Y69926D03*
X1838342Y75014D03*
X1846675Y67362D03*
X1844025D03*
X1849325D03*
X1839985Y77522D03*
X1842783Y77599D03*
X1842515Y70042D03*
X1839865D03*
X1845165D03*
X1842515Y72692D03*
X1839865D03*
X1844048Y75184D03*
X1846667Y75106D03*
X1841250Y75107D03*
X1845165Y72692D03*
X1847654Y164624D03*
X1852654D03*
X1883723Y263029D03*
Y260029D03*
X1880633Y260109D03*
Y263109D03*
X1886200Y454280D03*
X1882669Y454368D03*
X1886330Y448010D03*
X1892118Y454383D03*
X1888968D03*
X1888976Y448054D03*
X1892126D03*
X1895275D03*
X1895121Y647556D03*
X1895106Y638753D03*
X1895121Y643156D03*
X1890121Y647556D03*
X1890106Y638753D03*
X1890121Y643156D03*
X1885121Y647556D03*
X1885106Y638753D03*
X1885121Y643156D03*
X1880121Y647556D03*
X1880106Y638753D03*
X1880121Y643156D03*
X1875121Y647556D03*
X1875106Y638753D03*
X1875121Y643156D03*
X1870121Y647556D03*
X1870106Y638753D03*
X1870121Y643156D03*
X1865121Y647556D03*
X1865106Y638753D03*
X1865121Y643156D03*
X1860121Y647556D03*
X1860106Y638753D03*
X1860121Y643156D03*
X1855121Y647556D03*
X1855106Y638753D03*
X1855121Y643156D03*
X1850121Y647556D03*
X1850106Y638753D03*
X1850121Y643156D03*
X1845121Y647556D03*
X1845106Y638753D03*
X1845121Y643156D03*
X1840121Y647556D03*
X1840106Y638753D03*
X1840121Y643156D03*
X1844732Y610630D03*
X1851030Y619643D03*
Y601615D03*
X1858880Y620682D03*
X1858879Y600577D03*
X1868132Y624130D03*
Y597130D03*
X1877691Y620172D03*
X1877683Y601079D03*
X1881632Y610630D03*
X1895121Y660756D03*
Y656356D03*
Y651956D03*
X1890121Y660756D03*
Y656356D03*
Y651956D03*
X1885121Y660756D03*
Y656356D03*
Y651956D03*
X1880121Y660756D03*
Y656356D03*
Y651956D03*
X1875121Y660756D03*
Y656356D03*
Y651956D03*
X1870121Y660756D03*
Y656356D03*
Y651956D03*
X1865121Y660756D03*
Y656356D03*
Y651956D03*
X1860121Y660756D03*
Y656356D03*
Y651956D03*
X1855121Y660756D03*
Y656356D03*
Y651956D03*
X1850121Y660756D03*
Y656356D03*
Y651956D03*
X1845121Y660756D03*
Y656356D03*
Y651956D03*
X1840121Y660756D03*
Y656356D03*
Y651956D03*
X1927921Y-40764D03*
X1947921Y-45764D03*
X1942921D03*
X1937921D03*
X1932921D03*
X1927921D03*
X1922921D03*
X1917921D03*
X1912921D03*
X1907921D03*
X1902921D03*
X1927921Y-50764D03*
X1932921D03*
Y-40764D03*
X1937921D03*
X1942921D03*
X1947921D03*
X1907921Y-50764D03*
X1902921D03*
X1922921Y-40764D03*
X1917921D03*
X1912921D03*
X1907921D03*
X1902921D03*
X1922921Y-54764D03*
X1917921D03*
X1912921D03*
X1907921D03*
X1902921D03*
X1927921D03*
X1932921D03*
X1937921D03*
X1942921D03*
X1947921D03*
X1952921D03*
X1957921D03*
Y-50764D03*
X1952921D03*
X1947921D03*
X1942921D03*
X1937921D03*
X1922921D03*
X1917921D03*
X1912921D03*
X1957921Y-35764D03*
Y-58764D03*
X1952921Y-35764D03*
Y-58764D03*
X1947921Y-35764D03*
Y-58764D03*
X1942921Y-35764D03*
Y-58764D03*
X1937921Y-35764D03*
Y-58764D03*
X1932921Y-35764D03*
Y-58764D03*
X1927921Y-35764D03*
Y-58764D03*
X1922921Y-35764D03*
Y-58764D03*
X1917921Y-35764D03*
Y-58764D03*
X1912921Y-35764D03*
Y-58764D03*
X1907921Y-35764D03*
Y-58764D03*
X1902921Y-35764D03*
Y-58764D03*
X1938150Y70447D03*
X1937950Y73247D03*
X1940750Y73347D03*
X1929961Y73247D03*
X1935350D03*
X1932730Y73310D03*
X1942390Y76040D03*
X1943550Y73347D03*
X1946350Y73447D03*
X1948951Y73448D03*
X1945020Y76060D03*
X1954271Y80449D03*
X1936706Y75987D03*
X1939470Y76000D03*
X1930150Y70447D03*
X1932950D03*
X1935550D03*
X1940950Y70547D03*
X1943750D03*
X1907385Y93926D03*
X1904678Y93845D03*
X1907428Y91133D03*
X1904742Y96552D03*
X1907448Y96615D03*
X1908400Y101010D03*
X1937100Y146900D03*
X1940847Y227984D03*
X1938127Y228016D03*
X1910153Y226090D03*
X1910219Y223358D03*
X1914037Y243646D03*
X1917298Y466999D03*
X1914173Y467000D03*
X1910999D03*
X1960106Y638753D03*
X1955106D03*
X1950106D03*
X1945121Y647556D03*
Y643156D03*
X1945106Y638753D03*
X1940121Y647556D03*
Y643156D03*
X1940106Y638753D03*
X1935121Y647556D03*
Y643156D03*
X1935106Y638753D03*
X1930106D03*
X1925106D03*
X1920121Y647556D03*
X1910121Y643156D03*
X1910106Y638753D03*
X1905121Y647556D03*
Y643156D03*
X1905106Y638753D03*
X1900121Y647556D03*
X1900106Y638753D03*
X1900121Y643156D03*
X1920106Y638753D03*
X1915121Y647556D03*
X1920121Y643156D03*
X1910121Y647556D03*
X1915106Y638753D03*
X1915121Y643156D03*
X1960121Y656356D03*
Y660756D03*
X1955121Y656356D03*
Y660756D03*
X1950121Y651956D03*
Y656356D03*
Y660756D03*
X1945121Y651956D03*
Y656356D03*
Y660756D03*
X1940121Y651956D03*
Y656356D03*
Y660756D03*
X1935121Y651956D03*
Y656356D03*
Y660756D03*
X1930121Y651956D03*
Y656356D03*
Y660756D03*
X1925121Y651956D03*
Y656356D03*
Y660756D03*
X1920121Y651956D03*
Y656356D03*
X1905121Y651956D03*
Y656356D03*
Y660756D03*
X1900121D03*
Y656356D03*
Y651956D03*
X1915121D03*
Y656356D03*
Y660756D03*
X1920121D03*
X1910121D03*
Y656356D03*
Y651956D03*
X1967921Y-45764D03*
X1962921D03*
Y-40764D03*
X1967921D03*
Y-54764D03*
X1962921D03*
X1967921Y-50764D03*
X1962921D03*
X1967921Y-35764D03*
Y-58764D03*
X1962921Y-35764D03*
Y-58764D03*
X1969500Y229600D03*
X1966300D03*
X1970121Y647556D03*
Y643156D03*
X1970106Y638753D03*
X1965121Y647556D03*
Y643156D03*
X1965106Y638753D03*
X1970121Y651956D03*
Y656356D03*
Y660756D03*
X1965121Y651956D03*
Y656356D03*
Y660756D03*
X2088977Y1711752D03*
G54D20*
X3937Y204370D03*
X-3937D03*
X-11811D03*
X35433D03*
X27559D03*
X19685D03*
X3937Y227992D03*
X-3937D03*
X-11811D03*
X35433D03*
X27559D03*
X19685D03*
X3937Y313504D03*
X-3937D03*
X-11811D03*
X3937Y337126D03*
X-3937D03*
X-11811D03*
X35433D03*
X27559D03*
X19685D03*
X35433Y313504D03*
X27559D03*
X19685D03*
X2088977Y1375752D03*
G54D11*
X0Y0D03*
X2088977Y770952D03*
G54D30*
X95275Y217545D03*
X91626Y215364D03*
X85156Y212774D03*
X89386Y212744D03*
X87416Y215504D03*
X87542Y210043D03*
X83366Y215624D03*
X95140Y220946D03*
X91809Y221009D03*
X88447Y221136D03*
X85188Y221341D03*
X72074Y243282D03*
X65180Y243368D03*
X61800Y243400D03*
X68498Y243368D03*
X49560Y649770D03*
Y644670D03*
X54360D03*
X49560Y649570D03*
Y644670D03*
X54360D03*
X49560Y654670D03*
X54360D03*
X49560D03*
X54360D03*
X214820Y649570D03*
Y644670D03*
X210020D03*
X214820Y649770D03*
Y644670D03*
X210020D03*
X214820Y654670D03*
X210020D03*
X214820D03*
X210020D03*
X238282Y649670D03*
Y644770D03*
X243082D03*
X238282Y649870D03*
Y644770D03*
X243082D03*
X238282Y654770D03*
X243082D03*
X238282D03*
X243082D03*
X402404Y649650D03*
Y644550D03*
X397604D03*
X402404Y649450D03*
Y644550D03*
X397604D03*
X402404Y654550D03*
X397604D03*
X402404D03*
X397604D03*
X425750Y649400D03*
Y644500D03*
X430550D03*
X425750Y649600D03*
Y644500D03*
X430550D03*
X425750Y654500D03*
X430550D03*
X425750D03*
X430550D03*
X589871Y649379D03*
Y644279D03*
X585071D03*
X589872Y649180D03*
Y644280D03*
X585072D03*
X589871Y654279D03*
X585071D03*
X589872Y654280D03*
X585072D03*
X613298Y649331D03*
Y644231D03*
X618098D03*
X613298Y649131D03*
Y644231D03*
X618098D03*
X613298Y654231D03*
X618098D03*
X613298D03*
X618098D03*
X905515Y649159D03*
Y644259D03*
X900715D03*
X905515Y649359D03*
Y644259D03*
X900715D03*
X905515Y654259D03*
X900715D03*
X905515D03*
X900715D03*
X928952Y649120D03*
Y644220D03*
X933752D03*
X928952Y649320D03*
Y644220D03*
X933752D03*
X928952Y654220D03*
X933752D03*
X928952D03*
X933752D03*
X1219041Y649348D03*
Y644248D03*
X1214241D03*
X1219041Y649148D03*
Y644248D03*
X1214241D03*
X1219041Y654248D03*
X1214241D03*
X1219041D03*
X1214241D03*
X1242450Y649150D03*
Y644250D03*
X1247250D03*
X1242450Y649350D03*
Y644250D03*
X1247250D03*
X1242450Y654250D03*
X1247250D03*
X1242450D03*
X1247250D03*
X1527739Y644278D03*
D03*
Y654278D03*
D03*
X1532539Y649378D03*
Y644278D03*
Y649178D03*
Y644278D03*
Y654278D03*
D03*
X2088977Y1577352D03*
G54D12*
X-20700Y31400D03*
Y25200D03*
Y22300D03*
Y28100D03*
X-20600Y41200D03*
X-20526Y44263D03*
X-16602Y81858D03*
Y79358D03*
X-20500Y60300D03*
Y57300D03*
X-20700Y48800D03*
X-20726Y37463D03*
X-20800Y34400D03*
X-20500Y54300D03*
Y51300D03*
X-19210Y162529D03*
X-15768Y161922D03*
X-18000Y247400D03*
X-15000D03*
X-18000Y262700D03*
X-15000D03*
X-17014Y455604D03*
X-14800Y526100D03*
X-16700Y497400D03*
X-17200Y510800D03*
X-17302Y506798D03*
X-19802Y476738D03*
X-19783Y481286D03*
X-18160Y522609D03*
X-16186Y519304D03*
X-14690Y471140D03*
X-16726Y503651D03*
X-17084Y467626D03*
X-16766Y500106D03*
X-14971Y540000D03*
X-17300Y530800D03*
X-17500Y574000D03*
X-17397Y564242D03*
X30600Y-12000D03*
X22499Y-19381D03*
X19924Y-18875D03*
X19964Y18793D03*
X16550Y18300D03*
X25060Y16214D03*
X25838Y-20458D03*
X25827Y-16958D03*
X38227Y-20485D03*
X42520Y-16896D03*
X41677Y-14390D03*
X602Y30502D03*
X2871Y22791D03*
X-10850Y30800D03*
X34719Y19455D03*
X8660Y27274D03*
X16400Y24744D03*
X10600Y25100D03*
X1068Y24831D03*
X27102Y25383D03*
X40530Y20220D03*
X43960Y20572D03*
X39530Y5205D03*
X45670Y5185D03*
X33370D03*
X45429Y-4669D03*
X33628Y131D03*
X40994Y-7148D03*
X45700Y40D03*
X11539Y31427D03*
X27200Y30600D03*
X27239Y28027D03*
X25600Y32500D03*
X11600Y33944D03*
X37739Y19501D03*
X13716Y24861D03*
X2934Y26933D03*
X23728Y18731D03*
X26760Y49595D03*
X-8610Y59810D03*
X-1750Y43320D03*
X-1920Y47290D03*
X27800Y86900D03*
X22100Y56400D03*
X6500Y84400D03*
X6600Y87900D03*
X27800Y89900D03*
Y83900D03*
X9425Y88067D03*
X11925D03*
X30400Y89800D03*
Y86800D03*
Y83800D03*
X8700Y49700D03*
X-1470Y63910D03*
X1863Y59426D03*
X1572Y38307D03*
X14025Y56211D03*
X-3560Y34620D03*
X-13610Y64360D03*
X-9987Y50899D03*
X-7050Y50900D03*
X-10470Y64450D03*
X-8370Y62600D03*
X-6010Y61030D03*
X-9390Y67410D03*
X8988Y58267D03*
X3600Y36200D03*
X16625Y56211D03*
X3100Y65900D03*
X10925Y56167D03*
X27904Y56294D03*
X30686Y79943D03*
X23530Y94840D03*
X11030D03*
X13530D03*
X16030D03*
X18530D03*
X22380Y92670D03*
X21030Y94840D03*
X2380Y92670D03*
X4880D03*
X7380D03*
X9880D03*
X12380D03*
X14880D03*
X17380D03*
X19880D03*
X3530Y94840D03*
X6030D03*
X8530D03*
X-1000Y81500D03*
X24880Y92670D03*
X25870Y80880D03*
X28294Y80889D03*
X32500Y81791D03*
X35650Y91150D03*
X34000Y93350D03*
X5500Y77444D03*
X5600Y80444D03*
X11625Y81267D03*
X9125D03*
X-8562Y81858D03*
Y79358D03*
X-14102Y81858D03*
Y79358D03*
X-5912Y84258D03*
X-8812Y84308D03*
X-5930Y79358D03*
X-5860Y81858D03*
X-11452Y79308D03*
Y81808D03*
X9225Y84467D03*
X11725D03*
X25100Y56300D03*
X-1190Y53240D03*
X11200Y49600D03*
X14010Y49570D03*
X11925Y74867D03*
X11864Y71294D03*
X11539Y39927D03*
X11500Y43400D03*
X11539Y47127D03*
X25886Y71467D03*
X25925Y75867D03*
X26185Y67017D03*
X27488Y64671D03*
X11925Y65311D03*
X27625Y73967D03*
X27525Y69367D03*
X11925Y67811D03*
X11864Y62794D03*
X24064Y61894D03*
X15111Y62553D03*
X27564Y61894D03*
X11600Y36444D03*
X25900Y40300D03*
X27564Y59394D03*
X24064D03*
X25700Y36200D03*
X27300Y34300D03*
Y38300D03*
X27208Y42313D03*
X27239Y47027D03*
X25700Y44400D03*
X27525Y77867D03*
X11864Y78494D03*
X1382Y68100D03*
X1826Y56447D03*
X44200Y139400D03*
X44300Y144800D03*
X44200Y130700D03*
Y116800D03*
X44100Y97800D03*
X44200Y111500D03*
X44300Y102700D03*
Y125600D03*
X39109Y154901D03*
X44600Y154100D03*
X37037Y138425D03*
X46900Y139750D03*
X47309Y154356D03*
X46900Y144750D03*
Y130750D03*
Y116750D03*
Y97750D03*
Y102750D03*
Y111750D03*
Y125750D03*
X-12861Y163165D03*
X5120Y276058D03*
X2269Y273532D03*
X19904Y254162D03*
X41000Y265350D03*
X37000D03*
X41000Y274647D03*
X37000Y275000D03*
X44310Y268160D03*
X33490Y267900D03*
X3806Y302347D03*
X1500Y295000D03*
X7995Y285385D03*
X6806Y302347D03*
X47100Y327000D03*
X2450Y460000D03*
X32450Y454050D03*
X35100Y453900D03*
X35900Y423500D03*
X37550Y425400D03*
X43550Y431300D03*
X40965Y429434D03*
X20075Y424850D03*
X12025Y427900D03*
Y424850D03*
X17025D03*
X7025Y427900D03*
X2025D03*
Y424850D03*
X7025D03*
X21397Y439354D03*
Y444354D03*
X24447Y439354D03*
Y444354D03*
X10786Y441785D03*
X15786D03*
X18836D03*
X7736D03*
X10365Y461602D03*
X-6100Y464840D03*
X11100Y446200D03*
X-6104Y461190D03*
X46100Y416271D03*
Y413520D03*
X5000Y469000D03*
X2350Y469650D03*
X10443Y490649D03*
X40132Y499800D03*
X-6712Y515731D03*
X2160Y479000D03*
X-6676Y501800D03*
X44050Y504383D03*
X-9900Y486400D03*
X-13500D03*
X17000Y475500D03*
X-6650Y487800D03*
X-14190Y473840D03*
X-5690Y467840D03*
X14500Y475500D03*
X11972Y475417D03*
X5100Y478330D03*
X-11490Y473840D03*
X-2430Y524340D03*
X-4350Y482100D03*
X2589Y481983D03*
X-900Y482300D03*
X22491Y500618D03*
X24400Y519500D03*
X280Y524350D03*
X-9600Y526100D03*
X46507Y523953D03*
X40185Y482918D03*
X37568Y482836D03*
X34300Y482890D03*
X31477Y482788D03*
X26780Y488910D03*
X41993Y523425D03*
X37000Y511200D03*
X39200Y509500D03*
X40111Y520623D03*
X31800Y510600D03*
X38389Y523748D03*
X34300Y511000D03*
X37600Y507400D03*
X35707Y509055D03*
X21000Y495800D03*
X6748Y517021D03*
X3354Y517143D03*
X13300Y509600D03*
X13600Y504300D03*
X4000Y509500D03*
X2485Y498185D03*
X13700Y498500D03*
X-5680Y524570D03*
X10932Y523601D03*
X14700Y517000D03*
X-7360Y512000D03*
X-2083Y513704D03*
X-1000Y479000D03*
X5689Y481983D03*
X27280Y510420D03*
X-6200Y505400D03*
X24591Y479139D03*
X35896Y557668D03*
X33396D03*
X38696D03*
X-10200Y558200D03*
X3600Y531300D03*
X-10947Y544117D03*
X-4100Y554400D03*
X-9287Y531604D03*
X21700Y532300D03*
X19100D03*
X27000D03*
X1040Y531218D03*
X-8318Y542216D03*
X6200Y531300D03*
X-3100Y533991D03*
X21948Y566700D03*
X19448D03*
X27114Y557563D03*
X24748Y566700D03*
X0Y566800D03*
X-8200Y578600D03*
X6200Y567300D03*
X-2500Y569500D03*
X-12600Y578900D03*
X-4300Y558400D03*
X1400Y556500D03*
X-1200D03*
X3600Y567300D03*
X-9283Y571324D03*
X29400Y532300D03*
X46400Y536290D03*
Y539790D03*
X43505Y538714D03*
X43241Y535965D03*
X41500Y533800D03*
X29914Y557563D03*
X45880Y554710D03*
Y557820D03*
X46560Y581000D03*
Y577500D03*
X1439Y546583D03*
Y553783D03*
X1539Y550183D03*
X1500Y540600D03*
X15787Y551700D03*
X17100Y545400D03*
X13639Y534683D03*
Y537183D03*
X15800Y543300D03*
X15600Y539100D03*
X17139Y534683D03*
Y537183D03*
X17100Y541200D03*
X17035Y549558D03*
X15800Y547500D03*
X17139Y553683D03*
X1500Y543100D03*
X1439Y538083D03*
X15800Y579500D03*
Y575300D03*
X17108Y585513D03*
X17156Y581481D03*
X17100Y577400D03*
X17139Y573183D03*
X1500Y576600D03*
X17139Y570683D03*
X1500Y579100D03*
X1539Y586183D03*
X1439Y582583D03*
Y574083D03*
X15770Y587700D03*
X15800Y583500D03*
X-6566Y568363D03*
X-9291Y535201D03*
X27495Y591409D03*
X-900Y592500D03*
X1600D03*
X-4500Y594000D03*
X-12450Y590965D03*
X30212Y591417D03*
X35085Y591621D03*
X32609Y591538D03*
X46500Y595190D03*
X43190Y598410D03*
X43210Y595180D03*
X43190Y601910D03*
X1439Y589783D03*
X17139Y589683D03*
X77000Y25992D03*
X74000D03*
X62000Y28500D03*
X59500D03*
X65000D03*
X68000D03*
X71000D03*
X74000D03*
X77000D03*
X80000Y29000D03*
Y26000D03*
X62000D03*
X59500D03*
X65000D03*
X71000Y25992D03*
X68000D03*
X65800Y14200D03*
X59061Y476D03*
X61152Y-12752D03*
X71172Y-18486D03*
X52389Y-14258D03*
X52744Y-4368D03*
X74386Y-18439D03*
X67564Y-20745D03*
X65164Y-19456D03*
X59281Y-20641D03*
X104500Y-1850D03*
X64159Y11303D03*
X50586Y-20687D03*
X63683Y-12866D03*
X66061Y-13689D03*
X60035Y7508D03*
X106000Y17260D03*
X87091Y-16391D03*
X88777Y-10586D03*
X82300Y-16600D03*
X93500Y-18000D03*
X82013Y14129D03*
X79372Y14895D03*
X79096Y9886D03*
X79116Y12361D03*
X81669Y11693D03*
X81610Y9159D03*
X64200Y17389D03*
X99102Y-12010D03*
X105892Y8700D03*
X62076Y5575D03*
X76247Y1189D03*
X84202Y-11395D03*
X81702D03*
X79202D03*
X73611Y1158D03*
X71111D03*
X68611D03*
X73574Y-1437D03*
X71074D03*
X68574D03*
X79500Y-16600D03*
X55713Y-5095D03*
X76165Y-1415D03*
X62008Y13249D03*
X106200Y26500D03*
X61446Y18238D03*
X62536Y-2379D03*
X61994Y362D03*
X54307Y-8051D03*
X62486Y-19184D03*
X51090Y8080D03*
X53382Y-1173D03*
X60500Y79000D03*
X70500Y70500D03*
X73000D03*
X78000D03*
X75500D03*
X81000Y61500D03*
Y58500D03*
X63000Y74000D03*
X60500D03*
X63000Y76500D03*
X60500D03*
X67500Y49500D03*
X70500D03*
X73500D03*
X79500D03*
X61500Y43500D03*
X59000D03*
X64500D03*
X67500D03*
X70500D03*
X60500Y70500D03*
X63000D03*
X61500Y58500D03*
Y49500D03*
X59000Y56000D03*
X61500D03*
X59000Y49500D03*
X76500Y43500D03*
X79500Y82000D03*
Y46500D03*
X76500D03*
X73500D03*
X70500D03*
X67500D03*
X64500D03*
X59000D03*
X61500D03*
X68000Y70500D03*
X65500D03*
X79500Y43500D03*
X63000Y81500D03*
X59000Y58500D03*
X61500Y61000D03*
X59000D03*
X76500Y49500D03*
X73500Y43500D03*
X64500Y49500D03*
X79500Y79000D03*
X63000D03*
X60500Y81500D03*
X79500Y72500D03*
X102100Y73800D03*
X105892Y45290D03*
X52500Y67200D03*
Y63700D03*
Y60700D03*
Y37700D03*
Y34700D03*
Y43700D03*
Y40700D03*
Y57700D03*
X82046Y90043D03*
X100140Y83170D03*
X79725Y75993D03*
X71050Y89600D03*
X48700Y90700D03*
Y95500D03*
X61300Y89800D03*
X81861Y93392D03*
X86600Y94000D03*
X76106Y89337D03*
X108385Y84291D03*
X68725Y90900D03*
X63725D03*
X51381Y90750D03*
X105898Y55194D03*
X63737Y130602D03*
X48900Y132600D03*
X68592D03*
X85250Y127680D03*
X77730Y126860D03*
X63858Y97620D03*
X66600Y102360D03*
X62422Y109413D03*
X68000Y111000D03*
X48900Y123500D03*
X62524Y123395D03*
X68584Y123900D03*
X68654Y118680D03*
X48800Y118900D03*
X48700Y109600D03*
X48600Y104900D03*
X63582Y116409D03*
X62502Y105100D03*
X52500Y152000D03*
X60300Y151500D03*
X70800Y151400D03*
X79670Y132300D03*
X91913Y121318D03*
X77790Y121030D03*
X70980Y97166D03*
X104424Y110833D03*
X98420Y112198D03*
X48800Y137600D03*
X63878Y144800D03*
X68632Y137800D03*
X63888Y140064D03*
X87200Y152374D03*
X107254Y128041D03*
X75660Y152380D03*
X78950Y152810D03*
X51381Y104750D03*
Y109750D03*
X63098Y151473D03*
X68098D03*
X51309Y154356D03*
X51569Y132750D03*
Y118750D03*
X51381Y95750D03*
X51569Y123750D03*
Y137750D03*
X65384Y109750D03*
Y104750D03*
X65405Y118730D03*
X60831Y144750D03*
X65687Y132750D03*
X60831Y130750D03*
X60700Y116750D03*
X60801Y97750D03*
X60831Y139750D03*
X65687Y137750D03*
X60831Y125750D03*
X65405Y123730D03*
X60700Y111750D03*
X60801Y102750D03*
X91306Y157194D03*
X106698Y215610D03*
X102507Y211047D03*
X107700Y211040D03*
X100500Y188600D03*
X97500Y185700D03*
X104800D03*
X102400D03*
X99900D03*
X77650Y178150D03*
X76143Y183019D03*
X61402Y177773D03*
X97900Y194500D03*
X104820Y198800D03*
X97800Y197600D03*
X104820Y202100D03*
X90831Y184982D03*
X86952Y181721D03*
X87151Y184872D03*
X61800Y191600D03*
X99250Y160370D03*
X61356Y181000D03*
X61256Y186000D03*
X64187Y176332D03*
X104820Y195700D03*
X97800Y200800D03*
X86731Y189148D03*
X73500Y191500D03*
X107750Y238730D03*
X99500Y223800D03*
X83300Y267400D03*
X84000Y272500D03*
X79300Y272300D03*
X57500Y254100D03*
X62000Y278000D03*
X59500D03*
X108000Y249330D03*
X99758Y240300D03*
X53400Y277582D03*
Y274500D03*
X97200Y265000D03*
X91600Y278700D03*
X69125Y310625D03*
X98538Y341139D03*
X94360Y335210D03*
X94938Y323467D03*
X92086Y324258D03*
X48800Y282600D03*
Y285100D03*
X53500Y307300D03*
X48800Y292400D03*
Y289600D03*
X53400Y298100D03*
X61900Y286200D03*
X68300Y281600D03*
X70900D03*
X66300Y285850D03*
X58700Y283000D03*
X58600Y297200D03*
X58700Y299800D03*
X88600Y302997D03*
X75626Y310418D03*
X72100Y321800D03*
X79410Y331636D03*
X84000Y324542D03*
X53100Y327000D03*
X74800Y338850D03*
X69000Y338800D03*
X72000D03*
X81324Y316119D03*
X82500Y341400D03*
X65800Y338900D03*
X54400Y340300D03*
X64000Y313900D03*
Y316500D03*
X56300Y338500D03*
X79400Y325400D03*
X74887Y321780D03*
X79600Y335200D03*
X49200Y340650D03*
X87400Y337200D03*
X77600Y320800D03*
X68418Y336150D03*
X53100Y315000D03*
X59452Y338800D03*
X82150Y335800D03*
X66900Y322000D03*
X85300Y335750D03*
X69500Y322000D03*
X58400Y314600D03*
X77300Y315600D03*
X53000Y323500D03*
X52804Y333247D03*
X61300Y328600D03*
X84000Y316083D03*
X70700Y330349D03*
X103500Y302100D03*
X93500Y289000D03*
X93400Y296000D03*
X103500Y304700D03*
Y308500D03*
X102322Y295478D03*
X104600Y316602D03*
X103200Y335190D03*
X100550Y335140D03*
X103200Y330190D03*
X88840Y324740D03*
X98680Y338080D03*
X99770Y325249D03*
X71500Y298000D03*
X66000Y292700D03*
X76800Y298000D03*
X76900Y292600D03*
X66500Y303400D03*
X76800D03*
X62900Y339000D03*
X53250Y302800D03*
X48550Y301650D03*
X64700Y310525D03*
X84300Y305700D03*
Y310700D03*
X61625Y283201D03*
X72904Y284898D03*
X84300Y289000D03*
X82050Y283951D03*
X77103Y283900D03*
X84866Y294213D03*
X84300Y299000D03*
X58600Y302700D03*
X72600Y310800D03*
X77500Y312500D03*
X53025Y337475D03*
X93500Y285000D03*
X67400Y391690D03*
X67230Y397380D03*
X64725Y391645D03*
Y396645D03*
X67710Y402040D03*
X65384Y403258D03*
X93712Y380507D03*
X66350Y347950D03*
X87900Y347500D03*
X88000Y343900D03*
X51900Y351000D03*
X63800Y348600D03*
X58271Y363669D03*
X61041Y351737D03*
X49091Y351509D03*
X49017Y346509D03*
X49117Y349009D03*
X49017Y344009D03*
X55616Y368998D03*
X52000Y354500D03*
X60400Y355750D03*
X90518Y388828D03*
X54900Y389400D03*
X74800Y383114D03*
X85609Y385234D03*
X61000Y383000D03*
X57500Y388100D03*
X77300Y390600D03*
X101880Y346300D03*
X102060Y351759D03*
X101750Y360120D03*
X101965Y368296D03*
X107224Y393848D03*
X50510Y359240D03*
X47970Y359550D03*
X76500Y368300D03*
X76300Y358400D03*
X82037Y358542D03*
X70600Y368400D03*
X82100Y368300D03*
X70900Y358300D03*
X102040Y348960D03*
X101828Y371096D03*
X51923Y346164D03*
X60934Y362307D03*
X57395Y366795D03*
X55500Y371700D03*
X61914Y368731D03*
X60900Y348300D03*
X79100Y347000D03*
X49100Y354500D03*
X57800Y376100D03*
X60565Y380131D03*
X65000Y383000D03*
X74800Y379700D03*
X80200D03*
X62600Y375100D03*
X102160Y354780D03*
X101770Y363150D03*
X97472Y380934D03*
X54244Y405624D03*
X51500Y406000D03*
X57471Y410749D03*
X56383Y408163D03*
X63024Y405636D03*
X64007Y408276D03*
X61005Y429305D03*
Y424305D03*
X63630Y424280D03*
X63600Y429000D03*
X49265Y423995D03*
Y418995D03*
X51890Y424470D03*
Y418970D03*
X54662Y416478D03*
X51645Y416281D03*
X103100Y411800D03*
X65450Y475610D03*
X67477Y477940D03*
X47800Y487600D03*
X47550Y504367D03*
X66750Y521900D03*
Y519400D03*
X64503Y521054D03*
X64380Y523606D03*
Y526202D03*
X64600Y515600D03*
X66750Y516900D03*
X64600Y518100D03*
X66840Y526800D03*
Y524300D03*
X47369Y527005D03*
X55500Y521800D03*
X53000Y524300D03*
Y521800D03*
X58000D03*
X55500Y519300D03*
X52992Y516846D03*
X58000Y524300D03*
X57936Y519212D03*
X53900Y505450D03*
X57100D03*
X60300D03*
X55500Y524300D03*
X53000Y519300D03*
X53900Y502250D03*
X60300D03*
X57100D03*
X88855Y522359D03*
X86100Y505200D03*
X72603Y474072D03*
X59731Y480066D03*
X66016Y468350D03*
X89497Y479201D03*
X60300Y508650D03*
X51607Y511747D03*
X74480Y504480D03*
X79630Y504580D03*
X60000Y526500D03*
X79400Y502150D03*
X74600Y502064D03*
X77000Y502133D03*
X49800Y524300D03*
X76996Y504587D03*
X60700Y521900D03*
X57936Y516012D03*
X60202Y495342D03*
X57302Y495442D03*
X105958Y518550D03*
X91650Y522000D03*
X94998Y481612D03*
X106392Y527413D03*
X71050Y478670D03*
X92326Y480398D03*
X77960Y541468D03*
Y538468D03*
X75461Y541468D03*
Y538468D03*
X73009Y541444D03*
Y538444D03*
X62500Y535500D03*
X71500Y575000D03*
Y578000D03*
Y582000D03*
X81500Y575000D03*
X78500D03*
X81500Y578000D03*
X78500D03*
X74500Y575000D03*
Y578000D03*
Y582000D03*
X81500D03*
X78500D03*
X75500Y557500D03*
X72500Y561500D03*
Y557500D03*
X69500Y561500D03*
Y557500D03*
X75500Y561500D03*
X78500D03*
X81500D03*
Y557500D03*
X78500D03*
X66500Y554500D03*
X70521Y538403D03*
X63500Y554500D03*
X68500Y535500D03*
X65500D03*
X70498Y541394D03*
X75500Y554500D03*
X72500D03*
X69500D03*
X81500D03*
X78500D03*
X80389Y541468D03*
Y538468D03*
X66500Y557500D03*
X63500Y561500D03*
Y557500D03*
X66500Y561500D03*
X106392Y537000D03*
X105392Y574800D03*
X105412Y556580D03*
X105392Y566000D03*
X86230Y620250D03*
X89360Y620310D03*
X105000Y614533D03*
X102236Y614167D03*
X91150Y618250D03*
X93800Y618111D03*
X82459Y618932D03*
X78500Y615500D03*
X81500D03*
X75500D03*
X72500D03*
X69500D03*
X78500Y602000D03*
X72500D03*
X69500Y596000D03*
X81500Y599000D03*
X78500D03*
X81500Y596000D03*
Y612000D03*
X78500D03*
X69500Y599000D03*
Y602000D03*
X75500D03*
X78500Y596000D03*
X72500D03*
X63500Y602000D03*
Y596000D03*
X66500Y599000D03*
Y602000D03*
X63500Y599000D03*
X66500Y596000D03*
X81500Y602000D03*
X75500Y596000D03*
X72500Y599000D03*
X75500D03*
X105352Y594770D03*
X101898Y611483D03*
X91952Y620900D03*
X106192Y604600D03*
X114000Y3500D03*
X114680Y17320D03*
X150391Y14814D03*
X163427Y14714D03*
X157084Y14814D03*
X160431Y-1801D03*
X153738Y9114D03*
X150391Y-7851D03*
X163391D03*
X157084D03*
X153738Y-1751D03*
X160431Y9114D03*
X126616Y14714D03*
X136756Y16900D03*
X120273Y16839D03*
X132959Y14814D03*
X141880Y17114D03*
X147045Y9114D03*
X130163D03*
X141856Y9100D03*
X136780Y9098D03*
X123620Y9114D03*
X126580Y-7851D03*
X132959Y-7700D03*
X120273Y-9901D03*
X141893Y-9864D03*
X136806Y-9650D03*
X136780Y-1801D03*
X123620D03*
X130313Y-1751D03*
X141906Y-2050D03*
X147045Y-1751D03*
X169770Y14814D03*
X167124Y-1751D03*
X169770Y-7700D03*
X166974Y9114D03*
X114100Y6120D03*
X116300Y-9460D03*
X116692Y-1800D03*
X114050Y21320D03*
X169770Y30100D03*
X120273Y27899D03*
X141893Y27936D03*
X136806Y28150D03*
X126580Y29949D03*
X132959Y30100D03*
X157084Y29949D03*
X163391D03*
X150391D03*
X132959Y-4100D03*
X130313Y-9901D03*
X126580Y-4100D03*
X123620Y-9901D03*
X147045D03*
X141880Y-7260D03*
X136806Y-7050D03*
X136780Y-4401D03*
X132959Y33700D03*
X130313Y27899D03*
X126580Y33700D03*
X123620Y27899D03*
X147045D03*
X141880Y30540D03*
X136806Y30750D03*
X141880Y33149D03*
X136780Y33399D03*
X130313Y17157D03*
X132959Y12114D03*
X123620Y17157D03*
X126666Y12114D03*
X147045Y17157D03*
X141880Y14514D03*
X136780Y14300D03*
X141880Y11914D03*
X136780Y11700D03*
X163391Y-4100D03*
X160431Y-9901D03*
X157084Y-3700D03*
X153738Y-9901D03*
X150391Y-3700D03*
X169770Y-4100D03*
X167124Y-9901D03*
X163391Y33700D03*
X160431Y27899D03*
X153738D03*
X169770Y33700D03*
X167124Y27899D03*
X160431Y17157D03*
X163477Y12114D03*
X153738Y17157D03*
X157084Y12114D03*
X150391D03*
X167124Y17157D03*
X169770Y12114D03*
X120273Y9157D03*
X141880Y-4651D03*
X169770Y90364D03*
X166974Y84714D03*
Y73849D03*
Y46914D03*
X169770Y52614D03*
X167124Y36049D03*
X169770Y67900D03*
X157084Y67749D03*
X163391D03*
X130313Y73849D03*
X123620Y73799D03*
X141906Y73550D03*
X136780Y73799D03*
X126580Y67749D03*
X132959Y67900D03*
X141880Y54914D03*
X123620Y35983D03*
X141856Y46900D03*
X141906Y35750D03*
X136806Y65950D03*
X141893Y65736D03*
X136756Y54700D03*
X136780Y35999D03*
X130313Y35983D03*
X123620Y46914D03*
X132959Y52614D03*
X126616Y52514D03*
X147045Y46914D03*
Y36049D03*
X120273Y54839D03*
X119892Y84700D03*
X120273Y92500D03*
X126616Y90314D03*
X132959Y90414D03*
X141880Y92714D03*
X163427Y90314D03*
X157084Y90414D03*
X150391D03*
X160431Y84714D03*
X153738D03*
X136756Y92500D03*
X141856Y84700D03*
X136780Y84698D03*
X123620Y84714D03*
X147045D03*
X130163D03*
X109057Y92774D03*
X112007Y93139D03*
X116070Y35780D03*
X113100Y57770D03*
X115980Y73680D03*
X116200Y70387D03*
X114082Y55100D03*
X130163Y46914D03*
X136780Y46898D03*
X120273Y66000D03*
X147045Y73849D03*
X153738Y36049D03*
Y73849D03*
X160431Y73799D03*
X157084Y52614D03*
X160431Y35999D03*
X150391Y67749D03*
Y52614D03*
X163427Y52514D03*
X160431Y46914D03*
X153738D03*
X130313Y65699D03*
X123620D03*
X147045D03*
X136806Y68550D03*
X141880Y68340D03*
X130313Y54957D03*
X132959Y49914D03*
X123620Y54957D03*
X126666Y49914D03*
X147045Y54957D03*
X141880Y52314D03*
X136780Y52100D03*
X141880Y49714D03*
X136780Y49500D03*
X132959Y87714D03*
X126580Y71500D03*
X123620Y92757D03*
X126666Y87714D03*
X147045Y92757D03*
X141880Y70949D03*
Y87514D03*
X136780Y89900D03*
X141880Y90114D03*
X136780Y71199D03*
Y87300D03*
X132959Y71500D03*
X130313Y92757D03*
X160431Y65699D03*
X153738D03*
X167124D03*
X160431Y54957D03*
X163477Y49914D03*
X157084Y34100D03*
X153738Y54957D03*
X157084Y49914D03*
X150391Y34100D03*
Y49914D03*
X167124Y54957D03*
X169770Y49914D03*
X157084Y71900D03*
X153738Y92757D03*
X157084Y87714D03*
X150391Y71900D03*
Y87714D03*
X169770Y71500D03*
X167124Y92757D03*
X169770Y87714D03*
X163391Y71500D03*
X160431Y92757D03*
X163477Y87714D03*
X120273Y46957D03*
X117652Y132792D03*
X120117Y132865D03*
X120138Y130408D03*
X117682Y130387D03*
X112664Y128795D03*
X120533Y109535D03*
X120197Y106587D03*
X109622Y128879D03*
X156954Y192872D03*
X154454Y193021D03*
X151810Y192670D03*
X124895Y212033D03*
X127754Y211853D03*
X122542Y214019D03*
X130324Y212033D03*
X115508Y216512D03*
X153788Y187309D03*
X156928Y190053D03*
X148900Y180400D03*
X148800Y185300D03*
Y182900D03*
X148900Y190100D03*
X148800Y187700D03*
X113800Y180500D03*
X116900D03*
X124340Y197750D03*
X117600Y193805D03*
X151359Y187700D03*
X156294Y187625D03*
X151300Y190200D03*
X141263Y215216D03*
X125563Y218616D03*
X137763Y217716D03*
X128500Y218700D03*
X141263Y217716D03*
X137763Y215216D03*
X115536Y213508D03*
X154130Y190186D03*
X162788Y200650D03*
X162800Y195600D03*
X150000Y199850D03*
Y194850D03*
X117080Y225330D03*
X169150Y223600D03*
Y227600D03*
X112904Y237218D03*
X118008Y220991D03*
X116310Y222940D03*
X122820Y244133D03*
X115497Y248376D03*
X130324Y244033D03*
X122203Y246675D03*
X127500Y243500D03*
X123074Y275948D03*
X113100Y269163D03*
X115508Y280512D03*
X130324Y276033D03*
X116000Y254643D03*
X127500Y275500D03*
X117063Y257016D03*
X118008Y252991D03*
X122400Y278671D03*
X125624Y223633D03*
Y221133D03*
X141263Y234216D03*
X141200Y229600D03*
X141211Y225615D03*
X141300Y221700D03*
X139763Y231700D03*
Y227600D03*
Y223700D03*
X139582Y219800D03*
X125563Y234316D03*
X125663Y230716D03*
X125563Y227116D03*
X128200Y250700D03*
X125563Y250616D03*
X141263Y249716D03*
Y247216D03*
X137763D03*
Y249716D03*
X125624Y255633D03*
X125563Y259116D03*
X125663Y262716D03*
X125563Y266316D03*
X141300Y253700D03*
X139631Y251900D03*
X125624Y253133D03*
X137763Y279216D03*
X141263Y266216D03*
X139763Y255700D03*
Y259600D03*
X139800Y263700D03*
X141313Y257533D03*
X141263Y279216D03*
X141200Y261600D03*
X115525Y245372D03*
X115536Y277508D03*
X137300Y337200D03*
X118800Y298400D03*
X123301Y308044D03*
X110180Y280920D03*
X130324Y308033D03*
X127500Y307500D03*
X115508Y312512D03*
X129700Y340152D03*
X127000Y339000D03*
X109960Y313190D03*
X119050Y341625D03*
X116000Y286643D03*
X113000Y304000D03*
X117063Y289016D03*
X118008Y284991D03*
X122493Y310633D03*
X116000Y318643D03*
X118008Y316991D03*
X117063Y321016D03*
X113100Y333106D03*
X125624Y287633D03*
X125663Y294716D03*
X125563Y298316D03*
Y291116D03*
X128200Y282600D03*
X141263Y311216D03*
X137763D03*
X141263Y281716D03*
X139730Y284200D03*
X139763Y288200D03*
Y292000D03*
Y296000D03*
X125624Y285133D03*
X141200Y286100D03*
X141261Y290076D03*
X141300Y294000D03*
X141263Y298216D03*
X137763Y281716D03*
X125563Y282616D03*
X141211Y325515D03*
X128200Y314800D03*
X141263Y330216D03*
X139763Y327800D03*
X141300Y317500D03*
Y321500D03*
X139582Y315800D03*
X139763Y319400D03*
X125563Y323116D03*
X125663Y326716D03*
X125563Y330316D03*
Y314616D03*
X141263Y313716D03*
X137763D03*
X139763Y323600D03*
X125624Y317133D03*
Y319633D03*
X115536Y309508D03*
Y341508D03*
X109640Y376070D03*
X113500Y369000D03*
X115508Y344512D03*
X130585Y372085D03*
X127420Y371590D03*
X110670Y344500D03*
X112600Y366300D03*
X122300Y372100D03*
X119300Y400900D03*
X110397Y402603D03*
X109924Y393848D03*
X116000Y382643D03*
X122473Y374716D03*
X117063Y385016D03*
X153392Y404000D03*
X122361Y342649D03*
X116000Y350643D03*
X118008Y348991D03*
X117063Y353016D03*
X141289Y349488D03*
X128100Y346700D03*
X141300Y353300D03*
X141200Y357200D03*
X137763Y345716D03*
X141263D03*
Y343216D03*
X125624Y349133D03*
X137763Y343216D03*
X125563Y362316D03*
Y355116D03*
X125663Y358716D03*
X141263Y362216D03*
X139582Y347800D03*
X139763Y351400D03*
Y355200D03*
Y359500D03*
X125624Y351633D03*
X125563Y346616D03*
X141300Y381800D03*
X139763Y384000D03*
X125624Y381133D03*
X141263Y394216D03*
Y390416D03*
X141261Y385876D03*
X139736Y392300D03*
X125563Y378616D03*
X125663Y390716D03*
X125563Y387116D03*
Y394316D03*
X137763Y375216D03*
X141263D03*
Y377716D03*
X137763D03*
X139631Y379900D03*
X128500Y378700D03*
X139900Y388000D03*
X125624Y383633D03*
X118220Y360500D03*
X118629Y381193D03*
X109500Y370000D03*
X157862Y416012D03*
X117363Y417416D03*
X121981Y405573D03*
X110452Y407092D03*
X148666Y417397D03*
X148300Y414600D03*
X148409Y422239D03*
X119100Y411600D03*
X119016Y414201D03*
X119398Y406348D03*
X122242Y419199D03*
X123441Y421795D03*
X151909Y413267D03*
X153392Y407500D03*
X167680Y408440D03*
X167640Y404842D03*
X150650Y409860D03*
X111961Y499877D03*
X130163Y510114D03*
X147045D03*
X132959Y515814D03*
X126616Y515714D03*
X120273Y517900D03*
X136780Y510098D03*
X136756Y517900D03*
X141856Y510100D03*
X141880Y518114D03*
X123620Y510114D03*
X119892Y510100D03*
X114322Y525980D03*
X114442Y510300D03*
Y507800D03*
X116927Y517900D03*
X150391Y515814D03*
X169770Y515764D03*
X163427Y515714D03*
X166974Y510114D03*
X160431D03*
X157084Y515814D03*
X153738Y510114D03*
X112427Y497225D03*
X132959Y513114D03*
X163477D03*
X160431Y518157D03*
X130313D03*
X136780Y512700D03*
X141880Y515514D03*
X136780Y515300D03*
X141880Y512914D03*
X169770Y513114D03*
X167124Y518157D03*
X150391Y513114D03*
X147045Y518157D03*
X126666Y513114D03*
X123620Y518157D03*
X157084Y513114D03*
X153738Y518157D03*
X141893Y528936D03*
X136806Y529150D03*
X141906Y536750D03*
X132959Y553614D03*
X126616Y553514D03*
X130163Y547914D03*
X123620D03*
X136780Y547898D03*
X141856Y547900D03*
X147045Y537049D03*
Y547914D03*
X120210Y529200D03*
X130313Y537049D03*
X132959Y531100D03*
X126580Y530949D03*
X123620Y536999D03*
X136780D03*
X114792Y528600D03*
X119892Y536983D03*
Y547900D03*
X115883Y548024D03*
X123620Y574799D03*
X130313Y574849D03*
X132959Y568900D03*
X126580Y568749D03*
X141856Y585700D03*
X141906Y574550D03*
X136780Y574799D03*
Y585698D03*
X120092Y566900D03*
X136806Y566950D03*
X147045Y585714D03*
Y574849D03*
X113692Y566000D03*
X119892Y574700D03*
Y585700D03*
X114509Y575658D03*
X114150Y585850D03*
X116927Y555700D03*
X141880Y555914D03*
X120273Y555700D03*
X136756D03*
X141893Y566736D03*
X130163Y585714D03*
X123620D03*
X150391Y530949D03*
Y553614D03*
X166974Y537049D03*
X163391Y530949D03*
X160431Y536999D03*
X169770Y553564D03*
X163427Y553514D03*
X166974Y547914D03*
X160431D03*
X157084Y530949D03*
X153738Y537049D03*
X157084Y553614D03*
X153738Y547914D03*
X169770Y531100D03*
X150391Y568749D03*
X163391D03*
X160431Y585714D03*
X166974D03*
Y574849D03*
X160431Y574799D03*
X169770Y568900D03*
X157084Y568749D03*
X153738Y585714D03*
Y574849D03*
X130313Y528899D03*
X132959Y588714D03*
X160431Y528899D03*
X163391Y534700D03*
X132959D03*
X136780Y550500D03*
X141880Y553314D03*
X136780Y553100D03*
X141880Y550714D03*
X169770Y550914D03*
X167124Y555957D03*
X150391Y550914D03*
X147045Y555957D03*
X126666Y550914D03*
X123620Y555957D03*
X157084Y550914D03*
X153738Y555957D03*
X132959Y550914D03*
X163477D03*
X160431Y555957D03*
X130313D03*
X136780Y534399D03*
X141880Y531540D03*
X136806Y531750D03*
X141880Y534149D03*
X167124Y528899D03*
X169770Y534700D03*
X147045Y528899D03*
X150391Y535100D03*
X123620Y528899D03*
X126580Y534700D03*
X153738Y528899D03*
X157084Y535100D03*
X136780Y588300D03*
X141880Y588514D03*
X169770Y588714D03*
X150391D03*
X126666D03*
X157084D03*
X163477D03*
X136780Y572199D03*
X136806Y569550D03*
X141880Y571949D03*
X167124Y566699D03*
X169770Y572500D03*
X147045Y566699D03*
X150391Y572900D03*
X123620Y566699D03*
X126580Y572500D03*
X153738Y566699D03*
X157084Y572900D03*
X130313Y566699D03*
X160431D03*
X163391Y572500D03*
X132959D03*
X141880Y569340D03*
X147045Y612649D03*
X123620Y612599D03*
X136780D03*
X130313Y612649D03*
X119892Y612583D03*
X160431Y612599D03*
X166974Y612649D03*
X153738D03*
X126616Y591314D03*
X116992Y590700D03*
X132959Y591414D03*
X136756Y593500D03*
X141880Y593714D03*
X132959Y606700D03*
X126580Y606549D03*
X120092Y604900D03*
X141906Y612350D03*
X136806Y604750D03*
X141893Y604536D03*
X114792Y604600D03*
X116927Y593500D03*
X150391Y591414D03*
Y606549D03*
X163427Y591314D03*
X163391Y606549D03*
X169770Y606700D03*
Y591364D03*
X157084Y591414D03*
Y606549D03*
X130313Y604499D03*
X136780Y609999D03*
X141880Y607140D03*
Y591114D03*
X136806Y607350D03*
X136780Y590900D03*
X167124Y604499D03*
Y593757D03*
X169770Y610300D03*
X147045Y604499D03*
X150391Y610700D03*
X147045Y593757D03*
X123620Y604499D03*
X126580Y610300D03*
X123620Y593757D03*
X153738Y604499D03*
X157084Y610700D03*
X153738Y593757D03*
X160431Y604499D03*
X163391Y610300D03*
X160431Y593757D03*
X132959Y610300D03*
X130313Y593757D03*
X141880Y609749D03*
X173591Y-1801D03*
X178691Y17114D03*
X173567Y16900D03*
X178717Y-2050D03*
X183856Y-1751D03*
X173617Y-9650D03*
X178704Y-9864D03*
X178667Y9100D03*
X173591Y9098D03*
X183856Y9114D03*
X178704Y27936D03*
X173617Y28150D03*
X190549Y9114D03*
X197242D03*
X210402Y9098D03*
X210428Y-9650D03*
X193895Y-3700D03*
X190549Y-9901D03*
X187202Y-3700D03*
X183856Y-9901D03*
X206581Y-4100D03*
X203935Y-9901D03*
X200202Y-4100D03*
X197242Y-9901D03*
X173617Y-7050D03*
X210428D03*
X173591Y-4401D03*
X210402D03*
X178691Y-4651D03*
X193895Y-7851D03*
X187202D03*
X200202D03*
X210402Y-1801D03*
X190549Y-1751D03*
X197242Y-1801D03*
X203935Y-1751D03*
X206581Y-7700D03*
X203785Y9114D03*
X210378Y16900D03*
X210428Y28150D03*
X200202Y29949D03*
X187202D03*
X193895Y14814D03*
Y29949D03*
X200238Y14714D03*
X187202Y14814D03*
X206581D03*
X190549Y27899D03*
X183856D03*
X206581Y33700D03*
X203935Y27899D03*
X200202Y33700D03*
X197242Y27899D03*
X173617Y30750D03*
X210428D03*
X178691Y30540D03*
X173591Y33399D03*
X210402D03*
X178691Y33149D03*
X190549Y17157D03*
X193895Y12114D03*
X183856Y17157D03*
X187202Y12114D03*
X203935Y17157D03*
X206581Y12114D03*
X197242Y17157D03*
X200288Y12114D03*
X173591Y14300D03*
X210402D03*
X178691Y14514D03*
X173591Y11700D03*
X210402D03*
X178691Y11914D03*
X206581Y30100D03*
X224013Y-3700D03*
X220667Y-9901D03*
X215502Y-7260D03*
Y-4651D03*
X220667Y-1751D03*
X215528Y-2050D03*
X215515Y-9864D03*
X227360Y-1751D03*
X230706Y-7851D03*
X224013D03*
X215478Y9100D03*
X220667Y9114D03*
X227360D03*
X230706Y-3700D03*
X227360Y-9901D03*
X224013Y29949D03*
X230706D03*
Y14814D03*
X227360Y27899D03*
X220667D03*
X215502Y30540D03*
Y33149D03*
X227360Y17157D03*
X230706Y12114D03*
X220667Y17157D03*
X224013Y12114D03*
X215502Y14514D03*
Y11914D03*
X224013Y14814D03*
X215502Y17114D03*
X215515Y27936D03*
X178691Y-7260D03*
Y92714D03*
X173591Y84698D03*
X178667Y84700D03*
X183856Y84714D03*
X173567Y92500D03*
X183856Y36049D03*
X173591Y46898D03*
X183856Y73849D03*
X178717Y73550D03*
X173591Y73799D03*
X178691Y54914D03*
X173591Y35999D03*
X183856Y46914D03*
X178717Y35750D03*
X178667Y46900D03*
X173567Y54700D03*
X173617Y65950D03*
X178704Y65736D03*
X206581Y52614D03*
X210378Y54700D03*
X210402Y46898D03*
X193895Y67749D03*
X200202D03*
X187202D03*
X203785Y46914D03*
X190549D03*
X197242D03*
X200238Y52514D03*
X193895Y52614D03*
X187202D03*
X190549Y36049D03*
X203935D03*
X190549Y65699D03*
X183856D03*
X203935D03*
X197242D03*
X173617Y68550D03*
X210428D03*
X178691Y68340D03*
X190549Y54957D03*
X193895Y34100D03*
Y49914D03*
X183856Y54957D03*
X187202Y34100D03*
Y49914D03*
X203935Y54957D03*
X206581Y49914D03*
X197242Y54957D03*
X200288Y49914D03*
X173591Y52100D03*
X210402D03*
X178691Y52314D03*
X173591Y49500D03*
X210402D03*
X178691Y49714D03*
X197242Y35999D03*
X206581Y67900D03*
X210428Y65950D03*
X210402Y35999D03*
X173591Y89900D03*
X210402D03*
X178691Y70949D03*
Y87514D03*
X173591Y71199D03*
Y87300D03*
X210402Y71199D03*
Y87300D03*
X178691Y90114D03*
X197242Y73799D03*
X203935Y73849D03*
X210402Y73799D03*
Y84698D03*
X210378Y92500D03*
X190549Y73849D03*
Y84714D03*
X197242D03*
X203785D03*
X193895Y90414D03*
X206581D03*
X200238Y90314D03*
X187202Y90414D03*
X193895Y71900D03*
X190549Y92757D03*
X193895Y87714D03*
X187202Y71900D03*
X183856Y92757D03*
X187202Y87714D03*
X206581Y71500D03*
X203935Y92757D03*
X206581Y87714D03*
X200202Y71500D03*
X197242Y92757D03*
X200288Y87714D03*
X215478Y46900D03*
X215502Y54914D03*
X215515Y65736D03*
X224013Y52614D03*
X220667Y46914D03*
X230706Y52614D03*
X224013Y67749D03*
X230706D03*
X227360Y46914D03*
Y65699D03*
X220667D03*
X215502Y68340D03*
X227360Y54957D03*
X230706Y34100D03*
Y49914D03*
X220667Y54957D03*
X224013Y34100D03*
Y49914D03*
X215502Y52314D03*
Y49714D03*
X227360Y36049D03*
X220667D03*
X215528Y35750D03*
X215502Y92714D03*
X230706Y71900D03*
X227360Y92757D03*
X230706Y87714D03*
X224013Y71900D03*
X220667Y92761D03*
X224013Y87714D03*
X215502Y70949D03*
Y87514D03*
Y90114D03*
X220667Y73849D03*
Y84714D03*
X227360D03*
X230706Y90414D03*
X215478Y84700D03*
X215528Y73550D03*
X227360Y73849D03*
X224013Y90414D03*
X197617Y243089D03*
X191537Y242989D03*
Y240489D03*
X197617Y240589D03*
X191537Y237989D03*
X197617Y238089D03*
X192037Y270750D03*
X194537D03*
X197037D03*
X206800Y246500D03*
X194537Y299750D03*
X197037D03*
X192037D03*
X194537Y332480D03*
X197037D03*
X192037D03*
X203947Y280933D03*
X194500Y360200D03*
X197137Y360350D03*
X191900Y360173D03*
X195200Y377800D03*
Y380300D03*
X177689Y404109D03*
X180799Y404049D03*
X174609Y404009D03*
X206600Y372400D03*
X195233Y348402D03*
X172697Y407196D03*
X197242Y510114D03*
X200238Y515714D03*
X203785Y510114D03*
X190549D03*
X187202Y515814D03*
X193895D03*
X183856Y510114D03*
X173591Y510098D03*
X173567Y517900D03*
X178691Y518114D03*
X206581Y515814D03*
X210402Y510098D03*
X210378Y517900D03*
X215502Y518114D03*
X215478Y510100D03*
X224013Y515814D03*
X220667Y510114D03*
X227360D03*
X230706Y515814D03*
X173591Y515300D03*
X200288Y513114D03*
X197242Y518157D03*
X230706Y513114D03*
X227360Y518157D03*
X206581Y513114D03*
X203935Y518157D03*
X187202Y513114D03*
X183856Y518157D03*
X193895Y513114D03*
X190549Y518157D03*
X215502Y515514D03*
X178691D03*
X210402Y512700D03*
X173591D03*
X215502Y512914D03*
X178691D03*
X210402Y515300D03*
X224013Y513114D03*
X220667Y518161D03*
X193895Y553614D03*
X200238Y553514D03*
X183856Y547914D03*
X190549D03*
X203785D03*
X197242D03*
X190549Y537049D03*
X183856D03*
X187202Y530949D03*
X193895D03*
X197242Y536999D03*
X203935Y537049D03*
X200202Y530949D03*
X206581Y553614D03*
X210402Y547898D03*
X178717Y536750D03*
X173617Y529150D03*
X173591Y536999D03*
X178704Y528936D03*
X178667Y547900D03*
X173591Y547898D03*
X206581Y531100D03*
X210402Y536999D03*
X210428Y529150D03*
X187202Y553614D03*
X173591Y553100D03*
X178691Y555914D03*
X173567Y555700D03*
X210378D03*
X203935Y574849D03*
X200202Y568749D03*
X197242Y574799D03*
X190549Y585714D03*
X183856D03*
X187202Y568749D03*
X193895D03*
X190549Y574849D03*
X183856D03*
X210402Y585698D03*
X206581Y568900D03*
X210428Y566950D03*
X210402Y574799D03*
X178667Y585700D03*
X178717Y574550D03*
X173591Y574799D03*
Y585698D03*
X173617Y566950D03*
X178704Y566736D03*
X197242Y585714D03*
X203785D03*
X173617Y569550D03*
X215515Y528936D03*
X215528Y536750D03*
X215478Y547900D03*
X224013Y530949D03*
X220667Y537049D03*
X230706Y530949D03*
X227360Y537049D03*
X230706Y553614D03*
X220667Y547914D03*
X227360D03*
X224013Y553614D03*
X215502Y555914D03*
X220667Y585714D03*
X215528Y574550D03*
X215478Y585700D03*
X215515Y566736D03*
X224013Y568749D03*
X220667Y574849D03*
X230706Y568749D03*
X227360Y574849D03*
Y585714D03*
X173617Y531750D03*
X224013Y535100D03*
X197242Y528899D03*
X200202Y534700D03*
X227360Y528899D03*
X230706Y535100D03*
X203935Y528899D03*
X206581Y534700D03*
X183856Y528899D03*
X187202Y535100D03*
X190549Y528899D03*
X193895Y535100D03*
X173591Y550500D03*
X215502Y550714D03*
X178691D03*
X210402Y553100D03*
X224013Y550914D03*
X220667Y555961D03*
X200288Y550914D03*
X197242Y555957D03*
X230706Y550914D03*
X227360Y555957D03*
X206581Y550914D03*
X203935Y555957D03*
X187202Y550914D03*
X183856Y555957D03*
X193895Y550914D03*
X190549Y555957D03*
X210402Y534399D03*
X215502Y534149D03*
X178691D03*
X210428Y531750D03*
X220667Y528899D03*
X215502Y553314D03*
X178691D03*
X210402Y550500D03*
X220667Y566699D03*
X224013Y572900D03*
X197242Y566699D03*
X200202Y572500D03*
X227360Y566699D03*
X230706Y572900D03*
X203935Y566699D03*
X206581Y572500D03*
X183856Y566699D03*
X187202Y572900D03*
X190549Y566699D03*
X193895Y572900D03*
X210402Y588300D03*
X173591D03*
X215502Y588514D03*
X178691D03*
X224013Y588714D03*
X200288D03*
X230706D03*
X206581D03*
X187202D03*
X193895D03*
X215502Y569340D03*
X178691D03*
X210402Y572199D03*
X173591D03*
X210428Y569550D03*
X215502Y531540D03*
X178691D03*
X173591Y534399D03*
X215502Y571949D03*
X178691D03*
X227360Y612649D03*
X220667D03*
X203935D03*
X197242Y612599D03*
X190549Y612649D03*
X183856D03*
X210402Y612599D03*
X173591D03*
X187202Y591414D03*
X193895D03*
X187202Y606549D03*
X193895D03*
X200202D03*
X210428Y604750D03*
X206581Y606700D03*
X210378Y593500D03*
X206581Y591414D03*
X178717Y612350D03*
X173617Y604750D03*
X178704Y604536D03*
X173567Y593500D03*
X178691Y593714D03*
X200238Y591314D03*
X224013Y606549D03*
X230706D03*
Y591414D03*
X215515Y604536D03*
X215528Y612350D03*
X215502Y593714D03*
X224013Y591414D03*
X173617Y607350D03*
X173591Y590900D03*
X215502Y607140D03*
Y591114D03*
X178691D03*
X173591Y609999D03*
X215502Y609749D03*
X178691D03*
X210402Y590900D03*
X210428Y607350D03*
X220667Y604499D03*
X224013Y610700D03*
X220667Y593761D03*
X197242Y604499D03*
Y593757D03*
X200202Y610300D03*
X227360Y604499D03*
X230706Y610700D03*
X227360Y593757D03*
X203935Y604499D03*
X206581Y610300D03*
X203935Y593757D03*
X183856Y604499D03*
Y593757D03*
X187202Y610700D03*
X190549Y604499D03*
Y593757D03*
X193895Y610700D03*
X178691Y607140D03*
X210402Y609999D03*
X243392Y-4100D03*
X240746Y-9901D03*
X267517Y-3700D03*
X264171Y-9901D03*
X237013Y-4100D03*
X234053Y-9901D03*
X260824Y-3700D03*
X257478Y-9901D03*
X252313Y-7260D03*
X247213Y-4401D03*
X252313Y-4651D03*
X270864Y-9901D03*
Y-1801D03*
X247213D03*
X240746Y-1751D03*
X264171D03*
X252339Y-2050D03*
X234053Y-1801D03*
X257478Y-1751D03*
X243392Y-7700D03*
X260824Y-7851D03*
X252326Y-9864D03*
X237013Y-7851D03*
X247239Y-9650D03*
X267517Y-7851D03*
X252289Y9100D03*
X264171Y9114D03*
X240596D03*
X247213Y9098D03*
X270864Y9114D03*
X234053D03*
X257478D03*
X267517Y14814D03*
Y29949D03*
X247189Y16900D03*
X252326Y27936D03*
X243392Y30100D03*
X247239Y28150D03*
X260824Y29949D03*
X237013D03*
X243392Y33700D03*
X240746Y27899D03*
X264171D03*
X237013Y33700D03*
X234053Y27899D03*
X257478D03*
X247239Y30750D03*
X252313Y33149D03*
X247213Y33399D03*
X252313Y30540D03*
X270864Y27899D03*
X240746Y17157D03*
X243392Y12114D03*
X264171Y17157D03*
X267517Y12114D03*
X234053Y17157D03*
X237099Y12114D03*
X257478Y17157D03*
X260824Y12114D03*
X247213Y14300D03*
X252313Y14514D03*
X247213Y11700D03*
X252313Y11914D03*
X270864Y17157D03*
X252313Y17114D03*
X243392Y14814D03*
X260824D03*
X237049Y14714D03*
X284050Y-9650D03*
X289137Y-9864D03*
X284050Y-7050D03*
X289124Y-7260D03*
Y-4651D03*
X280203Y-4100D03*
X277557Y-9901D03*
X273824Y-4100D03*
Y-7851D03*
X280203Y-7700D03*
X289100Y9100D03*
X284024Y9098D03*
X277407Y9114D03*
X277557Y-1751D03*
X289150Y-2050D03*
X284024Y-1801D03*
X273824Y29949D03*
X273860Y14714D03*
X284000Y16900D03*
X280203Y14814D03*
Y30100D03*
X289124Y17114D03*
X284050Y28150D03*
X289137Y27936D03*
X289124Y33149D03*
X284024Y33399D03*
X280203Y33700D03*
X277557Y27899D03*
X273824Y33700D03*
X284024Y14300D03*
X289124Y14514D03*
X284024Y11700D03*
X289124Y11914D03*
X277557Y17157D03*
X280203Y12114D03*
X273910D03*
X247239Y-7050D03*
X284024Y-4401D03*
X284050Y30750D03*
X289124Y30540D03*
X247213Y46898D03*
X257478Y46914D03*
X240596D03*
X243392Y67900D03*
X267517Y67749D03*
Y52614D03*
X270864Y46914D03*
X252326Y65736D03*
X237013Y67749D03*
X260824D03*
X247239Y65950D03*
X243392Y52614D03*
X264171Y46914D03*
X247213Y35999D03*
X257478Y36049D03*
X252339Y35750D03*
X234053Y35999D03*
X240746Y36049D03*
X264171D03*
X237049Y52514D03*
X252289Y46900D03*
X240746Y65699D03*
X264171D03*
X234053D03*
X257478D03*
X247239Y68550D03*
X270864Y65699D03*
X240746Y54957D03*
X243392Y49914D03*
X264171Y54957D03*
X267517Y34100D03*
Y49914D03*
X234053Y54957D03*
X237099Y49914D03*
X257478Y54957D03*
X260824Y34100D03*
Y49914D03*
X247213Y52100D03*
X252313Y49714D03*
X247213Y49500D03*
X252313Y52314D03*
X270864Y54957D03*
X247189Y54700D03*
X252313Y54914D03*
X260824Y52614D03*
X270864Y35999D03*
X234053Y46914D03*
X247213Y73799D03*
X243392Y71500D03*
X240746Y92757D03*
X243392Y87714D03*
X267517Y71900D03*
X264171Y92757D03*
X267517Y87714D03*
X237013Y71500D03*
X234053Y92757D03*
X237099Y87714D03*
X260824Y71900D03*
X257478Y92757D03*
X260824Y87714D03*
X247213Y89900D03*
X252313Y70949D03*
Y87514D03*
X247213Y71199D03*
Y87300D03*
X252313Y90114D03*
X270864Y92757D03*
X247213Y84698D03*
X264171Y84714D03*
X252339Y73550D03*
X257478Y84714D03*
X240746Y73849D03*
X257478D03*
X234053Y73799D03*
X264171Y73849D03*
X243392Y90414D03*
X252313Y92714D03*
X237049Y90314D03*
X270864Y84714D03*
X247189Y92500D03*
X240596Y84714D03*
X234053D03*
X252289Y84700D03*
X260824Y90414D03*
X267517D03*
X270864Y73799D03*
X273824Y67749D03*
X280203Y67900D03*
X284024Y35999D03*
X277557Y36049D03*
X277407Y46914D03*
X289137Y65736D03*
X284050Y65950D03*
X284024Y46898D03*
X284000Y54700D03*
X289100Y46900D03*
X289150Y35750D03*
X289124Y54914D03*
X280203Y52614D03*
X284050Y68550D03*
X289124Y68340D03*
X277557Y65699D03*
X284024Y52100D03*
X289124Y49714D03*
X284024Y49500D03*
X289124Y52314D03*
X277557Y54957D03*
X280203Y49914D03*
X273910D03*
X284024Y89900D03*
X289124Y70949D03*
Y87514D03*
X284024Y71199D03*
Y87300D03*
X289124Y90114D03*
X280203Y71500D03*
X277557Y92757D03*
X280203Y87714D03*
X273824Y71500D03*
X273910Y87714D03*
X273860Y90314D03*
X277407Y84714D03*
X289100Y84700D03*
X284024Y84698D03*
X284000Y92500D03*
X289150Y73550D03*
X284024Y73799D03*
X289124Y92714D03*
X280203Y90414D03*
X277407Y73849D03*
X252313Y68340D03*
X240746Y112327D03*
X243392Y106934D03*
X264171Y112327D03*
X267517Y107284D03*
X234053Y112327D03*
X237099Y107284D03*
X257478Y112327D03*
X260824Y107284D03*
X247213Y110514D03*
X252313Y107655D03*
X247239Y107865D03*
X252339Y110264D03*
X270864Y112327D03*
X264171Y104284D03*
X267517Y109984D03*
X270864Y104284D03*
X257478D03*
X260824Y109984D03*
X243392Y109534D03*
X252339Y112865D03*
X247213Y113114D03*
X237049Y109884D03*
X240596Y104284D03*
X247239Y105265D03*
X252326Y105051D03*
X234053Y104284D03*
X284024Y110514D03*
X289124Y107655D03*
X284050Y107865D03*
X289150Y110264D03*
X277557Y112327D03*
X280203Y106934D03*
X273910Y107284D03*
X273860Y109884D03*
X284050Y105265D03*
X289137Y105051D03*
X289150Y112865D03*
X284024Y113114D03*
X280203Y109534D03*
X277407Y104284D03*
X271239Y211060D03*
X284759Y207159D03*
X291519D03*
X274619Y213009D03*
Y216909D03*
X277999Y211060D03*
Y214960D03*
Y203260D03*
Y207159D03*
X281379Y213009D03*
X288139Y216909D03*
X284759Y214960D03*
X281379Y216909D03*
X284759Y218860D03*
Y203260D03*
Y211060D03*
X281379Y205210D03*
X291519Y203260D03*
Y211060D03*
X288139Y213009D03*
Y205210D03*
X291519Y214960D03*
Y218860D03*
X281379Y201309D03*
X284759Y199360D03*
X291519D03*
X267859Y244209D03*
Y240309D03*
X271239Y238360D03*
X264179D03*
Y250060D03*
X264092Y222710D03*
X264179Y226660D03*
Y246160D03*
X271239D03*
Y250060D03*
Y269560D03*
Y273460D03*
Y265660D03*
X267859Y263709D03*
Y259809D03*
X264179Y265660D03*
X267859Y252009D03*
X264179Y253960D03*
Y257860D03*
X271239D03*
X267859Y255909D03*
X271239Y277360D03*
X267392Y276000D03*
X267359Y279310D03*
X267859Y271509D03*
X264179Y273460D03*
X291519Y238360D03*
X284759Y234460D03*
X288139Y232509D03*
X281379D03*
X277999Y234460D03*
X274619Y232509D03*
Y220809D03*
Y224709D03*
Y228610D03*
X277999Y230559D03*
X274619Y244209D03*
X277999Y250060D03*
X274619Y240309D03*
Y248109D03*
Y236409D03*
X291519Y246160D03*
Y250060D03*
X284759Y246160D03*
X291519Y242260D03*
X281379Y220809D03*
X284759Y226660D03*
Y230559D03*
X277999Y222760D03*
X281379Y224709D03*
X284759Y222760D03*
X277999Y238360D03*
X288139Y248109D03*
X277999Y242260D03*
X284759Y238360D03*
X281379Y248109D03*
X288139Y244209D03*
X277999Y246160D03*
X284759Y242260D03*
X288139Y236409D03*
X291519Y234460D03*
Y222760D03*
Y230559D03*
Y226660D03*
X281379Y240309D03*
Y228610D03*
X288139Y224709D03*
X281379Y252009D03*
X274619D03*
X277999Y253960D03*
X284759D03*
X291519D03*
X284759Y265660D03*
X291519D03*
Y277360D03*
X281379Y275409D03*
Y271509D03*
X284759Y277360D03*
Y273460D03*
X288139Y275409D03*
Y271509D03*
X277999Y277360D03*
X274619Y255909D03*
Y259809D03*
X277999Y269560D03*
X274619Y275409D03*
Y267609D03*
Y263709D03*
X288139Y255909D03*
X291519Y269560D03*
Y257860D03*
Y261760D03*
X281379Y259809D03*
Y267609D03*
Y255909D03*
X284759Y269560D03*
X277999Y261760D03*
X284759Y257860D03*
Y261760D03*
X281379Y263709D03*
X288139Y279310D03*
X274619D03*
X288139Y252009D03*
X281379Y279310D03*
X288139Y263709D03*
X239778Y274478D03*
X271239Y328060D03*
X267859Y333909D03*
Y341709D03*
Y330009D03*
X264179Y328060D03*
Y339760D03*
X271239Y320260D03*
Y324160D03*
X270939Y316160D03*
X267359Y318309D03*
X267859Y326110D03*
X267392Y322000D03*
X270892Y304660D03*
Y311960D03*
Y300760D03*
Y308560D03*
Y292959D03*
Y289060D03*
X271239Y281260D03*
X270892Y285500D03*
Y296860D03*
X267359Y283209D03*
X291519Y285160D03*
Y292959D03*
X284759Y285160D03*
X277999Y308560D03*
Y300760D03*
Y292959D03*
Y285160D03*
X291519Y308560D03*
X284759D03*
Y300760D03*
X291519D03*
X284759Y292959D03*
X281379Y302709D03*
X288139D03*
X291519Y304660D03*
X281379Y306609D03*
Y310509D03*
X288139Y306609D03*
Y310509D03*
X284759Y304660D03*
X281379Y287109D03*
X288139Y291009D03*
X284759Y289060D03*
Y281260D03*
X291519Y289060D03*
Y281260D03*
Y296860D03*
X288139Y298809D03*
X274619Y306609D03*
Y310509D03*
X277999Y304660D03*
X274619Y302709D03*
Y298809D03*
Y294909D03*
X277999Y289060D03*
Y281260D03*
X274619Y283209D03*
Y287109D03*
Y291009D03*
X277999Y296860D03*
X288139Y283209D03*
Y287109D03*
X281379Y298809D03*
Y294909D03*
X288139D03*
X284759Y296860D03*
X281379Y291009D03*
Y283209D03*
X291519Y316360D03*
X281379Y318309D03*
X291519Y328060D03*
X288139Y341709D03*
X274619Y330009D03*
Y326110D03*
Y322209D03*
X277999Y328060D03*
X274619Y341709D03*
X277999Y320260D03*
Y316360D03*
X274619Y333909D03*
Y337809D03*
X284759Y324160D03*
X288139Y318309D03*
X284759Y316360D03*
X281379Y337809D03*
X291519Y339760D03*
Y335860D03*
X284759Y331960D03*
X291519D03*
X281379Y326110D03*
X288139D03*
X291519Y312460D03*
X284759D03*
X277999D03*
X274619Y314409D03*
X281379D03*
X288139D03*
X274619Y318309D03*
X264179Y335860D03*
X288139Y337809D03*
X281379Y333909D03*
X277999Y331960D03*
X284759Y339760D03*
Y328060D03*
X277999Y339760D03*
X288139Y333909D03*
X267859Y337809D03*
X271239Y335860D03*
X267559Y369010D03*
X271239Y355360D03*
X267859Y349509D03*
Y353409D03*
X267559Y361209D03*
X264179Y343660D03*
Y355360D03*
X267492Y380709D03*
X271239Y390460D03*
X267859Y388509D03*
X271239Y382660D03*
X284759Y351460D03*
X281379Y345609D03*
X291519Y359260D03*
Y355360D03*
Y351460D03*
X284759Y343660D03*
X274619Y365109D03*
X277999Y363160D03*
Y367060D03*
X274619Y369010D03*
Y361209D03*
Y345609D03*
X277999Y347560D03*
X274619Y353409D03*
Y357309D03*
Y349509D03*
X277999Y343660D03*
X291519Y347560D03*
Y343660D03*
X288139Y365109D03*
X281379D03*
X284759Y363160D03*
X291519D03*
X284759Y370959D03*
X291519Y367060D03*
Y370959D03*
X288139Y361209D03*
X281379Y357309D03*
X288139Y345609D03*
Y380709D03*
Y400209D03*
X274619Y380709D03*
X277999Y394359D03*
X274619Y392410D03*
X277999Y390460D03*
Y386560D03*
X274619Y376809D03*
Y372909D03*
X291519Y374860D03*
X277999Y382660D03*
X284759Y398260D03*
X281379Y396309D03*
X291519Y398260D03*
X284759Y390460D03*
X291519D03*
X281379Y376809D03*
Y384609D03*
X284759Y382660D03*
X291519D03*
Y378760D03*
X288139Y392410D03*
X281379Y353409D03*
X288139Y384609D03*
Y357309D03*
Y396309D03*
X277999Y351460D03*
X281379Y349509D03*
X288139Y353409D03*
X291519Y386560D03*
X281379Y392410D03*
X284759Y386560D03*
X277999Y359260D03*
X288139Y349509D03*
X284759Y359260D03*
X281379Y372909D03*
X288139Y376809D03*
X277999Y370959D03*
X271239Y343660D03*
Y351460D03*
X264179D03*
X284759Y378760D03*
Y367060D03*
X277999Y378760D03*
X288139Y372909D03*
X264171Y510114D03*
X257478D03*
X260824Y515814D03*
X247213Y515300D03*
X260824Y491044D03*
X247177Y490514D03*
X252313D03*
X236892Y493400D03*
X243392Y493094D03*
X267584Y491219D03*
X271092Y495944D03*
X257392Y495800D03*
X264192D03*
X233292Y495900D03*
X239492Y498500D03*
X247177Y498514D03*
X252313D03*
X252289Y510100D03*
X267517Y515814D03*
X270864Y510114D03*
X247189Y517900D03*
X252313Y518114D03*
X247213Y510098D03*
X240596Y510114D03*
X243392Y515814D03*
X234053Y510114D03*
X237049Y515714D03*
X284024Y490644D03*
X289124D03*
X273860Y515714D03*
X277557Y495944D03*
X277407Y510114D03*
X289100Y510100D03*
X289124Y518114D03*
X284024Y510098D03*
X280203Y515814D03*
X273992Y491144D03*
X280203Y490644D03*
X284024Y498644D03*
X289124D03*
X284000Y517900D03*
X247228Y495909D03*
X289124Y493344D03*
X252313Y493214D03*
X284039Y495944D03*
X260824Y493744D03*
X257478Y498487D03*
X236892Y490800D03*
X233292Y498500D03*
X267584Y493919D03*
X264171Y498487D03*
X243392Y495694D03*
X239592Y495900D03*
X273910Y513114D03*
X270864Y518157D03*
X280203Y513114D03*
X277557Y518157D03*
X289124Y515514D03*
X252313D03*
X284024Y512700D03*
X247213D03*
X289124Y512914D03*
X252313D03*
X284024Y515300D03*
X260824Y513114D03*
X257478Y518157D03*
X237099Y513114D03*
X234053Y518157D03*
X267517Y513114D03*
X264171Y518157D03*
X243392Y513114D03*
X240746Y518157D03*
X273992Y493744D03*
X271092Y498644D03*
X280203Y493244D03*
X277557Y498644D03*
X289124Y495944D03*
X252313Y495814D03*
X284039Y493344D03*
X247228Y493209D03*
X257478Y537049D03*
X237013Y530949D03*
X252339Y536750D03*
X243392Y531100D03*
X247213Y536999D03*
X252326Y528936D03*
X240746Y537049D03*
X234053Y536999D03*
X267517Y553614D03*
X270864Y547914D03*
X267517Y530949D03*
X270864Y536999D03*
X260824Y553614D03*
X237049Y553514D03*
X243392Y553614D03*
X264171Y547914D03*
X257478D03*
X252289Y547900D03*
X240596Y547914D03*
X247213Y547898D03*
X234053Y547914D03*
X264171Y537049D03*
X260824Y530949D03*
X247189Y555700D03*
X252313Y555914D03*
X270864Y574799D03*
Y585714D03*
X267517Y568749D03*
X247239Y566950D03*
X252326Y566736D03*
X234053Y574799D03*
X240746Y574849D03*
X247213Y574799D03*
X234053Y585714D03*
X237013Y568749D03*
X264171Y585714D03*
X257478D03*
X264171Y574849D03*
X257478D03*
X260824Y568749D03*
X252339Y574550D03*
X252289Y585700D03*
X240596Y585714D03*
X247213Y585698D03*
X243392Y568900D03*
X277407Y537049D03*
X273824Y530949D03*
X273860Y553514D03*
X284024Y547898D03*
X289100Y547900D03*
X280203Y553614D03*
Y531100D03*
X284024Y536999D03*
X289137Y528936D03*
X284050Y529150D03*
X289150Y536750D03*
X277407Y547914D03*
X273824Y568749D03*
X284000Y555700D03*
X289124Y555914D03*
X280203Y568900D03*
X277407Y574849D03*
Y585714D03*
X289100Y585700D03*
X289150Y574550D03*
X284024Y574799D03*
Y585698D03*
X284050Y566950D03*
X289137Y566736D03*
X284024Y588300D03*
X247213Y553100D03*
X247239Y569550D03*
X289124Y550714D03*
X252313D03*
X284024Y553100D03*
X260824Y550914D03*
X257478Y555957D03*
X237099Y550914D03*
X234053Y555957D03*
X267517Y550914D03*
X264171Y555957D03*
X243392Y550914D03*
X240746Y555957D03*
X270864Y528899D03*
X273824Y534700D03*
X277557Y528899D03*
X280203Y534700D03*
X289124Y531540D03*
X252313D03*
X247213Y534399D03*
X289124Y534149D03*
X252313D03*
X284050Y531750D03*
X257478Y528899D03*
X260824Y535100D03*
X234053Y528899D03*
X237013Y534700D03*
X264171Y528899D03*
X267517Y535100D03*
X240746Y528899D03*
X243392Y534700D03*
X273910Y550914D03*
X270864Y555957D03*
X280203Y550914D03*
X277557Y555957D03*
X289124Y553314D03*
X252313D03*
X284024Y550500D03*
X247213D03*
X264171Y566699D03*
X267517Y572900D03*
X240746Y566699D03*
X243392Y572500D03*
X280203Y588714D03*
X247213Y588300D03*
X289124Y588514D03*
X252313D03*
X260824Y588714D03*
X237099D03*
X267517D03*
X243392D03*
X270864Y566699D03*
X273824Y572500D03*
X277557Y566699D03*
X280203Y572500D03*
X289124Y569340D03*
X284024Y572199D03*
X252313Y571949D03*
X257478Y566699D03*
X260824Y572900D03*
X234053Y566699D03*
X237013Y572500D03*
X273910Y588714D03*
X247239Y531750D03*
X284024Y534399D03*
X252313Y569340D03*
X247213Y572199D03*
X289124Y571949D03*
X284050Y569550D03*
X284024Y612599D03*
X240746Y612649D03*
X247213Y612599D03*
X234053D03*
X257478Y612649D03*
X247239Y604750D03*
X252326Y604536D03*
X260824Y606549D03*
X237013D03*
X243392Y606700D03*
X264171Y612449D03*
X252339Y612350D03*
X267517Y591414D03*
X260824D03*
X237049Y591314D03*
X247189Y593500D03*
X252313Y593714D03*
X243392Y591414D03*
X267517Y606549D03*
X270864Y612399D03*
X273824Y606549D03*
X273860Y591314D03*
X284050Y604750D03*
X289150Y612350D03*
X280203Y606700D03*
Y591414D03*
X277407Y612449D03*
X289124Y593714D03*
X284000Y593500D03*
X289137Y604536D03*
X247213Y590900D03*
X247239Y607350D03*
X277557Y604499D03*
X280203Y610300D03*
X277557Y593757D03*
X289124Y607140D03*
Y591114D03*
X252313Y607140D03*
Y591114D03*
X289124Y609749D03*
X252313D03*
X284050Y607350D03*
X284024Y590900D03*
X257478Y604499D03*
Y593757D03*
X260824Y610700D03*
X234053Y604499D03*
Y593757D03*
X237013Y610300D03*
X264171Y604499D03*
X267517Y610700D03*
X264171Y593757D03*
X240746Y604499D03*
Y593757D03*
X243392Y610300D03*
X270864Y604499D03*
X273824Y610300D03*
X270864Y593757D03*
X284024Y609999D03*
X247213D03*
X297635Y-7851D03*
X304328D03*
X300982Y-1751D03*
X294289D03*
X308157Y-7180D03*
X324407Y-4536D03*
X304328Y-3700D03*
X300982Y-9901D03*
X297635Y-3700D03*
X294289Y-9901D03*
X321061Y-1743D03*
X314368Y-1843D03*
X331100Y-4536D03*
X327754Y-7108D03*
X317714Y-9786D03*
X311021D03*
X314368Y9114D03*
X321061D03*
X331100D03*
X317714Y-4536D03*
X294289Y9114D03*
X300982D03*
X307675Y-1843D03*
X311021Y28014D03*
X307675Y9300D03*
X304328Y29949D03*
X307992Y13200D03*
X297635Y14814D03*
X321192Y13200D03*
X321334Y32100D03*
X308092D03*
X297635Y29949D03*
X304328Y14814D03*
X300982Y27899D03*
X294289D03*
X300982Y17157D03*
X304328Y12114D03*
X294289Y17157D03*
X297635Y12114D03*
X317714Y28014D03*
X311021Y17057D03*
X317714D03*
X327754D03*
Y28014D03*
X334447Y-1743D03*
Y-7108D03*
X347833D03*
X351179Y9122D03*
Y-4536D03*
X341140Y-1743D03*
X337793Y-9901D03*
X341140Y9122D03*
X334292Y13200D03*
Y32100D03*
X347833Y17057D03*
Y28022D03*
X337793Y17057D03*
Y28014D03*
X314368Y-7108D03*
X324407Y-9901D03*
X327754Y-1743D03*
X321061Y-7108D03*
X341140D03*
X337793Y-4536D03*
X344486Y-9786D03*
Y-4536D03*
X351179Y-9901D03*
X354525Y-1742D03*
X354526Y-7108D03*
X331100Y-9786D03*
X311021Y-4536D03*
X347833Y-1743D03*
X311021Y65814D03*
X317714D03*
X321061Y35957D03*
X307950Y50729D03*
X300982Y36049D03*
X294289Y46914D03*
X304328Y52614D03*
X321192Y51000D03*
X307675Y35957D03*
X304328Y67749D03*
X297635D03*
X294289Y36049D03*
X300982Y46914D03*
X297635Y52614D03*
X300982Y65699D03*
X294289D03*
X300982Y54957D03*
X304328Y34100D03*
Y49914D03*
X294289Y54957D03*
X297635Y34100D03*
Y49914D03*
X314368Y35957D03*
Y46914D03*
X311021Y54857D03*
X317714D03*
X321061Y46914D03*
X331100D03*
X327754Y65814D03*
X331100Y35957D03*
X327754Y54857D03*
X304328Y71900D03*
X300982Y92757D03*
X304328Y87714D03*
X297635Y71900D03*
X294289Y92757D03*
X297635Y87714D03*
X331100Y89964D03*
X327754Y92757D03*
X331100Y84714D03*
Y73757D03*
X314368D03*
Y87392D03*
X311021Y89964D03*
X317714D03*
X321061Y87392D03*
Y73757D03*
X317714Y84714D03*
X307992Y70400D03*
X321334Y69900D03*
X304278Y90414D03*
X307592Y73800D03*
X300982Y84714D03*
X294289D03*
X300982Y73849D03*
X294289D03*
X308166Y87394D03*
X297635Y90414D03*
X307675Y92657D03*
X321061Y92757D03*
X327754Y87392D03*
X324407Y89964D03*
Y84599D03*
X314368Y92657D03*
X311021Y84714D03*
X334292Y51000D03*
X341140Y35957D03*
X337793Y65814D03*
Y54857D03*
X351179Y46922D03*
X347833Y54857D03*
X341140Y46922D03*
X347833Y65822D03*
X351179Y35957D03*
X354415Y87392D03*
X351179Y89964D03*
X347833Y87392D03*
X344486Y84714D03*
Y89964D03*
X337793Y84599D03*
X341140Y92757D03*
X334447D03*
X347833D03*
X351179Y84599D03*
Y73757D03*
X337793Y89964D03*
X341140Y87392D03*
Y73757D03*
X334292Y69900D03*
X334447Y87392D03*
X354415Y92757D03*
X300982Y109700D03*
X304178Y107684D03*
X294889Y110927D03*
X297635Y105084D03*
X326592Y105600D03*
X313637Y105725D03*
X300992Y112300D03*
X297642Y107700D03*
X304192Y105000D03*
X324492Y103500D03*
X327092Y103021D03*
X294899Y213009D03*
X308418Y201309D03*
X317428Y193507D03*
X301648Y194841D03*
X332078Y218860D03*
X329818Y214958D03*
X298279Y214960D03*
X305039D03*
X301659Y213009D03*
X294899Y209109D03*
X298279Y218860D03*
X311798Y211060D03*
Y218860D03*
Y214960D03*
X308418Y213009D03*
X305039Y211060D03*
Y218860D03*
X324200Y201308D03*
X298279Y199360D03*
X294899Y201309D03*
X312918Y205210D03*
X315178Y209109D03*
X298279Y207159D03*
Y203260D03*
Y211060D03*
X318558Y218860D03*
X315178Y216909D03*
Y213009D03*
X301659Y209109D03*
X325318Y211060D03*
X348978Y205210D03*
Y216909D03*
X342218Y213009D03*
X355737Y216909D03*
Y213009D03*
X338838Y218860D03*
X345598Y214960D03*
X352357D03*
X334328Y199108D03*
X348978Y209109D03*
X352357Y211060D03*
X345598Y203260D03*
X355737Y205210D03*
X338838Y211058D03*
X335458Y216909D03*
X355737Y209109D03*
X345598Y207159D03*
X342218Y209109D03*
X294899Y224709D03*
X332078Y242260D03*
Y250060D03*
X328698Y232509D03*
Y220809D03*
X332078Y234460D03*
X298279Y246160D03*
X325318Y250060D03*
X321938Y248109D03*
X305039Y246160D03*
X308418Y244209D03*
X294899D03*
Y248109D03*
X325318Y242260D03*
Y226660D03*
X308418Y220809D03*
X294899D03*
X301659Y224709D03*
X328698Y248109D03*
Y240309D03*
X301659Y220809D03*
X325318Y238360D03*
Y246160D03*
X321938Y244209D03*
X332078Y238360D03*
Y246160D03*
X298279Y230559D03*
X305039Y242260D03*
X294899Y236409D03*
X311798Y230559D03*
X318558Y234460D03*
X321938Y224709D03*
X315178Y236409D03*
Y224709D03*
X298279Y234460D03*
X308418Y228610D03*
Y224709D03*
X305039Y230559D03*
X311798Y222760D03*
X308418Y232509D03*
X294899Y228610D03*
X325318Y234460D03*
Y230559D03*
Y222760D03*
X321938Y228610D03*
X298279Y250060D03*
Y242260D03*
X305039Y234460D03*
X321938Y232509D03*
X298279Y238360D03*
X315178Y228610D03*
X301659Y236409D03*
X318558Y250060D03*
X305039D03*
X318558Y246160D03*
X301659Y248109D03*
X308418Y240309D03*
X315178D03*
X301659D03*
X318558Y242260D03*
X298279Y226660D03*
X318558D03*
X315178Y220809D03*
X321938D03*
X315178Y232509D03*
X301659Y228610D03*
X308418Y236409D03*
X321938D03*
X311798Y238360D03*
X318558D03*
X305039Y226660D03*
X308418Y252009D03*
X298279Y253960D03*
X325318D03*
X308418Y275409D03*
X301659D03*
X308418Y255909D03*
X321938Y275409D03*
X315178Y279310D03*
X318558Y277360D03*
X311798Y261760D03*
X321938Y259809D03*
X301659D03*
X308418Y263709D03*
X325318Y269560D03*
X305039D03*
X318558D03*
X328698Y267609D03*
Y259809D03*
X332078Y269560D03*
X321938Y255909D03*
X308418Y259809D03*
X325318Y273460D03*
Y265660D03*
X301659Y267609D03*
X321938Y263709D03*
X294899Y275409D03*
Y263709D03*
X298279Y265660D03*
X305039Y273460D03*
Y277360D03*
X311798D03*
Y269560D03*
X305039Y265660D03*
X298279Y277360D03*
X328698Y252009D03*
X298279Y261760D03*
X328698Y263709D03*
X325318Y257860D03*
X305039Y261760D03*
X294899Y255909D03*
X305039Y253960D03*
X332078D03*
X315178Y263709D03*
X332078Y265660D03*
X315178Y275409D03*
X301659Y255909D03*
X332078Y257860D03*
X315178Y267609D03*
X298279Y257860D03*
X311798Y273460D03*
X321938Y267609D03*
X308418D03*
X318558Y273460D03*
X301659Y279310D03*
X308418D03*
X294899D03*
X338838Y222760D03*
X352357D03*
X348978Y228610D03*
X352357Y246160D03*
X345598D03*
X342218Y244209D03*
Y232509D03*
X355737Y244209D03*
X348978D03*
X345598Y226660D03*
X352357D03*
X348978Y232509D03*
Y220809D03*
X352357Y238360D03*
X345598D03*
X342218Y220809D03*
X355737Y232509D03*
X338838Y246160D03*
X335458Y248109D03*
X338838Y242260D03*
Y234460D03*
X335458Y236409D03*
X338838Y238360D03*
X335458Y224709D03*
X355737Y248109D03*
X348978D03*
X355737Y220809D03*
X335458Y244209D03*
X338838Y253960D03*
X335458Y252009D03*
X338838Y265660D03*
X335458Y259809D03*
Y267609D03*
X345598Y265660D03*
X348978Y263709D03*
X355737Y259809D03*
X352357Y261760D03*
X345598Y273460D03*
Y269560D03*
X342218Y263709D03*
Y271509D03*
Y259809D03*
Y255909D03*
Y267609D03*
Y279310D03*
Y275409D03*
X338838Y257860D03*
X335458Y263709D03*
X348978Y267609D03*
X345598Y277360D03*
X348978Y279310D03*
Y275409D03*
Y271509D03*
X352357Y265660D03*
X355737Y263709D03*
X342218Y240309D03*
X352357Y234460D03*
X348978Y240309D03*
X355737D03*
Y228610D03*
X342218D03*
X311798Y292959D03*
X305039D03*
X321938Y283209D03*
X315178D03*
X318558Y281260D03*
Y292959D03*
X311798Y285160D03*
X328698Y310509D03*
X332078Y300760D03*
X328698Y283209D03*
X332078Y292959D03*
Y281260D03*
X298279Y308560D03*
X321938Y310509D03*
X315178D03*
X305039Y308560D03*
X311798D03*
X305039Y300760D03*
X325318D03*
X311798D03*
X298279D03*
X318558D03*
X325318Y292959D03*
Y281260D03*
X305039Y285160D03*
X298279D03*
Y292959D03*
X308418Y306609D03*
X301659Y310509D03*
Y306609D03*
X311798Y304660D03*
X305039D03*
X321938Y306609D03*
X325318Y304660D03*
Y308560D03*
X298279Y304660D03*
X294899Y302709D03*
X308418D03*
X301659D03*
X315178D03*
X321938D03*
X294899Y310509D03*
Y306609D03*
X318558Y304660D03*
Y308560D03*
X321938Y291009D03*
X318558Y296860D03*
X315178Y294909D03*
X321938D03*
X301659D03*
X325318Y285160D03*
Y289060D03*
Y296860D03*
X298279D03*
Y289060D03*
Y281260D03*
X308418Y298809D03*
X301659D03*
X308418Y283209D03*
X305039Y281260D03*
Y289060D03*
X308418Y291009D03*
Y287109D03*
X311798Y281260D03*
Y289060D03*
X308418Y294909D03*
X311798Y296860D03*
X305039D03*
X315178Y287109D03*
X318558Y285160D03*
X321938Y287109D03*
X301659Y283209D03*
Y287109D03*
Y291009D03*
X294899Y298809D03*
Y294909D03*
Y291009D03*
Y283209D03*
Y287109D03*
X315178Y298809D03*
X321938D03*
X318558Y289060D03*
X315178Y291009D03*
X332078Y308560D03*
Y304660D03*
X328698Y302709D03*
Y306609D03*
Y287109D03*
Y291009D03*
Y294909D03*
Y298809D03*
X332078Y296860D03*
Y285160D03*
Y289060D03*
X315178Y306609D03*
X308418Y310509D03*
X318558Y312460D03*
X325318D03*
X308418Y333909D03*
Y341709D03*
X325318Y339760D03*
Y335860D03*
X301659Y337809D03*
X315178Y330009D03*
X301659D03*
X308418Y337809D03*
X305039Y331960D03*
X298279Y328060D03*
Y331960D03*
X311798Y324160D03*
X308418Y330009D03*
X315178Y322209D03*
X321938D03*
X294899Y333909D03*
X305039Y328060D03*
X321938Y330009D03*
Y337809D03*
X328698Y330009D03*
Y326110D03*
Y333909D03*
X325318Y324160D03*
X318558Y320260D03*
X301659Y318309D03*
X308418D03*
X305039Y316360D03*
X332078Y331960D03*
Y339760D03*
X298279Y316360D03*
X294899Y322209D03*
Y318309D03*
X311798Y316360D03*
X308418Y326110D03*
X318558Y324160D03*
X311798Y312460D03*
X305039D03*
X298279D03*
X294899Y314409D03*
X308418D03*
X301659D03*
X328698D03*
X321938D03*
X332078Y328060D03*
X328698Y322209D03*
Y318309D03*
X332078Y324160D03*
Y320260D03*
Y316360D03*
X325318Y320260D03*
X305039D03*
X321938Y318309D03*
X315178D03*
X318558Y316360D03*
X301659Y322209D03*
X315178Y314409D03*
X332078Y312460D03*
X325318Y316360D03*
X305039Y324160D03*
X311798Y320260D03*
X308418Y322209D03*
X301659Y326110D03*
X335458Y310509D03*
X338838Y300760D03*
Y292959D03*
Y281260D03*
X335458Y283209D03*
X342218Y310509D03*
Y283209D03*
X335458Y298809D03*
X348978Y287109D03*
X345598Y285160D03*
Y281260D03*
X348978Y283209D03*
Y298809D03*
Y291009D03*
X345598Y289060D03*
Y292959D03*
Y296860D03*
X348978Y294909D03*
X345598Y300760D03*
X348978Y302709D03*
Y306609D03*
X345598Y304660D03*
Y308560D03*
X348978Y310509D03*
X342218Y302709D03*
Y306609D03*
Y291009D03*
Y287109D03*
Y294909D03*
Y298809D03*
X338838Y308560D03*
X335458Y302709D03*
X338838Y304660D03*
X335458Y306609D03*
Y287109D03*
X338838Y289060D03*
Y285160D03*
X335458Y291009D03*
X338838Y296860D03*
X335458Y294909D03*
X345598Y335860D03*
Y331960D03*
X348978Y314409D03*
X345598Y312460D03*
X348978Y322209D03*
X355737Y333909D03*
X345598Y316360D03*
X348978Y318309D03*
Y330009D03*
X352357Y331960D03*
X348978Y326110D03*
X335458Y314409D03*
Y326110D03*
Y318309D03*
X338838Y320260D03*
Y324160D03*
Y328060D03*
X342218Y314409D03*
X338838Y312460D03*
Y316360D03*
X335458Y330009D03*
X338838Y331960D03*
Y339760D03*
X345598Y328060D03*
Y339760D03*
X352357Y335860D03*
X348978Y333909D03*
X342218Y322209D03*
Y318309D03*
Y330009D03*
Y326110D03*
Y333909D03*
X355737Y337809D03*
X345598Y320260D03*
Y324160D03*
X335458Y337809D03*
X348978Y341709D03*
Y337809D03*
X305039Y339760D03*
X321938Y333909D03*
X311798Y328060D03*
X325318D03*
X315178Y333909D03*
X335458D03*
X298279Y339760D03*
X318558Y335860D03*
Y328060D03*
X294899Y337809D03*
X301659Y333909D03*
X328698Y337809D03*
X342218D03*
X308418Y357309D03*
X311798Y359260D03*
X298279Y351460D03*
X294899Y349509D03*
Y353409D03*
X321938Y349509D03*
X318558Y359260D03*
X321938Y361209D03*
X298279Y343660D03*
X315178Y357309D03*
X301659D03*
Y349509D03*
X308418Y361209D03*
Y353409D03*
Y345609D03*
X305039Y347560D03*
X325318Y343660D03*
Y347560D03*
X328698Y365109D03*
X332078Y363160D03*
X328698Y345609D03*
X325318Y355360D03*
X332078Y347560D03*
Y355360D03*
X294899Y369010D03*
X325318Y367060D03*
Y370959D03*
X318558D03*
X308418Y365109D03*
X315178D03*
X325318Y363160D03*
X298279D03*
X305039Y370959D03*
X308418Y369010D03*
X305039Y367060D03*
X301659Y369010D03*
X298279Y370959D03*
X318558Y351460D03*
Y355360D03*
X315178Y349509D03*
Y353409D03*
X311798Y355360D03*
Y347560D03*
Y351460D03*
X305039D03*
X301659Y388509D03*
X308418D03*
X318558Y394359D03*
X324458Y399911D03*
X332078Y378760D03*
X318558Y386560D03*
X325318D03*
X301659Y376809D03*
X311798Y374860D03*
X325318D03*
X294899Y372909D03*
X308418D03*
X321938Y376809D03*
X318558Y382660D03*
Y378760D03*
X298279D03*
X305039D03*
X308418Y384609D03*
X311798Y382660D03*
Y378760D03*
X315178Y376809D03*
X328698D03*
X294899Y384609D03*
X318558Y390460D03*
X320808Y401941D03*
X298279Y386560D03*
Y390460D03*
X315178Y392410D03*
Y388509D03*
X311798Y386560D03*
X298279Y398260D03*
Y394359D03*
X294899Y396309D03*
X325318Y378760D03*
X321938Y380709D03*
X305039Y394359D03*
X302608Y402421D03*
X352357Y359260D03*
X345598Y370959D03*
X355737Y353409D03*
X348978D03*
X342218Y365109D03*
X338838Y347560D03*
X335458Y361209D03*
X338838Y359260D03*
Y355360D03*
Y351460D03*
X335458Y349509D03*
X345598Y359260D03*
X348978Y349509D03*
X345598Y343660D03*
X342218Y345609D03*
X355737Y349509D03*
X342218Y353409D03*
X338838Y367060D03*
X348978Y365109D03*
X355737D03*
X352357Y370959D03*
X355737Y376809D03*
Y388509D03*
X348978Y376809D03*
X342218Y388509D03*
Y376809D03*
Y384609D03*
X338838Y382660D03*
X345598D03*
X352357D03*
X348978Y392410D03*
X355737D03*
X335458Y372909D03*
Y384609D03*
Y380709D03*
X345598Y390460D03*
X352357Y386560D03*
X348978Y361209D03*
X355737D03*
X332078Y359260D03*
X321938Y353409D03*
X335458D03*
X325318Y359260D03*
X328698Y357309D03*
Y349509D03*
X301659Y372909D03*
Y384609D03*
X328698Y353409D03*
X305039Y382660D03*
X294899Y376809D03*
X308418D03*
X298279Y382660D03*
X315178Y361209D03*
X321938Y372909D03*
X311798Y367060D03*
X294899Y365109D03*
X301659Y353409D03*
Y365109D03*
X342218Y361209D03*
X345598Y355360D03*
X355737Y384609D03*
X352357Y367060D03*
X355737Y372909D03*
X352357Y378760D03*
X294899Y392410D03*
X338838Y378760D03*
Y370959D03*
X342218Y372909D03*
X348978D03*
X345598Y367060D03*
Y378760D03*
X348978Y388509D03*
X352357Y355360D03*
X305039Y343660D03*
X298279Y359260D03*
X321938Y365109D03*
X305039Y363160D03*
X335458Y345609D03*
X311798Y370959D03*
X294899Y357309D03*
X318558Y367060D03*
X305039Y359260D03*
X301659Y345609D03*
X294899D03*
X338838Y343660D03*
X332078D03*
X315178Y372909D03*
X348978Y345609D03*
X294289Y490444D03*
X301092Y490700D03*
X307675Y518057D03*
X326797Y499767D03*
X317714Y515364D03*
X321061Y512792D03*
X311701Y499136D03*
X331100Y510114D03*
X327754Y518157D03*
X314368Y512792D03*
X311021Y515364D03*
X317714Y510114D03*
X297835Y497644D03*
X308166Y512794D03*
X300982Y510114D03*
X304278Y515814D03*
X297635D03*
X294289Y510114D03*
X304392Y497300D03*
X324187Y499793D03*
X337793Y515364D03*
X350882Y509999D03*
X347833Y518157D03*
X341140Y512792D03*
X327754D03*
X321061Y518157D03*
X297835Y494944D03*
X294392Y493100D03*
X304392Y494700D03*
X301092Y493300D03*
X334447Y518157D03*
X341140D03*
X337793Y509999D03*
X344486Y515364D03*
Y510114D03*
X347833Y512792D03*
X351179Y515364D03*
X354307Y512792D03*
X354526Y518157D03*
X331100Y515364D03*
X334447Y512792D03*
X297635Y513114D03*
X294289Y518157D03*
X304328Y513114D03*
X300982Y518157D03*
X311021Y510114D03*
X314368Y518057D03*
X324407Y509999D03*
Y515364D03*
X326922Y497170D03*
X321061Y536957D03*
X317714Y529014D03*
X331100Y547914D03*
Y536957D03*
X327754Y529014D03*
X321061Y547914D03*
X314368D03*
Y536957D03*
X311021Y529014D03*
X307675Y548200D03*
X304278Y553614D03*
X297635D03*
X300982Y547914D03*
X294289D03*
X307675Y536957D03*
X304328Y530949D03*
X300982Y537049D03*
X297635Y530949D03*
X294289Y537049D03*
X307992Y533100D03*
X321334D03*
X321123Y552000D03*
X308100D03*
X307992Y570900D03*
X321334D03*
X294289Y574849D03*
Y585714D03*
X304328Y568749D03*
X307675Y574757D03*
X300982Y574849D03*
X307848Y588334D03*
X300982Y585714D03*
X297635Y568749D03*
X327754Y555857D03*
X317714D03*
X311021D03*
X327754Y566814D03*
X331100Y574757D03*
Y585714D03*
X314368D03*
Y574757D03*
X317714Y566814D03*
X311021D03*
X321061Y585714D03*
Y574757D03*
X334292Y533100D03*
Y552000D03*
X337793Y529014D03*
X351179Y547922D03*
Y536957D03*
X347833Y529022D03*
X341140Y547922D03*
Y536957D03*
X334292Y570900D03*
X337793Y555857D03*
X347833D03*
X337793Y566814D03*
X341140Y574757D03*
Y585722D03*
X351179Y574757D03*
Y585722D03*
X347833Y566822D03*
X297635Y550914D03*
X294289Y555957D03*
X304328Y550914D03*
X300982Y555957D03*
X294289Y528899D03*
X297635Y535100D03*
X300982Y528899D03*
X304328Y535100D03*
X297635Y588714D03*
X304328D03*
X294289Y566699D03*
X297635Y572900D03*
X300982Y566699D03*
X304328Y572900D03*
X317714Y609864D03*
X304328Y606549D03*
X297635D03*
X294289Y612249D03*
X300982D03*
X307675Y611600D03*
X307892Y591000D03*
X321192Y589800D03*
X304278Y591414D03*
X297635D03*
X308157Y607220D03*
X327754Y607292D03*
X331100Y609864D03*
X327754Y593657D03*
X317714D03*
X311021D03*
X317714Y604614D03*
X311021D03*
X314368Y612457D03*
X321061D03*
X334292Y589800D03*
X337793Y593657D03*
Y604499D03*
X352109Y609918D03*
X347833Y607292D03*
X341140Y612457D03*
X347833Y593657D03*
X324407Y609864D03*
X334447Y607292D03*
X341140D03*
X337793Y609864D03*
X344486Y604614D03*
X347833Y612357D03*
X351179Y604499D03*
X354525Y612358D03*
X354526Y607292D03*
X331100Y604614D03*
X334447Y612457D03*
X294289Y604499D03*
X297635Y610700D03*
X294289Y593757D03*
X300982Y604499D03*
X304328Y610700D03*
X300982Y593757D03*
X311021Y609864D03*
X314368Y607292D03*
X324407Y604499D03*
X327754Y612457D03*
X321061Y607292D03*
X344486Y609864D03*
X375792Y6500D03*
X377592Y-10880D03*
X380232Y-10900D03*
X380200Y-1200D03*
X378792Y6500D03*
X357872Y-9786D03*
X367911D03*
Y-1858D03*
X357872D03*
X367911Y9114D03*
X357672D03*
X371258Y-1858D03*
Y-9800D03*
X376700Y-1300D03*
X374401Y-11346D03*
X373670Y17580D03*
X374773Y19819D03*
X358592Y30736D03*
X380792Y27812D03*
X357492Y14314D03*
X380792Y24933D03*
X357492Y11714D03*
X358619Y33342D03*
X357872Y28014D03*
X367911D03*
Y17042D03*
X357872Y17014D03*
X404722Y-4536D03*
X398029D03*
X401375Y-7108D03*
X408068Y-1743D03*
X411415Y-9786D03*
X398029Y9107D03*
X408069D03*
X411415Y-4536D03*
X394192Y-9700D03*
X409522Y-20794D03*
X401375Y-1743D03*
X411416Y17057D03*
X401376Y17042D03*
X394682Y17157D03*
X408184Y32100D03*
Y13200D03*
X398029Y28007D03*
X408069D03*
X365311Y17042D03*
X404722Y-9901D03*
X394682Y11792D03*
X394683Y-2200D03*
X408068Y-7108D03*
X414761Y-1743D03*
X398029Y-9901D03*
X361218Y9114D03*
X362662Y17014D03*
X361218Y-9786D03*
X364565Y9114D03*
Y-1858D03*
Y-9786D03*
X414761Y-7108D03*
X361218Y-1858D03*
X380600Y37400D03*
X380980Y60210D03*
X380892Y63200D03*
X357762Y49659D03*
X357772Y68335D03*
X371042Y46900D03*
X380792Y56500D03*
X357762Y52333D03*
X364565Y54842D03*
X361218D03*
Y35942D03*
X367911Y46914D03*
Y54842D03*
Y35942D03*
X358619Y36031D03*
X358618Y54842D03*
X357872Y65736D03*
X366992Y65950D03*
X357872Y46914D03*
X357965Y92500D03*
X367911Y87500D03*
X368311Y92500D03*
X367742Y73450D03*
X357872Y87500D03*
X358491Y73479D03*
X384992Y81600D03*
X375337Y86377D03*
Y83877D03*
X357772Y70935D03*
X374292Y77200D03*
Y74100D03*
X365607Y92500D03*
X365234Y87500D03*
X362792Y92500D03*
X362435Y87500D03*
X408069Y35942D03*
X401376Y54842D03*
X408069Y46907D03*
X394682Y68492D03*
X408184Y51000D03*
X394492Y54700D03*
X398029Y65807D03*
X408069D03*
X394682Y49592D03*
X398029Y35942D03*
Y46907D03*
X411416Y54857D03*
X394682Y87392D03*
X401375Y92757D03*
X398029Y84800D03*
Y73742D03*
X408068Y87392D03*
X411415Y89964D03*
X408069Y73742D03*
X411415Y84714D03*
X408184Y69900D03*
X404722Y89964D03*
X401375Y87392D03*
X414761Y92757D03*
X398029Y89964D03*
X404722Y84599D03*
X414761Y87392D03*
X408068Y92757D03*
X364565Y35942D03*
X386292Y98800D03*
X408126Y103116D03*
Y105750D03*
X414820Y105800D03*
X401375D03*
Y103116D03*
X414819D03*
X369257Y213009D03*
X376017Y216909D03*
X362497D03*
X382777Y213009D03*
X369257Y216909D03*
X382777D03*
X362497Y213009D03*
X389537Y216909D03*
X376017Y213009D03*
X386157Y207159D03*
X362497Y209109D03*
X382777D03*
X376017D03*
X382777Y201309D03*
X365877Y214960D03*
X372637D03*
X379397D03*
X359117D03*
X365877Y203260D03*
X376017Y205211D03*
X362497Y205210D03*
X386157Y214960D03*
X389537Y209109D03*
X372637Y207159D03*
X389537Y213009D03*
X415634Y204496D03*
Y212296D03*
X396296Y209109D03*
X404392Y199100D03*
X415634Y208397D03*
X407706Y209109D03*
X399676Y207159D03*
X396296Y213009D03*
Y216909D03*
X415634Y216196D03*
X392898Y195041D03*
X392916Y214960D03*
Y203260D03*
X396296Y197359D03*
X399676Y203260D03*
Y214960D03*
X372637Y222760D03*
X365877D03*
X386157D03*
X379397D03*
X359117D03*
X369257Y240309D03*
X376017D03*
X359117Y246160D03*
X386157Y226660D03*
X389537Y232509D03*
X369257Y244209D03*
X362497D03*
X379397Y238360D03*
X362497Y220809D03*
X379397Y250060D03*
X369257Y220809D03*
X382777D03*
X376017D03*
X386157Y238360D03*
X372637Y226660D03*
X365877D03*
X369257Y232509D03*
X362497D03*
X379397Y226660D03*
X382777Y232509D03*
X376017D03*
X359117Y226660D03*
X372637Y250060D03*
X389537Y248109D03*
Y220809D03*
X376017Y248109D03*
X382777D03*
X386157Y250060D03*
X359117Y238360D03*
X365877D03*
X372637D03*
X365877Y253960D03*
X362497Y255909D03*
X359117Y257860D03*
X372637Y253960D03*
X376017Y252009D03*
X357057Y277360D03*
X368127Y264300D03*
X364747Y266300D03*
X361492Y268100D03*
X362497Y259809D03*
X365877Y257860D03*
X369257Y255909D03*
X357092Y270700D03*
X391787Y254259D03*
X388407Y256500D03*
X359648Y269777D03*
X374887Y260300D03*
X385027Y254259D03*
X359117Y261760D03*
X371507Y262300D03*
X381647Y256400D03*
X378267Y258400D03*
X357057Y273460D03*
X390894Y264899D03*
X369257Y252009D03*
X392916Y222760D03*
Y250060D03*
Y238360D03*
X396296Y248109D03*
Y220809D03*
X399676Y250060D03*
X407706Y248109D03*
Y240309D03*
Y232509D03*
X399676Y246160D03*
X415634Y247396D03*
Y235696D03*
Y223996D03*
X407706Y220809D03*
X415634Y239596D03*
X396296Y228610D03*
X399676Y222760D03*
X415634Y220096D03*
Y227896D03*
X399676Y238360D03*
X392916Y226660D03*
X396296Y232509D03*
X399676Y226660D03*
X395166Y256400D03*
X398546Y254259D03*
X405306Y254500D03*
X401926Y256500D03*
X397394Y264899D03*
X400394D03*
X393894D03*
X379397Y230559D03*
X389537Y228610D03*
X392916Y234460D03*
X386157D03*
X359117D03*
X362497Y240309D03*
X376017Y236409D03*
X407706Y228610D03*
X382777Y236409D03*
X399676Y234460D03*
X382777Y228610D03*
X362497D03*
X369257D03*
X365877Y234460D03*
X372637D03*
X376017Y228610D03*
X407448Y338641D03*
X416448D03*
X413948D03*
X410948D03*
X357057Y281260D03*
Y296860D03*
Y285160D03*
Y292959D03*
Y300760D03*
Y308560D03*
Y304660D03*
Y289060D03*
Y312460D03*
X364747Y331509D03*
X361367Y329560D03*
X357987Y327609D03*
X371507Y335409D03*
X362497Y337809D03*
X369257Y341709D03*
X368127Y333460D03*
X365877Y339760D03*
X374887Y337360D03*
X381647Y341260D03*
X378267Y339309D03*
X359117Y335860D03*
X357057Y320260D03*
Y324160D03*
X370650Y312441D03*
X378156D03*
X375674D03*
X373162Y312400D03*
X368165Y312504D03*
X359117Y339760D03*
X362497Y341709D03*
X357057Y316360D03*
X414294Y292904D03*
X411294D03*
Y309904D03*
X414294D03*
X403648Y338341D03*
X401148D03*
X398148D03*
X394648D03*
X379397Y359260D03*
X382777Y349509D03*
X379397Y347560D03*
X391787Y347109D03*
X388407Y345160D03*
X372637Y343660D03*
X385027Y343209D03*
X379397Y370959D03*
X372637D03*
X365877D03*
X359117D03*
X386157D03*
X362497Y353409D03*
X376017D03*
X369257D03*
Y349509D03*
X386157Y355360D03*
X365877Y347560D03*
X369257Y345609D03*
X376017D03*
X386157Y351460D03*
Y359260D03*
X372637Y347560D03*
X389537Y353409D03*
X372637Y359260D03*
X365877D03*
X359117D03*
X365877Y343660D03*
X389537Y365109D03*
X382777D03*
X369257D03*
X362497D03*
X376017D03*
Y376809D03*
X369257D03*
X382777Y388509D03*
X369257D03*
X362497D03*
X376017D03*
X390657Y394359D03*
X391787Y402800D03*
X357987D03*
X369257Y392410D03*
X362497D03*
X379397Y382660D03*
X372637D03*
X365877D03*
X359117D03*
X379397Y390460D03*
X378267Y402800D03*
X376017Y392410D03*
X386157Y382660D03*
X389537Y388509D03*
Y376809D03*
X382777D03*
X362497D03*
X396296Y353409D03*
X411086Y351460D03*
X405306Y347109D03*
X399676Y351460D03*
X392916Y355360D03*
X395166Y345160D03*
X398546Y347109D03*
X401926Y345160D03*
X392916Y370959D03*
X399676D03*
X396296Y365109D03*
X403056D03*
Y357309D03*
X392916Y351460D03*
Y359260D03*
X396296Y388509D03*
Y376809D03*
X392916Y382660D03*
Y390460D03*
X399676Y382660D03*
X406568Y402471D03*
X403056Y392410D03*
X411086Y390460D03*
Y374860D03*
X403056Y376809D03*
Y388509D03*
X411547Y368260D03*
Y365660D03*
X403056Y353409D03*
X411447Y363160D03*
X411431Y359351D03*
X411086Y355360D03*
X386157Y367060D03*
X396296Y384609D03*
X372637Y390460D03*
X403056Y372909D03*
X392916Y367060D03*
X382777Y361209D03*
X399676Y367060D03*
X389537Y361209D03*
X365877Y367060D03*
X372637D03*
X362497Y361209D03*
X403056D03*
X365877Y355360D03*
X379397Y367060D03*
X376017Y384609D03*
X396296Y372909D03*
X386157Y378760D03*
X359117D03*
X362497Y384609D03*
X392916Y378760D03*
X379397D03*
X382777Y372909D03*
X389537D03*
X399676Y378760D03*
X382777Y384609D03*
X365877Y378760D03*
X372637D03*
X362497Y372909D03*
X369257D03*
Y384609D03*
X376017Y372909D03*
X399676Y390460D03*
X389537Y384609D03*
X396296Y361209D03*
X359117Y367060D03*
Y355360D03*
X399676Y359260D03*
X372637Y355360D03*
X376017Y361209D03*
X385244Y504027D03*
X386630Y521860D03*
X359042Y515200D03*
X358918Y510114D03*
X366865D03*
Y515152D03*
X375192Y516356D03*
Y518856D03*
X401375Y518157D03*
X398029Y509999D03*
X411415Y515364D03*
X408068Y512792D03*
X411415Y510114D03*
X364265Y515152D03*
X401375Y512792D03*
X404722Y515364D03*
X394682Y512792D03*
X408068Y518157D03*
X414761Y512792D03*
X404722Y509999D03*
X398029Y515364D03*
X414761Y518157D03*
X364265Y510114D03*
X361642Y515200D03*
X361518Y510114D03*
X370596Y585614D03*
X370080Y555700D03*
X366890Y586000D03*
X376892Y581127D03*
X357539Y550511D03*
X357661Y534000D03*
X376829Y546303D03*
X357661Y531546D03*
X357539Y553111D03*
X376785Y538305D03*
X363760Y529293D03*
X367692Y547914D03*
X357672D03*
X357872Y528942D03*
X367911Y529057D03*
X367692Y536200D03*
X357910Y536727D03*
X376792Y543700D03*
X357724Y569474D03*
X376892Y577500D03*
X356798Y588366D03*
X357724Y571973D03*
X367211Y555842D03*
X357910D03*
X367192Y566814D03*
X357910D03*
X367192Y574742D03*
X357872D03*
X357025Y585714D03*
X398029Y536942D03*
X408069Y547907D03*
Y536942D03*
X394587Y529026D03*
X408184Y533100D03*
Y552000D03*
X398029Y547907D03*
X394682Y569492D03*
X408184Y570900D03*
X401376Y555842D03*
X411416Y555857D03*
X398029Y574742D03*
Y585707D03*
X408069D03*
Y574742D03*
X394682Y550592D03*
X361518Y547914D03*
X361320Y555842D03*
X364265Y547914D03*
X364565Y555842D03*
X394595Y537058D03*
X398029Y529007D03*
X361218Y566814D03*
X394682Y588392D03*
X361518Y585714D03*
X364265D03*
X408069Y566807D03*
X398029D03*
X361218Y574742D03*
X408069Y529007D03*
X364565Y574742D03*
Y566814D03*
X386970Y623539D03*
X378600Y606200D03*
X408068Y612657D03*
X413324Y623559D03*
X399824D03*
X356798Y590939D03*
X373400Y593800D03*
X376204Y593650D03*
X374039Y611186D03*
X357872Y604614D03*
X367170Y611759D03*
X357872Y612242D03*
X367911Y593642D03*
X357026D03*
X367911Y604614D03*
X371134Y612453D03*
X370659Y593691D03*
X371312Y604709D03*
X411415Y609864D03*
X394682Y607292D03*
X408184Y589800D03*
X398029Y609864D03*
X401376Y593642D03*
X401375Y607292D03*
X411416Y593657D03*
X411415Y604614D03*
X414761Y612657D03*
X394682D03*
X408068Y607292D03*
X404722Y609864D03*
X414761Y607292D03*
X361218Y612242D03*
X361964Y593642D03*
X364565Y612242D03*
X365311Y593642D03*
X364565Y604614D03*
X401376Y612658D03*
X404722Y604499D03*
X398029D03*
X361218Y604614D03*
X438187Y-4536D03*
X451573Y-9901D03*
X428147Y-1743D03*
X421454Y-7108D03*
X434840Y-1743D03*
X418108Y-4536D03*
X431494D03*
X424801D03*
X428147Y-7108D03*
X434840D03*
X431494Y9107D03*
X424801D03*
X418108D03*
Y-9701D03*
X441533Y-1843D03*
Y9107D03*
X447744Y-7180D03*
X451573Y-1801D03*
Y9114D03*
X436392Y-20760D03*
X422892Y-20789D03*
X421454Y-1817D03*
X434842Y17057D03*
X441533Y17042D03*
X418108D03*
X428149Y17057D03*
X448226Y11100D03*
Y28100D03*
X433508Y32100D03*
X448292Y31900D03*
X421368Y32100D03*
X433508Y13200D03*
X448292Y13700D03*
X421368Y13200D03*
X448892Y17000D03*
X451573Y27899D03*
X424801Y28007D03*
X451573Y17157D03*
X418108Y28007D03*
X441533D03*
X458266Y-1751D03*
X460912Y-7700D03*
Y-4100D03*
X458266Y-9901D03*
X454533Y-4100D03*
X478344Y-3700D03*
X474998Y-9901D03*
X464758Y-7050D03*
X469832Y-7260D03*
X464732Y-4401D03*
X469832Y-4651D03*
X454533Y-7851D03*
X458116Y9114D03*
X469832Y-2051D03*
X464732Y-1801D03*
X474998Y-1751D03*
X469845Y-9864D03*
X478344Y-7851D03*
X464758Y-9652D03*
X474998Y9114D03*
X464732Y9098D03*
X478344Y29949D03*
X460912Y30100D03*
Y14814D03*
X469832Y17114D03*
X454569Y14714D03*
X460912Y33700D03*
X458266Y27899D03*
X454533Y33700D03*
X474998Y27899D03*
X464758Y30750D03*
X469832Y33149D03*
X464732Y33399D03*
X454533Y29949D03*
X469792Y9300D03*
X469832Y30540D03*
X458266Y17157D03*
X460912Y12114D03*
X454619D03*
X474998Y17157D03*
X478344Y12114D03*
X464732Y14300D03*
X469832Y14514D03*
X464732Y11700D03*
X469832Y11914D03*
X478344Y14814D03*
X469845Y27936D03*
X464792Y28100D03*
X464692Y16900D03*
X444880Y-9786D03*
X431494Y-9901D03*
Y28007D03*
X438187Y-9786D03*
X424801D03*
X444880Y-4536D03*
X434842Y54857D03*
X441533Y54842D03*
X424801Y46907D03*
X431494D03*
X428149Y54857D03*
X441533Y46907D03*
X448414Y35761D03*
X448973Y54883D03*
X451573Y35999D03*
X448627Y68090D03*
X448517Y46975D03*
X448492Y51000D03*
X421368D03*
X433508D03*
X451573Y46900D03*
X431494Y65807D03*
X451573Y65699D03*
X424801Y65807D03*
X451573Y54957D03*
X418108Y65807D03*
Y54842D03*
X441533Y65807D03*
X431494Y35942D03*
X441533D03*
X424801D03*
X418108D03*
Y46907D03*
X424801Y89964D03*
X438187D03*
X428147Y92500D03*
X424801Y84800D03*
X431400D03*
X431494Y73742D03*
X441533Y87392D03*
Y92500D03*
Y73742D03*
X418108Y89964D03*
Y84599D03*
Y73742D03*
X424801D03*
X434840Y92500D03*
X448651Y70896D03*
X433508Y69900D03*
X421368D03*
X451573Y84714D03*
Y73799D03*
X448610Y85296D03*
X448599Y73589D03*
X448692Y89900D03*
X438187Y84714D03*
X431494Y89964D03*
X444880D03*
Y84714D03*
X451573Y92757D03*
X428147Y87392D03*
X421454Y92757D03*
X434840Y87392D03*
X474998Y36049D03*
X464732Y46898D03*
X460912Y52614D03*
X458266Y36049D03*
X458116Y46914D03*
X464758Y65950D03*
X474998Y46914D03*
X458266Y65699D03*
X474998D03*
X464758Y68550D03*
X469832Y68340D03*
X458266Y54957D03*
X460912Y49914D03*
X454619Y49564D03*
X474998Y54957D03*
X478344Y34100D03*
Y49914D03*
X464732Y52100D03*
X469832Y49714D03*
X464732Y49500D03*
X454533Y67749D03*
X454569Y52514D03*
X469832Y52314D03*
Y54914D03*
X469792Y47100D03*
Y35800D03*
X464692Y54700D03*
X464732Y35999D03*
X478344Y52614D03*
X460912Y67900D03*
X478344Y67749D03*
X469845Y65736D03*
X478344Y87714D03*
X464732Y89900D03*
X469832Y70949D03*
Y87514D03*
X464732Y71199D03*
Y87300D03*
X469832Y90114D03*
X458116Y84714D03*
X464708Y92500D03*
X464732Y84698D03*
X469808Y84700D03*
X474998Y73849D03*
X469858Y73550D03*
X474998Y84714D03*
X478344Y90414D03*
X469832Y92714D03*
X460912Y90314D03*
X464732Y73799D03*
X458266Y73849D03*
X454569Y90314D03*
X460912Y71500D03*
X458266Y92757D03*
X460912Y87714D03*
X454533Y71500D03*
X454619Y87714D03*
X478344Y71900D03*
X474998Y92757D03*
X421512Y103116D03*
X427696Y105800D03*
X421503D03*
X427696Y103100D03*
X441743Y199841D03*
X421464Y199583D03*
X446253Y206446D03*
X425974D03*
X453013Y218147D03*
X449633Y212296D03*
Y216196D03*
X422594D03*
X419214Y214247D03*
X436113Y212296D03*
X432733Y214247D03*
X429354Y216196D03*
X432733Y218147D03*
X425974D03*
X429353Y212296D03*
X446253Y218147D03*
X442873Y216196D03*
X439493Y214247D03*
X436113Y216196D03*
X453013Y214247D03*
X439493Y210346D03*
X434983Y198931D03*
X439493Y218147D03*
X459773D03*
X455263Y198050D03*
X473292Y218147D03*
X469913Y216196D03*
X469912Y212296D03*
X475692Y199900D03*
X466533Y218147D03*
X473292Y214247D03*
X476672Y212296D03*
Y216196D03*
X459773Y214247D03*
X466533Y206446D03*
X456393Y216196D03*
X462023Y198327D03*
X456393Y212296D03*
X463153Y216196D03*
X425974Y233746D03*
Y241547D03*
X436113Y239596D03*
X422594D03*
X432733Y233746D03*
X429354Y251296D03*
X453013Y245447D03*
Y229847D03*
Y237647D03*
X449633Y251296D03*
Y247396D03*
Y227896D03*
Y223996D03*
X436113Y243496D03*
X442873D03*
X422594D03*
X425974Y245447D03*
Y249347D03*
X432733D03*
X436113Y251296D03*
X429354Y247396D03*
X422594Y251296D03*
X446253Y245447D03*
X419214Y249347D03*
X432733Y245447D03*
X439493Y237647D03*
X446253D03*
X422594Y223996D03*
Y231797D03*
X419214Y233746D03*
Y237647D03*
X436113Y231797D03*
X439493Y241547D03*
X419214D03*
X436113Y223996D03*
X429354D03*
Y220096D03*
Y227896D03*
X446253Y229847D03*
X432733D03*
X425974D03*
X439493Y233746D03*
X442873Y231797D03*
Y223996D03*
X425974Y237647D03*
X432733D03*
X449633Y220096D03*
X419214Y245447D03*
X453013Y222047D03*
X425974Y225947D03*
X422594Y220096D03*
Y227896D03*
X419214Y222047D03*
Y229847D03*
X432733Y241547D03*
X446253Y233746D03*
Y241547D03*
X442873Y239596D03*
X453013Y233746D03*
Y241547D03*
Y249347D03*
X429354Y243496D03*
X449633D03*
X429354Y235696D03*
X449633D03*
X436113Y247396D03*
X446253Y249347D03*
X442873Y251296D03*
X439493Y249347D03*
X442873Y247396D03*
X439493Y245447D03*
X444408Y267305D03*
X440500Y266500D03*
X418084Y253546D03*
X451883Y265246D03*
X434983Y255497D03*
X438363Y257446D03*
X421464Y255497D03*
X431604Y257446D03*
X448503Y263297D03*
X445123Y261346D03*
X441743Y259397D03*
X446253Y253247D03*
X447148Y278841D03*
X449848D03*
X450800Y275600D03*
X429781Y264793D03*
X439493Y253247D03*
X449633Y255196D03*
Y259096D03*
X446253Y257147D03*
X442873Y255196D03*
X453013Y257147D03*
Y261047D03*
X448900Y269600D03*
X476672Y227896D03*
X459773Y225947D03*
X466533Y233746D03*
X476672Y239596D03*
X463153D03*
X473292Y233746D03*
X469913Y231797D03*
Y243496D03*
Y239596D03*
X456393D03*
X469913Y251296D03*
X466533Y245447D03*
X473292D03*
X466533Y249347D03*
X473292D03*
X459773Y245447D03*
Y249347D03*
X476672Y223996D03*
Y243496D03*
Y251296D03*
X469913Y247396D03*
Y223996D03*
X473292Y229847D03*
X469913Y227896D03*
X466533Y229847D03*
X473292Y237647D03*
X466533D03*
X469913Y220096D03*
X456393Y243496D03*
Y251296D03*
X459773Y233746D03*
Y241547D03*
Y237647D03*
X456393Y223996D03*
Y231797D03*
X476672D03*
X463153Y243496D03*
Y251296D03*
Y231797D03*
Y223996D03*
X456393Y227896D03*
X466533Y222047D03*
X476672Y259096D03*
X463153D03*
X458408Y278940D03*
X477792Y272747D03*
X462023Y271097D03*
X458643Y269146D03*
X456393Y262996D03*
Y259096D03*
X459773Y261047D03*
X469913Y255196D03*
X473292Y257147D03*
X466533D03*
X468783Y274997D03*
X469913Y270796D03*
X466533Y264947D03*
X456393Y255196D03*
X463153D03*
X476672D03*
X459773Y257147D03*
X465100Y280300D03*
X455263Y267197D03*
X466533Y261047D03*
X463153Y262996D03*
X477792Y276646D03*
Y280547D03*
X453400Y275600D03*
X473292Y261047D03*
X469913Y259096D03*
X476672Y266896D03*
X473292Y268847D03*
Y264947D03*
X474413Y274696D03*
X469913Y278596D03*
X466533Y268847D03*
X469913Y262996D03*
X458400Y276400D03*
X459773Y264947D03*
X426494Y338361D03*
X430089Y338428D03*
X442020Y339220D03*
X419400Y338600D03*
X438240Y339380D03*
X449500Y309800D03*
X451648Y308341D03*
X447000Y309800D03*
X421494Y292904D03*
X435894D03*
X432894D03*
X440094D03*
X443094D03*
X425694D03*
X418494D03*
X428694D03*
X418494Y309904D03*
X421494D03*
X425694D03*
X428694D03*
X432894D03*
X435894D03*
X440094Y309841D03*
X443148D03*
X450700Y335550D03*
X453200D03*
X469913Y305896D03*
X477792Y307851D03*
X469913Y286396D03*
X477792Y303947D03*
Y288347D03*
X464000Y294500D03*
X454148Y310341D03*
Y307841D03*
X469913Y298096D03*
Y301996D03*
X477792Y284447D03*
Y296147D03*
Y300047D03*
Y292247D03*
Y311747D03*
X469913Y309797D03*
X453400Y293686D03*
X469913Y282496D03*
Y294196D03*
Y290296D03*
X477792Y315647D03*
Y319547D03*
X458643Y338746D03*
X477792Y327347D03*
X462948Y315251D03*
X463671Y319386D03*
X474413Y329296D03*
X468783Y332897D03*
X474413Y333196D03*
Y325396D03*
X477792Y323446D03*
X456900Y333000D03*
X469913Y313696D03*
Y317596D03*
X455263Y340697D03*
X462848Y312741D03*
X467653Y340996D03*
X474413D03*
Y337096D03*
X469913Y321496D03*
X477792Y331247D03*
Y335147D03*
Y339047D03*
X463800Y289500D03*
X443993Y358547D03*
X441743Y348497D03*
X440613Y352696D03*
X437233Y358547D03*
X450753Y366347D03*
Y350747D03*
Y358547D03*
X437233Y362447D03*
X423714D03*
X433854Y368296D03*
X427094D03*
X440613Y364396D03*
X427094Y372197D03*
X447373D03*
Y368296D03*
X440613Y372197D03*
Y368296D03*
X443993Y366347D03*
X427094Y356596D03*
X433854Y352696D03*
X437233Y354647D03*
X423714D03*
X430474D03*
X427094Y360496D03*
X433854D03*
X445123Y346546D03*
X427094Y352696D03*
X447373Y356596D03*
X451883Y342646D03*
X448503Y344597D03*
X421464Y348497D03*
X438363Y346546D03*
X424844D03*
X434983Y348497D03*
X428224D03*
X431604Y346546D03*
X430474Y385847D03*
X450753Y397547D03*
X440613Y395595D03*
X429354Y399496D03*
X433854Y379996D03*
X423714Y381947D03*
X430474Y374146D03*
X423714D03*
X437233D03*
X430474Y378047D03*
X433854Y376096D03*
X443993Y397546D03*
Y401447D03*
Y393647D03*
X440613Y391696D03*
X443993Y385847D03*
X427094Y376096D03*
X437233Y381947D03*
X447373Y376096D03*
X440613Y379996D03*
X443993Y378047D03*
X423715Y397548D03*
X430474Y393647D03*
X433854Y391696D03*
X423715Y401449D03*
X450753Y385847D03*
Y393647D03*
Y378047D03*
X437233Y389747D03*
Y385847D03*
X423714D03*
X477792Y342947D03*
Y362447D03*
Y354647D03*
Y358547D03*
X457513Y362447D03*
X464273Y346847D03*
X471033Y342947D03*
X454133Y372197D03*
Y364396D03*
Y348796D03*
Y352696D03*
X464273Y366347D03*
X474413Y372197D03*
X471033Y366347D03*
X467653Y372197D03*
X474413Y364396D03*
X464273Y350747D03*
X474413Y348796D03*
X471033Y350747D03*
X474413Y352696D03*
X471033Y358547D03*
X464273D03*
X467653Y368296D03*
Y348796D03*
X460893Y372197D03*
Y364396D03*
Y352696D03*
X457513Y354647D03*
Y358547D03*
Y346847D03*
X477792Y389747D03*
X457513D03*
X471033Y393647D03*
X460893Y395595D03*
X464273Y401447D03*
X471033D03*
X460893Y391696D03*
X457513Y385847D03*
Y381947D03*
X460893Y379996D03*
X477792Y381947D03*
X474413Y391696D03*
X464273Y385847D03*
X454133Y391696D03*
Y379996D03*
X471033Y385847D03*
X464273Y393647D03*
X474413Y379996D03*
X471033Y378047D03*
X467653Y376096D03*
X464273Y378047D03*
Y397546D03*
X477792Y385847D03*
Y346847D03*
Y350747D03*
X471033Y346847D03*
X454133Y356596D03*
X443993Y362447D03*
X460893Y376096D03*
X450753Y370247D03*
X464273D03*
X454133Y376096D03*
X433854Y372197D03*
Y364396D03*
X437233Y370247D03*
X423714D03*
X427094Y364396D03*
X477792Y366347D03*
X427094Y379996D03*
X477792Y378047D03*
X427094Y391696D03*
X477792Y370247D03*
X427094Y383896D03*
X471033Y370247D03*
X474413Y376096D03*
X430474Y389747D03*
X433854Y383896D03*
X423714Y389747D03*
X447373Y387796D03*
X467653Y383896D03*
X447373Y379996D03*
X467653Y391696D03*
X447373D03*
X471033Y389747D03*
Y381947D03*
X460893Y387796D03*
X474413D03*
X464273Y389747D03*
Y381947D03*
X450753D03*
X440613Y387796D03*
X454133D03*
X443993Y381947D03*
X467653Y352696D03*
X447373D03*
X457513Y366347D03*
X467653Y364396D03*
X447373D03*
X457513Y378047D03*
X467653Y356596D03*
X457513Y370247D03*
X430474Y366347D03*
X471033Y362447D03*
X460893Y356596D03*
X474413D03*
X464273Y362447D03*
X450753D03*
X440613Y356596D03*
X447091Y407782D03*
X428224Y407800D03*
X443993Y405347D03*
X467653Y407296D03*
X464273Y405347D03*
X441533Y512792D03*
Y518057D03*
X433192Y497650D03*
X434840Y518157D03*
X431494Y509999D03*
X424801Y510114D03*
X418108Y515364D03*
Y509999D03*
X428147Y518157D03*
X451573Y510114D03*
X448692Y515300D03*
X447735Y512794D03*
X474998Y510114D03*
X464732Y510098D03*
X460912Y515714D03*
X458116Y510114D03*
X454569Y515714D03*
X478344Y515814D03*
X464708Y517900D03*
X469832Y518114D03*
X464732Y512700D03*
X469832Y512914D03*
X464732Y515300D03*
X478344Y513114D03*
X474998Y518157D03*
X454619Y513114D03*
X451573Y518157D03*
X460912Y513114D03*
X458266Y518157D03*
X444880Y510114D03*
Y515364D03*
X431494D03*
X435192Y499400D03*
X438187Y510114D03*
Y515364D03*
X424801D03*
X434840Y512792D03*
X421454Y518157D03*
X428147Y512792D03*
X469832Y515514D03*
X418108Y536942D03*
Y547907D03*
X431494D03*
X424801D03*
X441533D03*
X418108Y529007D03*
X431494Y536942D03*
X424801D03*
X441533Y536957D03*
Y529007D03*
X451573Y547914D03*
Y536999D03*
X448510Y549843D03*
X448410Y531156D03*
X448432Y536723D03*
X448692Y553100D03*
X448557Y534061D03*
X421368Y533100D03*
X434395Y532904D03*
X433508Y552000D03*
X421368D03*
X447735Y588394D03*
X433508Y570900D03*
X421368D03*
X451573Y585714D03*
Y574799D03*
X448226Y569200D03*
X448291Y574773D03*
X451573Y566699D03*
X418108Y555842D03*
X428149Y555857D03*
X434842D03*
X441533Y555842D03*
Y585707D03*
Y574742D03*
X418108Y566807D03*
X441533D03*
X424801Y574742D03*
X418108Y585599D03*
Y574742D03*
X431494D03*
Y585707D03*
X424801D03*
X464732Y536999D03*
X460912Y553514D03*
X458116Y547914D03*
X454619Y550914D03*
X454569Y553514D03*
X454533Y530949D03*
X460912Y531100D03*
X458266Y537049D03*
X469845Y528936D03*
X474998Y537049D03*
X464758Y529150D03*
X469858Y536750D03*
X478344Y553614D03*
X464732Y547898D03*
X474998Y547914D03*
X469808Y547900D03*
X478344Y530949D03*
Y568749D03*
X464732Y574799D03*
X469808Y585700D03*
X469858Y574550D03*
X474998Y574849D03*
Y585714D03*
X464732Y585698D03*
X464758Y566950D03*
X469845Y566736D03*
X458266Y574849D03*
X460912Y568900D03*
X458116Y585714D03*
X454533Y568749D03*
X464708Y555700D03*
X469832Y555914D03*
Y534149D03*
X464758Y531750D03*
X474998Y528899D03*
X478344Y535100D03*
X451573Y528899D03*
X454533Y534700D03*
X458266Y528899D03*
X460912Y534700D03*
X469832Y553314D03*
X464732Y550500D03*
X469832Y550714D03*
X464732Y553100D03*
X478344Y550914D03*
X474998Y555957D03*
X451573D03*
X460912Y550914D03*
X458266Y555957D03*
X478344Y588714D03*
X454619D03*
X460912D03*
X469832Y569340D03*
Y571949D03*
X464758Y569550D03*
X474998Y566699D03*
X478344Y572900D03*
X454533Y572500D03*
X458266Y566699D03*
X460912Y572500D03*
X431494Y566807D03*
X464732Y588300D03*
X469832Y588514D03*
X464732Y534399D03*
X469832Y531540D03*
X424801Y566807D03*
X464732Y572199D03*
X421454Y612560D03*
X441533Y612557D03*
X447766Y612659D03*
X453250Y623320D03*
X474998Y612649D03*
X464732Y612599D03*
X458266Y612649D03*
X456910Y623320D03*
X427324Y623541D03*
X451573Y612599D03*
X441533Y607292D03*
X434840D03*
X428147D03*
X418108Y609864D03*
X424801D03*
X447744Y607220D03*
X448692Y590900D03*
X420634Y589800D03*
X433500D03*
X431494Y609864D03*
X418108Y593642D03*
X434842Y593657D03*
X428149D03*
X441533Y593642D03*
X418108Y604499D03*
X478344Y591414D03*
X464708Y593500D03*
X469832Y593714D03*
X464758Y604750D03*
X469845Y604536D03*
X478344Y606549D03*
X469858Y612350D03*
X460912Y591314D03*
Y606700D03*
X469832Y591114D03*
X469833Y607140D03*
X454533Y606549D03*
X454569Y591314D03*
X478344Y610700D03*
X474998Y593757D03*
X451573Y604499D03*
X454533Y610300D03*
X451573Y593757D03*
X458266Y604499D03*
Y593757D03*
X460912Y610300D03*
X444880Y609864D03*
X438187Y604614D03*
X424801D03*
X434840Y612657D03*
X421454Y607292D03*
X428147Y612657D03*
X464732Y609999D03*
X469832Y609749D03*
X464732Y590900D03*
X474998Y604499D03*
X444880Y604614D03*
X431494Y604499D03*
X464758Y607350D03*
X438187Y609864D03*
X511809Y-1751D03*
X485037Y-3700D03*
X481691Y-9901D03*
X497723Y-4100D03*
X495077Y-9901D03*
X491344Y-4100D03*
X488384Y-9901D03*
X511809D03*
X501570Y-7050D03*
X506644Y-7260D03*
X501544Y-4401D03*
X506644Y-4651D03*
X511809Y9114D03*
X495077Y-1751D03*
X501544Y-1801D03*
X506692Y-2000D03*
X488384Y-1801D03*
X481691Y-1751D03*
X485037Y-7851D03*
X491344D03*
X506657Y-9864D03*
X497723Y-7700D03*
X501592Y-9700D03*
X481691Y9114D03*
X494927D03*
X488384D03*
X501544Y9098D03*
X497723Y14814D03*
X506644Y17114D03*
X506657Y27936D03*
X497723Y30100D03*
X491380Y14714D03*
X481691Y27899D03*
X497723Y33700D03*
X495077Y27899D03*
X491344Y33700D03*
X488384Y27899D03*
X511809D03*
X501569Y30750D03*
X506643Y33149D03*
X506604Y9300D03*
X481691Y17157D03*
X485037Y12114D03*
X495077Y17157D03*
X497723Y12114D03*
X488384Y17157D03*
X491430Y12114D03*
X511809Y17157D03*
X501544Y14300D03*
X506644Y14514D03*
X501544Y11700D03*
X506644Y11914D03*
X485037Y14814D03*
X501504Y16900D03*
X485037Y29949D03*
X491344D03*
X501603Y28100D03*
X515155Y-7851D03*
X538355Y9098D03*
X518502Y-1751D03*
X521848Y-7851D03*
X538355Y-1801D03*
X531888Y-1751D03*
X525195Y-1801D03*
X538403Y-9700D03*
X528155Y-7851D03*
X534534Y-7700D03*
X518502Y9114D03*
X531738D03*
X525195D03*
X521848Y-3700D03*
X518502Y-9901D03*
X515155Y-3700D03*
X534534Y-4100D03*
X531888Y-9901D03*
X528155Y-4100D03*
X525195Y-9901D03*
X538381Y-7050D03*
X521848Y14814D03*
Y29949D03*
X528191Y14714D03*
X538315Y16900D03*
X534534Y30100D03*
X518502Y27899D03*
X534534Y33700D03*
X531888Y27899D03*
X528155Y33700D03*
X525195Y27899D03*
X538381Y30750D03*
X538355Y33399D03*
X518502Y17157D03*
X521848Y12114D03*
X515155D03*
X531888Y17157D03*
X534534Y12114D03*
X525195Y17157D03*
X528241Y12114D03*
X538355Y14300D03*
Y11700D03*
X515155Y29949D03*
Y14814D03*
X534534D03*
X528155Y29949D03*
X538415Y28100D03*
X501543Y33399D03*
X506643Y30540D03*
X538355Y-4401D03*
X488384Y35999D03*
X501492Y54700D03*
X497723Y52614D03*
Y67900D03*
X501544Y46898D03*
X511809Y46914D03*
X491344Y67749D03*
X506657Y65736D03*
X501570Y65950D03*
X481691Y36049D03*
Y65699D03*
X495077D03*
X488384D03*
X511809D03*
X501570Y68550D03*
X506644Y68340D03*
X485037Y34100D03*
X481691Y54957D03*
X485037Y49914D03*
X495077Y54957D03*
X497723Y49914D03*
X488384Y54957D03*
X491430Y49914D03*
X511809Y54957D03*
X501543Y52100D03*
X506643Y49714D03*
X501543Y49500D03*
X495077Y36049D03*
X506643Y52314D03*
X506644Y54914D03*
X494927Y46914D03*
X485037Y52614D03*
X481691Y46914D03*
X511809Y36049D03*
X485037Y67749D03*
X488384Y46914D03*
X506603Y35800D03*
X506592Y47000D03*
X501544Y35999D03*
X497723Y71500D03*
X495077Y92757D03*
X497723Y87714D03*
X491344Y71500D03*
X488384Y92757D03*
X491430Y87714D03*
X511809Y92757D03*
X501544Y89900D03*
X506644Y70949D03*
Y87514D03*
X501544Y71199D03*
Y87300D03*
X506644Y90114D03*
X511809Y84714D03*
X501544Y84698D03*
X494927Y84714D03*
X506670Y73550D03*
X481691Y84714D03*
X488384D03*
X501520Y92500D03*
X506620Y84700D03*
X511809Y73849D03*
X488384Y73799D03*
X481691Y73849D03*
X506644Y92714D03*
X491380Y90314D03*
X497723Y90414D03*
X485037D03*
X495077Y73849D03*
X501544Y73799D03*
X485037Y71900D03*
X481691Y92757D03*
X485037Y87714D03*
X518502Y36049D03*
Y46914D03*
X521848Y67749D03*
X531888Y36049D03*
X538355Y35999D03*
X534534Y52614D03*
X531738Y46914D03*
X525195Y35999D03*
X518502Y65699D03*
X531888D03*
X525195D03*
X538381Y68550D03*
X521848Y34100D03*
X518502Y54957D03*
X521848Y49914D03*
X515155Y34100D03*
Y49914D03*
X531888Y54957D03*
X534534Y49914D03*
X525195Y54957D03*
X528241Y49914D03*
X538355Y52100D03*
Y49500D03*
X515155Y67749D03*
Y52614D03*
X521848D03*
X538355Y89900D03*
X534534Y67900D03*
X538381Y65950D03*
X528155Y67749D03*
X538355Y46898D03*
X538304Y54700D03*
X525195Y46914D03*
X538355Y71199D03*
Y87300D03*
X515155Y90414D03*
X534534D03*
X528191Y90314D03*
X521848Y90414D03*
X518502Y73849D03*
Y84714D03*
X531738D03*
X525195D03*
X538355Y84698D03*
X538331Y92500D03*
X531888Y73849D03*
X525195Y73799D03*
X538355D03*
X521848Y71900D03*
X518502Y92757D03*
X521848Y87714D03*
X515155Y71900D03*
Y87714D03*
X534534Y71500D03*
X531888Y92757D03*
X534534Y87714D03*
X528155Y71500D03*
X525195Y92757D03*
X528241Y87714D03*
X494927Y112357D03*
X497723Y106964D03*
X488634Y112357D03*
X491430Y106964D03*
X512024Y112357D03*
X501544Y110514D03*
X506644Y107655D03*
X501570Y107865D03*
X506670Y110264D03*
X512024Y104314D03*
X497723Y109564D03*
X501544Y113114D03*
X506670Y112865D03*
X501570Y105265D03*
X491430Y109564D03*
X506657Y105051D03*
X488634Y104314D03*
X495077D03*
X518317Y112357D03*
X521113Y106964D03*
X514820D03*
X531888Y112357D03*
X534534Y106964D03*
X525134Y112357D03*
X528241Y107314D03*
X538355Y110514D03*
X538381Y107865D03*
X514820Y109564D03*
X521113D03*
X528191Y109914D03*
X534534Y109564D03*
X538355Y113114D03*
X531738Y104314D03*
X525134D03*
X538381Y105265D03*
X518467Y104314D03*
X480052Y218147D03*
X511592Y206447D03*
Y210346D03*
Y218147D03*
X486812Y214247D03*
Y218147D03*
X498350Y209900D03*
X501452Y212296D03*
X480052Y214247D03*
Y206447D03*
X486812Y210346D03*
X508212Y212296D03*
X518352Y218147D03*
Y206445D03*
X538631Y210346D03*
Y214247D03*
Y206447D03*
X528491Y208397D03*
X525111Y218147D03*
X528491Y216196D03*
X535251Y204496D03*
X525111Y206447D03*
X531871D03*
X521731Y208397D03*
Y216196D03*
X531871Y218147D03*
X528491Y204496D03*
X538631Y202247D03*
X498072Y218147D03*
X494692Y216196D03*
X525111Y214247D03*
X531871Y210346D03*
X535251Y216196D03*
X538631Y218147D03*
X535251Y208397D03*
X494692Y274696D03*
X483432Y227896D03*
X480052Y229847D03*
X511592Y241547D03*
Y249347D03*
X486812Y245447D03*
X494692Y247396D03*
X483432Y251296D03*
X501452Y247396D03*
X480052Y237647D03*
X508212Y239596D03*
X498072Y233746D03*
X486812D03*
Y229847D03*
X494692Y235696D03*
X504832Y229847D03*
X486812Y225947D03*
Y249347D03*
X480052Y245447D03*
Y249347D03*
X498072Y245447D03*
X494692Y223996D03*
X504832Y225947D03*
X511592Y222047D03*
X498072Y249347D03*
Y222047D03*
Y225947D03*
X486812Y222047D03*
Y237647D03*
X480052Y233746D03*
X504832Y241547D03*
X480052D03*
X486812D03*
X494692Y243496D03*
X483432D03*
X504832Y245447D03*
X501452Y223996D03*
X508212Y231797D03*
Y220096D03*
Y223996D03*
X483432Y235696D03*
Y223996D03*
X494692Y251296D03*
X501452Y274696D03*
X508212Y278596D03*
X484552Y268847D03*
X494692Y255196D03*
X486812Y257147D03*
X511592Y268847D03*
X483432Y255196D03*
X480052Y257147D03*
X508212Y274696D03*
X504832Y268847D03*
X508707Y258532D03*
X504832Y253247D03*
X487932Y278596D03*
Y274696D03*
X494692Y278596D03*
X501452Y266896D03*
Y259096D03*
X484552Y280547D03*
X511592Y253247D03*
X508212Y266896D03*
X513857Y260881D03*
X504832Y261047D03*
X501452Y278596D03*
X504832Y264947D03*
X487932Y270796D03*
X498072Y268847D03*
X491312D03*
X487932Y266896D03*
X491312Y264947D03*
X480052D03*
X481172Y270796D03*
X494692Y262996D03*
X483432Y259096D03*
X481172Y274696D03*
Y278596D03*
X508212Y270796D03*
X494692D03*
X480052Y261047D03*
X518352Y229847D03*
X521731Y231797D03*
Y235696D03*
Y247396D03*
Y220096D03*
X538631Y225947D03*
Y222047D03*
Y237647D03*
X528491Y247396D03*
Y243496D03*
X538631Y249347D03*
X535251Y235696D03*
X528491Y227896D03*
Y235696D03*
Y220096D03*
X535251Y247396D03*
Y251296D03*
Y239596D03*
X531871Y222047D03*
X525111Y237647D03*
X514972Y220096D03*
X518352Y233746D03*
Y222047D03*
X531871Y241547D03*
Y249347D03*
X528491Y223996D03*
X531871Y237647D03*
X535251Y223996D03*
X518352Y245447D03*
Y241547D03*
Y237647D03*
X521731Y239596D03*
Y243496D03*
X525111Y245447D03*
X518352Y249347D03*
X514972Y247396D03*
Y227896D03*
Y235696D03*
Y239596D03*
Y223996D03*
X535251Y259096D03*
X531871Y261047D03*
X514972Y255196D03*
Y270796D03*
Y278596D03*
X525111Y253247D03*
X518352D03*
X528491Y274696D03*
X531871Y268847D03*
Y276646D03*
X535251Y266896D03*
X525111Y280547D03*
X521731Y266896D03*
Y259096D03*
Y274696D03*
X538631Y257147D03*
X521731Y255196D03*
X514972Y274696D03*
X518352Y257147D03*
X528491Y270796D03*
Y278596D03*
X535251Y255196D03*
X531871Y264947D03*
X518352D03*
X531871Y257147D03*
X528491Y255196D03*
X525111Y268847D03*
X528491Y262996D03*
X525111Y276646D03*
X484552Y272747D03*
X525111D03*
X518352D03*
X514972Y251296D03*
X510401Y260511D03*
X498072Y264947D03*
X518352Y261047D03*
X498072Y229847D03*
X501452Y239596D03*
Y231797D03*
X511592Y233746D03*
X525111Y229847D03*
X521731Y223996D03*
X525111Y222047D03*
X531871Y229847D03*
X535251Y227896D03*
Y231797D03*
X498072Y241547D03*
Y237647D03*
X501452Y235696D03*
X508212D03*
X511592Y225947D03*
Y229847D03*
X535251Y270796D03*
X538631Y261047D03*
X504832Y233746D03*
X501452Y220096D03*
X525111Y257147D03*
Y261047D03*
X521731Y251296D03*
X511592Y245447D03*
X514972Y243496D03*
X508212Y247396D03*
X521731Y227896D03*
X538631Y229847D03*
Y280547D03*
X535251Y243496D03*
X494692Y227896D03*
X528491Y231797D03*
X535251Y278596D03*
X504832Y300045D03*
Y303947D03*
Y311747D03*
X508212Y301996D03*
Y305896D03*
X494692Y294196D03*
X501452Y290296D03*
Y282496D03*
X491312Y292245D03*
Y300047D03*
X508212Y290296D03*
Y294196D03*
X511592Y307847D03*
Y284447D03*
X481172Y309797D03*
X494692D03*
X481172Y301996D03*
X487932Y309797D03*
X498072Y303947D03*
X487932Y286396D03*
X481172Y298096D03*
X487932Y282496D03*
X481172Y305896D03*
X487932Y290296D03*
X484552Y288347D03*
Y296147D03*
X481172Y294196D03*
X508212Y309797D03*
X511592Y300047D03*
Y288347D03*
X494692Y305896D03*
X491312Y311747D03*
X501452Y301996D03*
X491312Y307847D03*
X498072Y311747D03*
X511592Y296147D03*
X501452Y294196D03*
X498072Y296147D03*
X504832D03*
X508212Y298096D03*
X498072Y300047D03*
X484552Y307847D03*
Y300047D03*
Y292245D03*
X494692Y286396D03*
X501452Y298096D03*
X481172Y290296D03*
X508212Y329296D03*
X487932Y317596D03*
X504832Y319547D03*
X484552Y323446D03*
X508212Y317596D03*
Y325396D03*
X491312Y339047D03*
X494692Y337096D03*
X511592Y327347D03*
Y339047D03*
Y331247D03*
Y335147D03*
Y315647D03*
Y323446D03*
X508212Y340996D03*
X498072Y339047D03*
X504832Y327347D03*
X508212Y321496D03*
X481172Y329296D03*
X491312Y323446D03*
X501452Y313696D03*
X508212D03*
X481172D03*
X494692Y340996D03*
Y313696D03*
X501452Y329296D03*
X487932Y340996D03*
Y329296D03*
X494692D03*
X491312Y327347D03*
X498072Y331247D03*
X484552Y335147D03*
X481172Y337096D03*
X501452Y321496D03*
X481172Y340996D03*
X484552Y339047D03*
X487932Y337096D03*
Y333196D03*
X491312Y335147D03*
X494692Y333196D03*
X498072Y335147D03*
X491312Y319547D03*
X494692Y321496D03*
X501452Y317596D03*
X498072Y315647D03*
Y323446D03*
X494692Y325396D03*
X501452D03*
X494692Y317596D03*
X487932Y321496D03*
X484552Y327347D03*
X487932Y325396D03*
X504832Y331247D03*
X508212Y337096D03*
Y333196D03*
X504832Y335147D03*
X501452Y333196D03*
X504832Y339047D03*
X501452Y340996D03*
X504832Y315647D03*
X498072Y319547D03*
X504832Y323446D03*
X498072Y327347D03*
X491312Y331247D03*
X511592Y319547D03*
X538631Y311747D03*
X535251Y290296D03*
X514972Y305896D03*
Y309797D03*
X528491Y301996D03*
Y309797D03*
X525111Y311747D03*
Y307847D03*
Y303947D03*
X521731Y305896D03*
Y309797D03*
X518352Y307847D03*
X514972Y298096D03*
X518352Y292245D03*
Y288347D03*
X521731Y286396D03*
Y290296D03*
Y298096D03*
X525111Y292245D03*
Y296147D03*
X528491Y290296D03*
X525111Y288347D03*
X521731Y294196D03*
X518352Y300047D03*
Y296147D03*
X514972Y301996D03*
Y290296D03*
Y286396D03*
Y294196D03*
X525111Y284447D03*
X531871Y288347D03*
Y292245D03*
X528491Y294196D03*
X525111Y300047D03*
X531871D03*
X521731Y301996D03*
X528491Y286396D03*
Y298096D03*
X535251Y294196D03*
X538631Y292245D03*
Y288347D03*
Y284447D03*
X531871Y303947D03*
X535251Y301996D03*
X531871Y311747D03*
Y307847D03*
X535251Y309797D03*
X514972Y333196D03*
Y321496D03*
Y317596D03*
Y329296D03*
Y325396D03*
Y337096D03*
X518352Y319547D03*
X514972Y313696D03*
X528491D03*
X521731D03*
X518352Y323446D03*
Y315647D03*
X521731Y317596D03*
Y325396D03*
X518352Y327347D03*
Y339047D03*
X531871Y335147D03*
X525111D03*
X528491Y337096D03*
X531871Y327347D03*
X535251Y329296D03*
X538631Y335147D03*
Y339047D03*
X528491Y317596D03*
X531871Y319547D03*
X535251Y321496D03*
X538631Y319547D03*
X514972Y340996D03*
X518352Y331247D03*
X521731Y321496D03*
X525111Y339047D03*
X535251Y333196D03*
Y325396D03*
X484552Y315647D03*
X481172Y282496D03*
X518352Y303947D03*
X531871Y284447D03*
X484552D03*
X504832Y342947D03*
X491312Y370247D03*
X498072Y366347D03*
X494692Y372197D03*
X504832Y366347D03*
X501452Y368296D03*
X487932D03*
X484552Y362447D03*
X498072D03*
X491312D03*
X494692Y360496D03*
X487932D03*
X501452Y344896D03*
X504832Y354647D03*
X494692Y344896D03*
Y348796D03*
X491312Y350747D03*
X508212Y344896D03*
Y348796D03*
X511592Y346847D03*
Y350747D03*
Y342947D03*
X504832Y362447D03*
X494692Y368296D03*
Y352696D03*
X508212Y356596D03*
X504832Y350747D03*
X491312Y366347D03*
X487932Y372197D03*
X484552Y370247D03*
X481172Y372197D03*
X484552Y366347D03*
X487932Y364396D03*
X494692D03*
X501452D03*
X491312Y358547D03*
X498072Y350747D03*
Y346847D03*
X501452Y360496D03*
X498072Y342947D03*
X487932Y348796D03*
X481172Y356596D03*
X484552Y358547D03*
Y350747D03*
Y354647D03*
X487932Y352696D03*
Y344896D03*
X491312Y346847D03*
X494692Y356596D03*
X498072Y358547D03*
Y354647D03*
X481172Y344896D03*
Y360496D03*
X484552Y346847D03*
X508212Y352696D03*
Y360496D03*
X504832Y346847D03*
Y358547D03*
X501452Y356596D03*
Y348796D03*
Y352696D03*
X511592Y370247D03*
X481172Y352696D03*
X484552Y393647D03*
X481172Y391696D03*
X484552Y385847D03*
X498072Y393647D03*
X494692Y391696D03*
X491312Y385847D03*
X498072D03*
X508212Y387796D03*
X501452Y391696D03*
Y395597D03*
X491312Y389747D03*
X504832Y381947D03*
Y378047D03*
X501452Y379996D03*
X481172Y395596D03*
X511592Y378047D03*
Y397546D03*
X491312Y378047D03*
X484552D03*
X481172Y379996D03*
X487932Y376096D03*
X491312Y381947D03*
X511592Y374146D03*
X501452Y383896D03*
X498072Y389747D03*
X494692Y376096D03*
X508212Y379996D03*
X491312Y374146D03*
X498072Y397546D03*
X487932Y403396D03*
Y399496D03*
X491312Y397546D03*
X487932Y395597D03*
X521731Y368296D03*
X518352Y366347D03*
X514972Y372197D03*
Y356596D03*
X521731Y360496D03*
Y356596D03*
Y348796D03*
X518352Y342947D03*
Y362447D03*
X521731Y372197D03*
X518352Y370247D03*
X525111Y354647D03*
X531871Y346847D03*
X535251Y356596D03*
X538631Y366347D03*
X528491Y364396D03*
X525111Y342947D03*
X514972Y348796D03*
Y344896D03*
Y352696D03*
X518352Y358547D03*
X521731Y344896D03*
X538631Y370247D03*
X525111Y350747D03*
Y370247D03*
X531871D03*
X525111Y362447D03*
X528491Y360496D03*
Y356596D03*
X525111Y366347D03*
X528491Y368296D03*
X521731Y364396D03*
X525111Y358547D03*
X531871Y354647D03*
X528491Y372197D03*
X525111Y378047D03*
Y374146D03*
X521731Y376096D03*
X514972Y403396D03*
Y379996D03*
X531871Y374146D03*
X521731Y399496D03*
X518352Y397546D03*
Y389747D03*
X535251Y383896D03*
X525111Y381947D03*
X538631Y393647D03*
Y378047D03*
X528491Y403396D03*
X531871Y401447D03*
Y389747D03*
X525111Y393647D03*
X514972Y399496D03*
X538631Y381947D03*
X531871Y385847D03*
X528491Y391696D03*
X525111Y397546D03*
X481172Y348796D03*
X535251Y395597D03*
Y387796D03*
Y391696D03*
Y352696D03*
X531871Y350747D03*
Y397546D03*
X528491Y399496D03*
X521731Y403396D03*
X538631Y385847D03*
Y389747D03*
X531871Y393647D03*
X535251Y399496D03*
X528491Y395597D03*
X525111Y401447D03*
X518352Y374146D03*
X521731Y379996D03*
X514972Y383896D03*
X511592Y381947D03*
X508212Y391696D03*
X504832Y389747D03*
X508212Y395597D03*
X518352Y378047D03*
Y381947D03*
Y385847D03*
X511592D03*
X501452Y387796D03*
X511592Y393647D03*
X504832Y397546D03*
X481172Y376096D03*
Y368296D03*
X487932Y387796D03*
Y391696D03*
Y379996D03*
X491312Y401447D03*
X481172Y387796D03*
X494692Y395597D03*
X484552Y381947D03*
Y405347D03*
X538750Y406200D03*
X531871Y405347D03*
X525111D03*
X511712Y495800D03*
X488384Y495887D03*
X494777D03*
X491380Y493744D03*
X506644Y490867D03*
X501560D03*
X497723Y493494D03*
X506620Y510100D03*
X506644Y518114D03*
X501544Y510098D03*
X485037Y515814D03*
X481691Y510114D03*
X491380Y515714D03*
X511809Y510114D03*
X497723Y515814D03*
X494927Y510114D03*
X488384D03*
X501520Y517900D03*
X506644Y498867D03*
X501560D03*
X514755Y491044D03*
X521048Y491144D03*
X538370Y490609D03*
X528241Y490944D03*
X534534Y490794D03*
X515155Y515814D03*
X530792Y495787D03*
X524595D03*
X517892Y495800D03*
X534534Y515814D03*
X528191Y515714D03*
X531738Y510114D03*
X525195D03*
X538355Y510098D03*
X538331Y517900D03*
X521848Y515814D03*
X518502Y510114D03*
X538370Y498609D03*
Y495909D03*
X538355Y515300D03*
X501544Y512700D03*
X506644Y512914D03*
X501544Y515300D03*
X528241Y513114D03*
X525195Y518157D03*
X534534Y513114D03*
X531888Y518157D03*
X515155Y513114D03*
X511809Y518157D03*
X491430Y513114D03*
X488384Y518157D03*
X521848Y513114D03*
X518502Y518157D03*
X497723Y513114D03*
X495077Y518157D03*
X485037Y513114D03*
X481691Y518157D03*
X506644Y496167D03*
X538370Y493209D03*
X501560Y493467D03*
X506644Y493567D03*
X501560Y496167D03*
X528191Y493544D03*
X524595Y498387D03*
X534534Y493394D03*
X530792Y498387D03*
X514755Y493744D03*
X511809Y498487D03*
X491430Y491144D03*
X488384Y498487D03*
X521048Y493844D03*
X517902Y498487D03*
X497723Y490894D03*
X494777Y498487D03*
X506644Y515514D03*
X538355Y512700D03*
X506670Y536750D03*
X501570Y529150D03*
X506657Y528936D03*
X501544Y536999D03*
X511809Y547914D03*
Y537049D03*
X491380Y553514D03*
X497723Y553614D03*
X485037D03*
X506620Y547900D03*
X501544Y547898D03*
X481691Y547914D03*
X494927D03*
X488384D03*
X481691Y537049D03*
X491344Y530949D03*
X488384Y536999D03*
X495077Y537049D03*
X497723Y531100D03*
X485037Y530949D03*
Y568749D03*
X481691Y574849D03*
Y585714D03*
X501544Y585698D03*
Y574799D03*
X506657Y566736D03*
X501570Y566950D03*
X506670Y574550D03*
X506620Y585700D03*
X488384Y585714D03*
X511809D03*
Y574849D03*
X494927Y585714D03*
X491344Y568749D03*
X501520Y555700D03*
X506644Y555914D03*
X497723Y568900D03*
X488384Y574799D03*
X495077Y574849D03*
X515155Y553614D03*
Y530949D03*
X534534Y531100D03*
X531888Y537049D03*
X528155Y530949D03*
X525195Y536999D03*
X538355D03*
X538381Y529150D03*
X525195Y547914D03*
X531738D03*
X538355Y547898D03*
X534534Y553614D03*
X528191Y553514D03*
X518502Y547914D03*
X521848Y553614D03*
X518502Y537049D03*
X521848Y530949D03*
X515155Y568749D03*
X538331Y555700D03*
X518502Y585714D03*
Y574849D03*
X521848Y568749D03*
X538355Y585698D03*
Y574799D03*
X538381Y566950D03*
X531738Y585714D03*
X525195D03*
X534534Y568900D03*
X525195Y574799D03*
X528155Y568749D03*
X531888Y574849D03*
X538355Y553100D03*
X538381Y531750D03*
X538355Y534399D03*
X501544D03*
X506644Y534149D03*
X501570Y531750D03*
X525195Y528899D03*
X528155Y534700D03*
X531888Y528899D03*
X534534Y534700D03*
X511809Y528899D03*
X515155Y535100D03*
X488384Y528899D03*
X491344Y534700D03*
X518502Y528899D03*
X521848Y535100D03*
X495077Y528899D03*
X497723Y534700D03*
X481691Y528899D03*
X485037Y535100D03*
X506644Y553314D03*
X538355Y550500D03*
X501544D03*
X506644Y550714D03*
X501544Y553100D03*
X528241Y550914D03*
X525195Y555957D03*
X534534Y550914D03*
X531888Y555957D03*
X515155Y550914D03*
X511809Y555957D03*
X491430Y550914D03*
X488384Y555957D03*
X521848Y550914D03*
X518502Y555957D03*
X497723Y550914D03*
X495077Y555957D03*
X485037Y550914D03*
X481691Y555957D03*
X497723Y588714D03*
X485037D03*
X506644Y569340D03*
X538355Y572199D03*
X501544D03*
X525195Y566699D03*
X528155Y572500D03*
X531888Y566699D03*
X534534Y572500D03*
X511809Y566699D03*
X515155Y572900D03*
X488384Y566699D03*
X491344Y572500D03*
X518502Y566699D03*
X521848Y572900D03*
X495077Y566699D03*
X497723Y572500D03*
X481691Y566699D03*
X485037Y572900D03*
X538355Y588300D03*
X501544D03*
X506644Y588514D03*
X528241Y588714D03*
X534534D03*
X515155D03*
X491430D03*
X521848D03*
X538381Y569550D03*
X506644Y531540D03*
Y571949D03*
X501570Y569550D03*
X525195Y612599D03*
X518502Y612649D03*
X538355Y612599D03*
X531888Y612649D03*
X501544Y612599D03*
X495077Y612649D03*
X488384Y612599D03*
X511809Y612649D03*
X497723Y591414D03*
X486250Y591020D03*
X491380Y591314D03*
X501520Y593500D03*
X506644Y593714D03*
X501570Y604750D03*
X506657Y604536D03*
X491344Y606549D03*
X497723Y606700D03*
X485037Y607230D03*
X506670Y612350D03*
X480950Y612430D03*
X515155Y606549D03*
Y591414D03*
X521848D03*
Y606549D03*
X534534Y591414D03*
X528191Y591314D03*
X538331Y593500D03*
X538381Y604750D03*
X534534Y606700D03*
X528155Y606549D03*
X538355Y590900D03*
X521848Y610700D03*
X495077Y604499D03*
Y593757D03*
X498092Y611200D03*
X481691Y604499D03*
Y593757D03*
X485037Y610700D03*
X506644Y591114D03*
Y607140D03*
X538355Y609999D03*
X501544D03*
Y590900D03*
X525195Y604499D03*
Y593757D03*
X531888Y604499D03*
X534534Y610300D03*
X531888Y593757D03*
X511809Y604499D03*
X515155Y610700D03*
X511809Y593757D03*
X488384Y604499D03*
Y593757D03*
X491724Y611668D03*
X518502Y604499D03*
Y593757D03*
X538381Y607350D03*
X506644Y609749D03*
X501570Y607350D03*
X528155Y610300D03*
X562006Y9114D03*
X568549D03*
X555313D03*
X548620D03*
X571345Y-7700D03*
X551966Y-7851D03*
X564966D03*
X558659D03*
X562006Y-1801D03*
X555313Y-1751D03*
X568699D03*
X548620D03*
X543503Y-2000D03*
X543468Y-9864D03*
X558659Y-3700D03*
X555313Y-9901D03*
X551966Y-3700D03*
X548620Y-9901D03*
X571345Y-4100D03*
X568699Y-9901D03*
X564966Y-4100D03*
X562006Y-9901D03*
X543455Y-7260D03*
Y-4651D03*
Y17114D03*
X564992Y14714D03*
X555313Y27899D03*
X548620D03*
X571345Y33700D03*
X568699Y27899D03*
X564966Y33700D03*
X562006Y27899D03*
X543455Y33149D03*
Y30540D03*
X555313Y17157D03*
X558659Y12114D03*
X548620Y17157D03*
X551966Y12114D03*
X568699Y17157D03*
X571345Y12114D03*
X561868Y17019D03*
X565052Y12114D03*
X543455Y14514D03*
Y11914D03*
X543415Y9300D03*
X558659Y14814D03*
Y29949D03*
X551966Y14814D03*
Y29949D03*
X564966D03*
X571345Y14814D03*
Y30100D03*
X543468Y27936D03*
X575166Y9098D03*
X595470Y-3700D03*
X592124Y-9901D03*
X588777Y-3700D03*
X585431Y-9901D03*
X575192Y-7050D03*
X580266Y-7260D03*
Y-4651D03*
X602163Y-1743D03*
Y9157D03*
Y16999D03*
X592124Y27899D03*
X585431D03*
X575192Y30750D03*
X575166Y33399D03*
X580266Y33149D03*
X592124Y17157D03*
X595470Y12114D03*
X585431Y17157D03*
X588777Y12114D03*
X575166Y14300D03*
X575214Y-9700D03*
X575166Y-1801D03*
X580279Y-9864D03*
X580314Y-2000D03*
X588777Y-7851D03*
X598817Y-9901D03*
X595470Y-7851D03*
X592124Y-1751D03*
X598817D03*
X585431D03*
X602163Y-9901D03*
X598817Y9157D03*
X592124Y9114D03*
X585431D03*
X580266Y14514D03*
X575166Y11700D03*
X580266Y11914D03*
X598817Y17057D03*
X602163Y27899D03*
X575182Y16900D03*
X575192Y28100D03*
X580192Y9300D03*
X588777Y29949D03*
X580279Y27936D03*
X595470Y29949D03*
Y14814D03*
X598817Y27899D03*
X588777Y14814D03*
X580266Y17114D03*
X575166Y-4401D03*
X580266Y30540D03*
X562006Y46914D03*
X555313Y65699D03*
X548620D03*
X568699D03*
X562006D03*
X543455Y68340D03*
X558659Y34100D03*
X555313Y54957D03*
X558659Y49914D03*
X551966Y34100D03*
X548620Y54957D03*
X551966Y49914D03*
X568699Y54957D03*
X571345Y49914D03*
X562006Y54957D03*
X565052Y49914D03*
X543455Y49714D03*
Y52314D03*
X551966Y52614D03*
X565352Y52864D03*
X548620Y46914D03*
Y36049D03*
X558659Y52614D03*
X568699Y36049D03*
X555313D03*
X562006Y35999D03*
X551966Y67749D03*
X564966D03*
X571345Y52614D03*
Y67900D03*
X558659Y67749D03*
X568549Y46914D03*
X555313D03*
X565266Y87374D03*
X543455Y70949D03*
X543468Y65736D03*
X543404Y47000D03*
X543415Y35800D03*
X543455Y54914D03*
Y87514D03*
Y90114D03*
Y92714D03*
X548620Y84714D03*
X568549D03*
X555313D03*
X562006D03*
X543481Y73550D03*
X543431Y84700D03*
X548620Y73849D03*
X568699D03*
X562006Y73799D03*
X555313Y73849D03*
X558659Y90414D03*
X551966D03*
X571345D03*
X558659Y71900D03*
X555313Y92757D03*
X558659Y87714D03*
X551966Y71900D03*
X548620Y92757D03*
X551966Y87714D03*
X571345Y71500D03*
X568699Y92757D03*
X571345Y87714D03*
X564966Y71500D03*
X562006Y92757D03*
X592124Y65699D03*
X585431D03*
X575192Y68550D03*
X580266Y68340D03*
X592124Y54957D03*
X595470Y34100D03*
Y49914D03*
X585431Y54957D03*
X588777Y34100D03*
Y49914D03*
X575166Y52100D03*
X580266Y52314D03*
X575166Y49500D03*
X580266Y49714D03*
X598817Y54857D03*
X602163Y46957D03*
Y54799D03*
Y36057D03*
X575166Y46898D03*
Y35999D03*
X575192Y65950D03*
X585431Y46914D03*
X595470Y52614D03*
X588777D03*
X585431Y36049D03*
X592124D03*
X598817D03*
Y46957D03*
X592124Y46914D03*
X598817Y65699D03*
X595470Y67749D03*
X588777D03*
X580266Y54914D03*
X580192Y35750D03*
X580279Y65736D03*
X602163Y65699D03*
X592124Y84714D03*
X585431D03*
X598817Y84757D03*
X580242Y84700D03*
X580266Y92714D03*
X588777Y90414D03*
X602163Y92599D03*
X595470Y71900D03*
X592124Y92757D03*
X595470Y87714D03*
X588777Y71900D03*
X585431Y92757D03*
X588777Y87714D03*
X575166Y89900D03*
X580266Y70949D03*
Y87514D03*
X575166Y71199D03*
Y87300D03*
X580266Y90114D03*
X598817Y92657D03*
X602163Y84757D03*
Y73857D03*
X575166Y73799D03*
X575142Y92500D03*
X575166Y84698D03*
X595470Y90414D03*
X585431Y73849D03*
X592124D03*
X598817D03*
X580292Y73550D03*
X555313Y112357D03*
X558659Y107314D03*
X548620Y112357D03*
X551966Y107314D03*
X543455Y107655D03*
X543481Y110264D03*
X548620Y104314D03*
X555313D03*
X558659Y110014D03*
X551966D03*
X543481Y112865D03*
X543468Y105051D03*
X602100Y109600D03*
X555531Y216196D03*
X557000Y206800D03*
X548771Y212296D03*
X552151Y214247D03*
X547800Y201400D03*
X545391Y210346D03*
X558911Y218147D03*
X542011Y208396D03*
X563900Y213500D03*
X560739Y207625D03*
X552151Y218147D03*
X590500Y215800D03*
Y213000D03*
X599773Y199596D03*
X600286Y202921D03*
X577375Y204125D03*
X542011Y216196D03*
X579497Y202003D03*
X578980Y217884D03*
X552151Y225947D03*
X558911Y222047D03*
X552151Y233746D03*
X548771Y235696D03*
X558911Y229847D03*
X552151D03*
X562591Y220096D03*
X564084Y235685D03*
X545391Y225947D03*
Y222047D03*
Y233746D03*
X542011Y239596D03*
Y247396D03*
X552151Y241547D03*
X548771Y239596D03*
X552151Y249347D03*
X570400Y243500D03*
X555531Y231797D03*
X548771Y227896D03*
X552151Y245447D03*
X548771Y251296D03*
X542011Y223996D03*
X545391Y237647D03*
X555531Y247396D03*
X562591Y251296D03*
X548771Y243496D03*
X562591D03*
X572930Y232750D03*
Y228130D03*
X552151Y257147D03*
X562591Y255196D03*
X548771D03*
X573200Y262600D03*
X573100Y258600D03*
X548771Y266896D03*
X558911Y264947D03*
X563800Y275900D03*
X559211Y280547D03*
X548771Y278596D03*
X558911Y272747D03*
X555531Y274696D03*
X564500Y264800D03*
Y268800D03*
X552151Y261047D03*
X545391Y272747D03*
Y280547D03*
Y264947D03*
Y268847D03*
X542011Y274696D03*
X548771Y270796D03*
Y262996D03*
X545391Y276646D03*
X542011Y270796D03*
X600400Y226800D03*
X580360Y234590D03*
Y230060D03*
X581102Y220006D03*
X542011Y227896D03*
X545391Y229847D03*
X558911Y253247D03*
X548771Y247396D03*
X545391Y241547D03*
X562630Y227896D03*
X555531Y223996D03*
X542011Y235696D03*
X552151Y272747D03*
X566926Y268055D03*
X555531Y262996D03*
X558911Y225947D03*
X575600Y261800D03*
X555531Y251296D03*
X565124Y243496D03*
X558911Y241547D03*
X577849Y231119D03*
X545391Y261047D03*
X555531Y255196D03*
X545391Y253247D03*
X558911Y268847D03*
X570404Y229015D03*
X577832Y233729D03*
X558911Y249347D03*
X570528Y231543D03*
X567868Y243482D03*
X566926Y265555D03*
X552151Y276646D03*
X555531Y266896D03*
X558911Y257147D03*
X555531Y278596D03*
X552151Y268847D03*
X542011Y255196D03*
Y266896D03*
X575600Y259300D03*
X592300Y220500D03*
X545391Y307847D03*
X555831Y309797D03*
Y305896D03*
X548771Y309797D03*
X555831Y298096D03*
X552151Y284447D03*
X548771Y286396D03*
X552151Y288347D03*
Y296147D03*
X558145Y286727D03*
X545391Y296147D03*
Y288347D03*
Y292245D03*
Y300047D03*
X542011Y294196D03*
Y298096D03*
X545391Y303947D03*
X548771Y282496D03*
Y290296D03*
Y294196D03*
Y337096D03*
Y313696D03*
X561971Y317320D03*
X548771Y325396D03*
X558911Y335147D03*
X555531Y333196D03*
X562591D03*
X548771Y340996D03*
X561966Y325502D03*
X559211Y319547D03*
X552151Y323446D03*
X545391Y319547D03*
X542011Y321496D03*
X545391Y335147D03*
Y331247D03*
Y315647D03*
X548771Y329296D03*
X560884Y286396D03*
X545391Y284447D03*
X555531Y282496D03*
X555831Y294196D03*
X542011Y286396D03*
X552151Y350747D03*
X558911Y342947D03*
X562591Y348796D03*
X559212Y370247D03*
X548771Y368296D03*
X562591Y352696D03*
Y344896D03*
X563200Y356596D03*
X545391Y354647D03*
Y346847D03*
X542011Y368296D03*
X545391Y366347D03*
Y358547D03*
X542011Y360496D03*
Y348796D03*
Y364396D03*
Y372197D03*
Y352696D03*
X545391Y342947D03*
X548771Y372196D03*
X545391Y362447D03*
Y378047D03*
X552151Y374146D03*
X548771Y376096D03*
X559212Y374146D03*
X555531Y387797D03*
X559212Y381947D03*
Y393647D03*
X552151Y378047D03*
X545391Y397546D03*
Y385847D03*
X542011Y376096D03*
X559212Y385847D03*
X542011Y383896D03*
X545391Y374146D03*
X548771Y360496D03*
Y356596D03*
X542011Y379996D03*
X548771Y383896D03*
X545391Y370247D03*
X552151Y358547D03*
X548771Y352696D03*
X545391Y381947D03*
X548771Y379996D03*
X573867Y459903D03*
X575614Y461694D03*
X584076Y443828D03*
X588285Y448306D03*
X586136Y446335D03*
X592216Y445152D03*
X595070Y447970D03*
X558659Y493444D03*
X551366Y490744D03*
X543455Y490909D03*
X555313Y510114D03*
X548492Y495800D03*
X554792Y495887D03*
X543431Y510100D03*
X543455Y518114D03*
X551966Y515814D03*
X548620Y510114D03*
X543455Y498909D03*
X568549Y510114D03*
X562006D03*
X571345Y515814D03*
X558659D03*
X582912Y468948D03*
X581032Y467202D03*
X575166Y510098D03*
X575142Y517900D03*
X580266Y518114D03*
X580242Y510100D03*
X598817Y510157D03*
X595470Y515814D03*
X588777D03*
X602163Y517999D03*
X592124Y510114D03*
X585431D03*
X598817Y518057D03*
X602163Y510157D03*
X562006Y518157D03*
X595470Y513114D03*
X592124Y518157D03*
X571345Y513114D03*
X568699Y518157D03*
X551966Y513114D03*
X548620Y518157D03*
X558659Y513114D03*
X555313Y518157D03*
X543455Y496209D03*
Y493509D03*
X551366Y493344D03*
X548492Y498400D03*
X558659Y496144D03*
X554792Y498487D03*
X580266Y515514D03*
X543455D03*
X575166Y512700D03*
X580266Y512914D03*
X543455D03*
X575166Y515300D03*
X588777Y513114D03*
X585431Y518157D03*
X565266Y512774D03*
X543468Y528936D03*
X543481Y536750D03*
X543431Y547900D03*
X548620Y547914D03*
X551966Y553614D03*
X548620Y537049D03*
X551966Y530949D03*
X558659D03*
X555313Y537049D03*
X562006Y536999D03*
X564966Y530949D03*
X568699Y537049D03*
X571345Y553614D03*
Y531100D03*
X558659Y553614D03*
X555313Y547914D03*
X568549D03*
X562006D03*
X543455Y555914D03*
X571345Y568900D03*
X564966Y568749D03*
X562006Y574799D03*
X555313Y585714D03*
Y574849D03*
X558659Y568749D03*
X568549Y585714D03*
X562006D03*
X568699Y574849D03*
X551966Y568749D03*
X548620Y574849D03*
Y585714D03*
X543481Y574550D03*
X543431Y585700D03*
X543468Y566736D03*
X575166Y547898D03*
X575192Y529150D03*
X575166Y536999D03*
X598817Y547957D03*
X592124Y547914D03*
X595470Y530949D03*
X580242Y547900D03*
X580279Y528936D03*
X580292Y536750D03*
X592124Y537049D03*
X588777Y530949D03*
X598817Y528899D03*
Y537049D03*
X602163Y528899D03*
X585431Y547914D03*
Y537049D03*
X588777Y553614D03*
X595470D03*
X602163Y547957D03*
Y537057D03*
X580279Y566736D03*
X585431Y574849D03*
Y585714D03*
X598817Y585757D03*
Y574849D03*
Y566699D03*
X592124Y585714D03*
X595470Y568749D03*
X588777D03*
X592124Y574849D03*
X602163Y566699D03*
X598817Y555857D03*
X602163Y555799D03*
Y574857D03*
Y585757D03*
X575142Y555700D03*
X575192Y566950D03*
X575166Y585698D03*
Y574799D03*
X580266Y555914D03*
X580292Y574550D03*
X580242Y585700D03*
X562006Y528899D03*
X564966Y534700D03*
X592124Y528899D03*
X595470Y535100D03*
X568699Y528899D03*
X571345Y534700D03*
X548620Y528899D03*
X551966Y535100D03*
X555313Y528899D03*
X558659Y535100D03*
X580266Y553314D03*
X543455D03*
X575166Y550500D03*
X580266Y550714D03*
X543455D03*
X575166Y553100D03*
X588777Y550914D03*
X585431Y555957D03*
X565266Y550574D03*
X562006Y555957D03*
X595470Y550914D03*
X592124Y555957D03*
X571345Y550914D03*
X568699Y555957D03*
X551966Y550914D03*
X548620Y555957D03*
X558659Y550914D03*
X555313Y555957D03*
X580266Y531540D03*
X543455D03*
X575166Y534399D03*
X543455Y534149D03*
X575192Y531750D03*
X585431Y528899D03*
X588777Y535100D03*
X558659Y572900D03*
X575166Y588300D03*
X580266Y588514D03*
X543455D03*
X588777Y588714D03*
X565052D03*
X595470D03*
X571345D03*
X551966D03*
X558659D03*
X580266Y569340D03*
X575166Y572199D03*
X580266Y571949D03*
X543455D03*
X585431Y566699D03*
X588777Y572900D03*
X562006Y566699D03*
X564966Y572500D03*
X592124Y566699D03*
X595470Y572900D03*
X568699Y566699D03*
X571345Y572500D03*
X548620Y566699D03*
X551966Y572900D03*
X555313Y566699D03*
X580266Y534149D03*
X543455Y569340D03*
X575192Y569550D03*
X575166Y612599D03*
X585431Y612649D03*
X592124D03*
X598817D03*
X602163Y612657D03*
X555313Y612649D03*
X562006Y612599D03*
X568699Y612649D03*
X548620D03*
X571345Y591414D03*
X558659D03*
X571345Y606700D03*
X558659Y606549D03*
X564966D03*
X551966D03*
Y591414D03*
X543455Y593714D03*
X543468Y604536D03*
X543481Y612350D03*
X580292D03*
X580266Y593714D03*
X595470Y591414D03*
X588777D03*
X598817Y604499D03*
X595470Y606549D03*
X588777D03*
X598817Y593657D03*
X575192Y604750D03*
X575142Y593500D03*
X602163Y593599D03*
Y604499D03*
X580279Y604536D03*
X580266Y591114D03*
Y607140D03*
X543455Y591114D03*
Y607140D03*
X575166Y609999D03*
Y590900D03*
X585431Y604499D03*
Y593757D03*
X588777Y610700D03*
X562006Y604499D03*
Y593757D03*
X592124Y604499D03*
Y593757D03*
X595470Y610700D03*
X568699Y604499D03*
X571345Y610300D03*
X568699Y593757D03*
X548620Y604499D03*
X551966Y610700D03*
X548620Y593757D03*
X555313Y604499D03*
X558659Y610700D03*
X555313Y593757D03*
X580266Y609749D03*
X543455D03*
X575192Y607350D03*
X564966Y610300D03*
X608856Y-9901D03*
X612203D03*
X608856Y-1743D03*
X612203D03*
X615549D03*
Y9157D03*
X608856D03*
X612203D03*
X615549Y-9901D03*
X623000Y-3000D03*
X624770Y-640D03*
X620092Y13078D03*
X620192Y31978D03*
Y-5822D03*
X612203Y16999D03*
X608856D03*
X612203Y27899D03*
X608856D03*
X615549D03*
Y16999D03*
X647317Y-1310D03*
X660676Y-2600D03*
X656807Y-20652D03*
X657250Y-2050D03*
X663699Y3861D03*
X660000Y-17500D03*
X648550Y8550D03*
X651100Y8650D03*
X662700Y-17900D03*
X651300Y20000D03*
X659200Y31500D03*
X651300Y17500D03*
X661494Y32946D03*
X645430Y31067D03*
X656300Y22800D03*
X653800D03*
X656600Y31500D03*
X663300Y10000D03*
X651100Y11700D03*
X648500Y11600D03*
X648867Y31258D03*
X651442Y31225D03*
X659700Y22900D03*
X654016Y31150D03*
X647400Y-6900D03*
X605510Y27899D03*
Y9157D03*
X647000Y-9500D03*
X605510Y-1743D03*
Y-9901D03*
Y16999D03*
X647000Y-12100D03*
X659747Y-12132D03*
X620070Y50878D03*
X620192Y69778D03*
X612203Y54799D03*
X615549Y46957D03*
X608856Y54799D03*
X612203Y46957D03*
X608856D03*
X615549Y36057D03*
X608856D03*
X612203D03*
X608856Y65699D03*
X612203D03*
X615549D03*
Y54799D03*
X612203Y92599D03*
X608856D03*
X612203Y84757D03*
X608856D03*
X615549D03*
Y73857D03*
X608856D03*
X612203D03*
X615549Y92599D03*
X620092Y88678D03*
X663500Y48000D03*
X663700Y65600D03*
X663476Y45296D03*
X655600Y69100D03*
X658100D03*
X655600Y66100D03*
X658100D03*
X658567Y47639D03*
Y44639D03*
X656067D03*
Y47639D03*
X647600Y84200D03*
X647304Y91882D03*
X650204Y91282D03*
X649200Y88800D03*
Y86300D03*
X656500Y75300D03*
X652500D03*
X650000D03*
X652804Y90482D03*
X659000Y75300D03*
X646200Y86300D03*
Y88800D03*
X644904Y92382D03*
X650000Y72300D03*
X659000D03*
X656500D03*
X652500D03*
X652718Y93881D03*
X662352Y89566D03*
X605510Y92599D03*
Y73857D03*
Y36057D03*
Y46957D03*
Y84757D03*
Y65699D03*
Y54799D03*
X618800Y100100D03*
X616115Y108339D03*
X603163Y103971D03*
X608600Y103000D03*
X620054Y114096D03*
X633800Y119000D03*
X609482Y124568D03*
X622200Y112200D03*
X616167Y118627D03*
X605300Y124600D03*
X630000Y126572D03*
X624500Y129400D03*
X626900Y128300D03*
X633580Y125560D03*
X628673Y142718D03*
X632173Y142018D03*
X661700Y142300D03*
X644055Y144493D03*
X642673Y139811D03*
X639173Y140618D03*
X654555Y142193D03*
X651055Y142893D03*
X647555Y143643D03*
X658055Y141493D03*
X635673Y141318D03*
X636481Y124951D03*
X635951Y127419D03*
X661053Y115971D03*
X658490Y115432D03*
X650307Y115518D03*
X647809Y116121D03*
X645311Y116724D03*
X650120Y122700D03*
X660900Y123650D03*
Y126650D03*
X647120Y122700D03*
X657900Y126650D03*
Y123650D03*
X651920Y125750D03*
X656111Y121550D03*
X653111D03*
X654558Y115101D03*
X640043Y117728D03*
X639100Y124200D03*
X638800Y126700D03*
X648690Y125590D03*
X643674Y123573D03*
X644950Y125750D03*
X641950D03*
X642899Y117112D03*
X626040Y98281D03*
X613602Y118047D03*
Y109247D03*
X617400Y115800D03*
X605028Y119000D03*
X604977Y110200D03*
X609860Y201356D03*
X613082Y200676D03*
X613773Y196796D03*
X610273Y197496D03*
X606400Y201000D03*
X606773Y198196D03*
X603273Y198896D03*
X613648Y204494D03*
X608648D03*
X604453Y202983D03*
X623648Y209494D03*
Y216994D03*
Y211994D03*
Y214494D03*
X613648Y209494D03*
Y211994D03*
X618648Y209494D03*
Y214494D03*
X621148Y211994D03*
Y216994D03*
X613648Y214494D03*
Y216994D03*
X623648Y206994D03*
X611148D03*
X618648D03*
X621148D03*
X616148D03*
Y211994D03*
Y216994D03*
X644750Y175650D03*
X660600Y175000D03*
X662786Y278084D03*
X660901Y279856D03*
X616148Y221994D03*
X623648Y224494D03*
Y226994D03*
X611148Y224494D03*
X613648D03*
X618648D03*
Y226994D03*
X621148D03*
X616148D03*
X608648D03*
Y224494D03*
X603300Y226700D03*
X613648Y226994D03*
X617235Y247735D03*
X614456Y244956D03*
X632500Y238500D03*
Y235000D03*
X632692Y248172D03*
X632532Y241717D03*
X630200Y248100D03*
X613648Y229494D03*
X621148D03*
X618648D03*
X611148D03*
X623648Y221994D03*
Y219494D03*
X611148Y221994D03*
X618648Y219494D03*
X621148Y221994D03*
X633308Y263808D03*
X621165Y256075D03*
X620850Y253416D03*
X613648Y219494D03*
Y221994D03*
X651235Y249165D03*
X657700Y250172D03*
X660588Y250312D03*
X662800Y248600D03*
X643500Y272262D03*
X654950Y253446D03*
X639320Y268000D03*
X652500Y273600D03*
X647487Y280308D03*
X643591Y266983D03*
X643500Y274868D03*
X642855Y269660D03*
X647469Y277639D03*
X642800Y264000D03*
X643100Y253700D03*
X642800Y261100D03*
X624500Y240500D03*
X627529Y280441D03*
X659900Y256900D03*
Y269200D03*
X606148Y229494D03*
X633410Y269610D03*
Y274610D03*
X656100Y275500D03*
X649800Y252600D03*
X652700Y270600D03*
X618279Y251393D03*
X662238Y296146D03*
X628950Y293550D03*
X654600Y296000D03*
X656042Y287439D03*
X664267Y292668D03*
X661232Y287321D03*
X655000Y284600D03*
X646700Y308850D03*
X652000Y284500D03*
X663200Y298600D03*
X644800Y292150D03*
X654500Y298600D03*
X652100Y288300D03*
X639045Y299555D03*
X639100Y309500D03*
X639622Y290210D03*
X643823Y289650D03*
X658500Y284500D03*
X658853Y294305D03*
X648900Y336600D03*
X646900Y320100D03*
Y317300D03*
X646800Y326100D03*
X646272Y328800D03*
X658900Y339150D03*
X636100Y329800D03*
X649000Y339400D03*
X638790Y329500D03*
X639350Y339980D03*
X639100Y319500D03*
X637143Y322000D03*
X637561Y312000D03*
X637600Y307000D03*
X662200Y284800D03*
X631250Y289650D03*
X628525Y287832D03*
X636799Y285670D03*
X636985Y288264D03*
X634407Y287915D03*
X641665Y281139D03*
X655900Y307700D03*
X656300Y312300D03*
X660700Y307700D03*
X655900Y316500D03*
X656000Y329800D03*
X655900Y320500D03*
X656000Y325100D03*
X660900Y329800D03*
X637561Y317000D03*
X637600Y302000D03*
X632869Y293720D03*
X646520Y297400D03*
X657950Y296850D03*
X637681Y332390D03*
Y337390D03*
X637143Y327000D03*
X664100Y348000D03*
X648800D03*
X658900D03*
X662936Y367171D03*
X659936Y364171D03*
X662936D03*
X654000Y348000D03*
X649600Y391200D03*
X664194Y351206D03*
X654194D03*
X659694D03*
X649194D03*
X609191Y451454D03*
X615300Y457900D03*
X624600Y419400D03*
X626737Y421000D03*
X619800Y416200D03*
X624300Y422100D03*
X627000Y423436D03*
X622900Y424200D03*
X619680Y422600D03*
X625200Y425400D03*
X621800Y421100D03*
X619700Y419500D03*
X634200Y436800D03*
X637300Y437200D03*
X640300Y437600D03*
X620400Y463990D03*
X629600Y425100D03*
X622100Y417900D03*
X608800Y463475D03*
X625430Y490100D03*
X607012Y465997D03*
X623660Y466746D03*
X605249Y480891D03*
X605826Y475894D03*
Y473394D03*
X634967Y470790D03*
X605206Y483291D03*
X618430Y491550D03*
X623400Y476300D03*
X619260Y466610D03*
X629300Y490000D03*
X612000Y484000D03*
X632113Y496892D03*
X619392Y514700D03*
X612515Y498752D03*
X612203Y510157D03*
X608856D03*
X615549D03*
X612203Y517999D03*
X608856D03*
X615549D03*
X623600Y521700D03*
X656900Y482290D03*
X649600Y492400D03*
X660500Y492000D03*
X656100Y486900D03*
X656050Y489500D03*
X637148Y472809D03*
X657227Y479116D03*
X662181Y479149D03*
X659770D03*
X648500Y477400D03*
X659070Y488709D03*
X639197Y490367D03*
X652000Y513900D03*
X655000D03*
X661500D03*
X658500D03*
X658900Y509300D03*
X646200Y499700D03*
X648025Y501575D03*
X609470Y484060D03*
X625569Y481568D03*
X628700Y482000D03*
X653800Y496600D03*
X641150Y484300D03*
X611250Y476750D03*
X605510Y517999D03*
Y510157D03*
X609284Y480055D03*
X618800Y474500D03*
X619390Y469450D03*
X639120Y475620D03*
X608800Y468475D03*
Y473475D03*
X636500Y493924D03*
X627000Y478300D03*
X620192Y532978D03*
X608856Y547957D03*
X615549D03*
X612203D03*
X608856Y528899D03*
X612203D03*
X608856Y537057D03*
X615549D03*
X612203D03*
X615549Y528899D03*
X608856Y566699D03*
X612203D03*
Y555799D03*
X608856D03*
X615549Y574857D03*
X612203D03*
X615549Y585757D03*
X612203D03*
X608856Y574857D03*
Y585757D03*
X615549Y555799D03*
Y566699D03*
X618892Y555800D03*
X618292Y574300D03*
X662640Y528330D03*
X646150Y540350D03*
Y543350D03*
Y546350D03*
X650900Y552500D03*
X657100D03*
X654150Y530200D03*
X651100Y532700D03*
X651150Y530200D03*
X657250Y534300D03*
Y531300D03*
X659750Y534300D03*
Y531300D03*
X654200Y532800D03*
X653700Y552500D03*
X660200D03*
X652140Y577011D03*
Y574511D03*
X660217Y576734D03*
X649700Y574400D03*
X662000Y589000D03*
X651750Y584150D03*
X653100Y587000D03*
X661500Y569800D03*
X658900D03*
X650050Y568623D03*
X647350D03*
X663100Y574200D03*
X644800Y563300D03*
X647800D03*
X650800D03*
X653800D03*
X649700Y577000D03*
X605510Y566699D03*
Y528899D03*
Y555799D03*
Y585757D03*
Y574857D03*
Y537057D03*
Y547957D03*
X608856Y612657D03*
X615549D03*
X612203D03*
X631741Y615759D03*
X655100Y614100D03*
X612203Y604499D03*
X608856D03*
X612203Y593599D03*
X608856D03*
X615549Y604499D03*
Y593599D03*
X618192Y593600D03*
X620033Y608878D03*
X655100Y611500D03*
X644500Y594400D03*
X648180Y590702D03*
X646760Y592992D03*
X660230Y598170D03*
X627705Y611973D03*
X629977Y613024D03*
X605510Y604499D03*
Y612657D03*
Y593599D03*
X718975Y-4451D03*
X713824Y-18333D03*
X665942Y4716D03*
X674300Y9847D03*
X671800D03*
X669300D03*
X673900Y23100D03*
X671400D03*
X668900D03*
X690000Y15300D03*
X683800Y24856D03*
X670430Y29253D03*
X689900Y20800D03*
X692500Y15300D03*
X666100Y10000D03*
X684126Y28137D03*
X681426D03*
X692400Y20800D03*
X679936Y18406D03*
X670400Y26100D03*
X716858Y-14448D03*
X710263Y-14500D03*
X723827Y-14658D03*
X710327Y-11968D03*
X712796Y-16011D03*
X716921Y-6048D03*
X701100Y8100D03*
X704450Y4950D03*
X710800Y7100D03*
X705250Y8600D03*
X717720Y23279D03*
X715114Y26395D03*
X704500Y26300D03*
X723715Y23462D03*
X714823Y23610D03*
X704150Y19650D03*
X708000Y26600D03*
X700500D03*
X701120Y19619D03*
X698470Y19669D03*
X714337Y7852D03*
Y5352D03*
Y2852D03*
X718555Y-16147D03*
X719400Y14300D03*
X711791Y23716D03*
X710107Y-19839D03*
X708330Y-17806D03*
X665396Y23000D03*
X680200Y13100D03*
X714300Y-1900D03*
X724837Y13852D03*
X666500Y48000D03*
X665100Y68600D03*
X668100D03*
X666700Y65600D03*
X684904Y39943D03*
X689500Y37900D03*
X675235Y36797D03*
X685000Y46650D03*
X685100Y43000D03*
X670227Y34277D03*
X690100Y93200D03*
X664471Y86061D03*
X694600Y85000D03*
X693000Y92500D03*
X678020Y69870D03*
X678300Y92630D03*
Y95130D03*
X675630Y94988D03*
X681300Y95130D03*
Y92630D03*
X684300D03*
X687400Y93900D03*
X673830Y83050D03*
X676430D03*
X676500Y80500D03*
X673900D03*
X674010Y77970D03*
X676610D03*
X692200Y83800D03*
X695000Y67000D03*
X699880Y66840D03*
X724200Y64730D03*
X722460Y69550D03*
X713680Y60910D03*
X700360Y72160D03*
X694910Y72220D03*
X713050Y63650D03*
X710440Y63710D03*
X704880Y66750D03*
X697747Y72184D03*
X723700Y67400D03*
X713620Y58270D03*
X715800Y59490D03*
Y57000D03*
X713590Y53260D03*
X713610Y55730D03*
X700640Y69500D03*
X703120Y69380D03*
X702380Y66840D03*
X697440Y66900D03*
X700904Y38439D03*
X723603Y46929D03*
X721141Y46900D03*
X716742Y41062D03*
X713300Y86000D03*
X707329Y88955D03*
X705972Y86660D03*
X716176Y46822D03*
X716700Y43800D03*
X711100Y38700D03*
X714023Y38653D03*
X713674Y46822D03*
X714023Y41053D03*
X716900Y38500D03*
X711100Y41100D03*
X714000Y43900D03*
X722312Y48999D03*
X718600Y46921D03*
X719850Y48970D03*
X699800Y89100D03*
X713830Y82730D03*
X715130Y79574D03*
X697200Y79500D03*
X697100Y90600D03*
X703845Y88830D03*
X716268Y88683D03*
X716894Y84047D03*
X713115Y88629D03*
X701500Y85500D03*
X698300Y85300D03*
X709560Y84648D03*
X670795Y89189D03*
X692000Y45000D03*
Y48500D03*
X697500D03*
Y45000D03*
X701525Y35610D03*
X720572Y88700D03*
X670503Y115884D03*
X664700Y142800D03*
X675600Y144900D03*
Y150000D03*
X679900Y128200D03*
X682400Y127085D03*
X684900D03*
X673566Y116724D03*
X676494Y116940D03*
X668665Y118185D03*
X671249Y118744D03*
X677896Y119093D03*
X674896D03*
X693600Y103100D03*
X694459Y105382D03*
X691810Y105540D03*
X701953Y104902D03*
X715505Y155076D03*
X720700Y154750D03*
X725650Y155000D03*
X696100Y102700D03*
X696832Y104986D03*
X699400Y105060D03*
X704419Y104448D03*
X698600Y102600D03*
X691583Y200124D03*
X689033D03*
X686533D03*
Y196624D03*
X689033D03*
X691583D03*
X715550Y158880D03*
X705550D03*
X710550D03*
X709341Y190507D03*
X724888Y188930D03*
X709200Y198700D03*
X720369Y205199D03*
X714391Y215809D03*
X709182Y203948D03*
X709200Y201300D03*
X711800Y203100D03*
X706600Y201300D03*
X715100Y213344D03*
X715727Y218267D03*
X716480Y194700D03*
X709400Y195763D03*
X701956Y195294D03*
X705292Y195729D03*
X714137Y195682D03*
X711886Y194714D03*
X719686Y195421D03*
X722117Y195399D03*
X697568Y196197D03*
X707529Y193200D03*
X704907Y191638D03*
X701129Y192106D03*
X697746Y193205D03*
X716557Y198557D03*
X692513Y213800D03*
X692673Y206200D03*
X692500Y210100D03*
X690861Y211917D03*
Y215717D03*
X692400Y218100D03*
X690861Y204317D03*
Y208117D03*
X706500Y217400D03*
Y214900D03*
Y207800D03*
X706561Y211417D03*
Y204217D03*
X719315Y239104D03*
X669900Y224000D03*
X672500Y224100D03*
X678454Y278000D03*
X675380Y246340D03*
X678000Y246400D03*
X668100Y232200D03*
X667240Y246600D03*
X672530Y246300D03*
X677400Y232300D03*
X674300Y232200D03*
X675200Y224100D03*
X667600Y250200D03*
X688643Y225980D03*
X688388Y231280D03*
X678400Y224100D03*
X690380Y252240D03*
X690939Y266630D03*
X693530Y261240D03*
X690660Y264000D03*
X690704Y271324D03*
X690130Y277380D03*
X689960Y260500D03*
X671100Y232200D03*
X701800Y246480D03*
X669750Y246350D03*
X710572Y244773D03*
X719360Y241504D03*
X710627Y242061D03*
X702000Y243900D03*
X722050Y221150D03*
X707653Y226347D03*
X718300Y227400D03*
X701700Y226600D03*
X725725Y241560D03*
X710500Y224500D03*
X720450Y249950D03*
X710900Y231660D03*
X700000Y233700D03*
X704450Y226600D03*
X713800Y221544D03*
X709700Y275500D03*
X709600Y278100D03*
X704500Y252500D03*
X700800Y261300D03*
X715200Y258900D03*
X704090Y256080D03*
X710675Y263425D03*
X700900Y264100D03*
X697255Y267098D03*
X700400Y257200D03*
X694361Y223317D03*
Y220817D03*
X690861D03*
Y223317D03*
X672300Y269200D03*
X672200Y256800D03*
X706561Y219917D03*
X719900Y269300D03*
X725500Y279300D03*
X725300Y269400D03*
X719600Y279400D03*
X713700Y224144D03*
X717420Y249920D03*
X679300Y261700D03*
X677800Y254100D03*
X667700Y275600D03*
X709949Y272647D03*
X706800Y278100D03*
X710700Y260200D03*
X723400Y250000D03*
X713970Y308360D03*
X704175Y287275D03*
X704214Y290775D03*
X674469Y287375D03*
X686470Y282220D03*
X695000Y289500D03*
X670800Y292600D03*
X688100Y308600D03*
X680000Y281900D03*
X672150Y288350D03*
X695300Y338100D03*
X695400Y328000D03*
X686600Y335600D03*
X687400Y319833D03*
X687138Y317397D03*
X674700Y339200D03*
X687400Y328200D03*
X687300Y325200D03*
X684100Y338200D03*
X695400Y318000D03*
X706800Y281900D03*
X695800Y308000D03*
X696088Y297069D03*
X704500Y293800D03*
X707130Y310150D03*
X718200Y295000D03*
X713970Y310860D03*
X711900Y327700D03*
X712400Y324400D03*
X701100Y339000D03*
X698600Y338900D03*
X706300Y318400D03*
X683490Y282110D03*
X704404Y310875D03*
X697521Y320500D03*
X697120Y305349D03*
X670800Y298400D03*
X690048Y284053D03*
X665000Y284800D03*
X690048Y281053D03*
X678200Y307800D03*
X672700Y307700D03*
X667100D03*
X678100Y324800D03*
X672200Y329800D03*
X678100Y329600D03*
X666900Y329700D03*
X678200Y313700D03*
Y319300D03*
X688924Y288147D03*
X668000Y298400D03*
X704404Y315875D03*
X673922Y298078D03*
X686140Y298260D03*
X667900Y339000D03*
X710272Y281911D03*
X724000Y291700D03*
X705800Y301600D03*
X697521Y325500D03*
X697352Y335500D03*
Y330500D03*
X697120Y300349D03*
X679000Y348000D03*
X674194Y358467D03*
X683417Y364972D03*
X677563Y365496D03*
X695700Y357300D03*
X695644Y354644D03*
X695700Y346300D03*
X688600Y365100D03*
X671936Y367171D03*
X665936Y370171D03*
X684900Y348000D03*
X674600D03*
X671936Y370171D03*
X665936Y367171D03*
X668936Y370171D03*
Y367171D03*
X665936Y364171D03*
X668936D03*
X669093Y348120D03*
X671936Y373171D03*
X668936D03*
X670300Y375600D03*
X683100Y392200D03*
X713900Y347800D03*
X698560Y374430D03*
X713900Y342800D03*
Y352800D03*
Y350300D03*
Y345300D03*
X679523Y385808D03*
X678730Y362841D03*
X686619Y392600D03*
X691240Y390039D03*
X669194Y351206D03*
X674194D03*
X679194D03*
X684194D03*
X676900Y381800D03*
X679385Y388705D03*
X687427Y384926D03*
X690040Y412030D03*
X685600Y432500D03*
X690600D03*
X680370Y427770D03*
X687400Y411200D03*
X690600Y437500D03*
X703876Y414949D03*
X705850Y417093D03*
X710600Y420267D03*
X710423Y417423D03*
X708346Y415859D03*
X708011Y419078D03*
X712980Y417900D03*
X713493Y420449D03*
X718546Y500283D03*
X723748Y499091D03*
X701255Y521538D03*
X676900Y489400D03*
X666500Y487600D03*
Y484600D03*
X669500D03*
Y481600D03*
X674300Y489500D03*
X689825Y491755D03*
X693604Y491803D03*
X664610Y512810D03*
X685050Y503970D03*
X682050D03*
X689825Y494255D03*
X693604Y494303D03*
X669300Y504000D03*
X677800Y485600D03*
X680300Y485700D03*
X676600Y501300D03*
X690500Y523300D03*
X675500Y521900D03*
X691000Y498200D03*
X688202Y497736D03*
X679049Y503746D03*
X671500Y501300D03*
X674000Y501200D03*
X704500Y512850D03*
X716267Y522020D03*
X703028Y495600D03*
X709028D03*
X706028D03*
X707511Y483439D03*
X720300Y485800D03*
X723792Y489148D03*
X721301Y488200D03*
X703028Y492600D03*
X706028D03*
X710137Y483583D03*
X708700Y499400D03*
X708500Y512500D03*
X700500Y512850D03*
X701200Y524250D03*
X712100Y512700D03*
X701500Y505500D03*
X710643Y505496D03*
X703800Y507100D03*
X716100Y525200D03*
X711339Y499478D03*
X713200Y505500D03*
X715900Y505650D03*
X715009Y512917D03*
X726040Y506080D03*
X721414Y508986D03*
X720565Y511338D03*
X721894Y501346D03*
X675080Y485570D03*
X696000Y496800D03*
X679700Y489400D03*
X686200Y511700D03*
X680000Y511800D03*
X711704Y525483D03*
X707850Y505700D03*
X686375Y527778D03*
X685200Y530500D03*
X684500Y532900D03*
X680910Y582000D03*
X693200Y575900D03*
X674200Y588900D03*
X690100Y575860D03*
X689193Y573493D03*
X693126Y581380D03*
X671599Y573493D03*
X671791Y588920D03*
X674099Y573493D03*
X669099D03*
X668891Y588900D03*
X696600Y581400D03*
X665700Y574200D03*
X713650Y540750D03*
X715650Y542250D03*
Y545250D03*
X713650Y546750D03*
X708000Y553250D03*
X720200Y551750D03*
X715650Y551250D03*
X716100Y527700D03*
X713600D03*
Y530200D03*
Y532700D03*
X716100D03*
Y530200D03*
X725000Y533700D03*
X696000Y553250D03*
X715650Y548250D03*
X713650Y549750D03*
X723200Y551750D03*
X699000Y553250D03*
X702000D03*
X705000D03*
X713650Y543750D03*
X723200Y554750D03*
X706500Y555750D03*
X703500D03*
X700500D03*
X720200Y554750D03*
X709500Y555750D03*
X712600Y571900D03*
X716300Y569400D03*
X707500Y587800D03*
X722200Y571300D03*
X702100Y568800D03*
X702000Y571400D03*
X725400Y580900D03*
X722500D03*
X691900Y531350D03*
Y534850D03*
X697500Y534750D03*
Y531250D03*
X680029Y577503D03*
X718200Y581000D03*
X713500Y618000D03*
X711500Y616274D03*
X665000Y598500D03*
X725173Y598171D03*
X724106Y609550D03*
X721106D03*
X708900Y589850D03*
X706100D03*
X712000Y597000D03*
Y599500D03*
X708800Y599300D03*
Y596700D03*
X712106Y604050D03*
X717612Y598554D03*
X716106Y609050D03*
X712106Y606650D03*
X722406Y598950D03*
X713132Y609306D03*
X755000Y17255D03*
X732600Y3600D03*
X755500Y8700D03*
X753600Y-4300D03*
X734500Y-5700D03*
X734916Y-1587D03*
X732316D03*
X732191Y-4087D03*
X735020Y-8858D03*
X726327Y-14658D03*
X728837Y-12763D03*
X728716Y-15465D03*
X731210Y-15134D03*
X736715Y33487D03*
X734201Y33510D03*
X726250Y23550D03*
X729500Y23500D03*
X729600Y17991D03*
X734256D03*
X754600Y300D03*
X751900Y400D03*
X731457Y8471D03*
X732335Y6000D03*
X786414Y-9650D03*
X766300Y-1800D03*
X765400Y-9800D03*
X779771Y9114D03*
X773228D03*
Y-1801D03*
X779921Y-1751D03*
X776188Y-7851D03*
X769881Y-9901D03*
X782567Y-7700D03*
X786388Y9098D03*
Y-1801D03*
X782567Y33700D03*
X779921Y27899D03*
X776188Y33700D03*
X773228Y27899D03*
X786414Y30750D03*
X786388Y33399D03*
X764100Y17100D03*
X760100Y17255D03*
X763500Y23940D03*
X786414Y28150D03*
X769881Y27899D03*
X782567Y14814D03*
Y30100D03*
X769881Y16839D03*
X776224Y14714D03*
X776188Y29949D03*
X786364Y16900D03*
X756714Y23130D03*
X753675Y23239D03*
X756176Y-4300D03*
X776274Y12114D03*
X773228Y-9901D03*
X776188Y-4100D03*
X773228Y17157D03*
X782567Y12114D03*
X779921Y-9901D03*
X782567Y-4100D03*
X779921Y17157D03*
X769881Y9157D03*
X786388Y11700D03*
Y-4401D03*
X786414Y-7050D03*
X786388Y14300D03*
X736631Y36122D03*
X736655Y38531D03*
X731887Y40916D03*
X734155Y38531D03*
X734131Y36122D03*
X731843Y43571D03*
X756100Y36200D03*
X755500Y46700D03*
X737800Y55800D03*
X731200Y68600D03*
X733600Y68546D03*
X733642Y66146D03*
X731242Y66200D03*
X731332Y63801D03*
X733732Y63747D03*
X751600Y41000D03*
X755500Y55200D03*
X752600Y86200D03*
X735700Y82700D03*
X752680Y83500D03*
X733740Y95230D03*
X730923Y75315D03*
X731910Y92790D03*
X751708Y73800D03*
X755500Y84361D03*
X733671Y75412D03*
X753100Y92111D03*
X779921Y65699D03*
X773228D03*
X786414Y68550D03*
X779921Y54957D03*
X782567Y49914D03*
X773228Y54957D03*
X776274Y49914D03*
X786388Y52100D03*
Y49500D03*
X764100Y55100D03*
X763500Y59700D03*
X765900Y35800D03*
X786388Y35999D03*
X786364Y54700D03*
X786388Y46898D03*
X773228Y46914D03*
X779771D03*
X776188Y67749D03*
X769881Y66000D03*
X782567Y67900D03*
Y52614D03*
X769881Y54839D03*
X779921Y35983D03*
X773228D03*
X776224Y52514D03*
X769881Y92500D03*
X773228Y84714D03*
X779771D03*
X776224Y90314D03*
X782567Y90414D03*
X779921Y73849D03*
X773228Y73799D03*
X782567Y71500D03*
X779921Y92757D03*
X782567Y87714D03*
X776188Y71500D03*
X773228Y92757D03*
X776274Y87714D03*
X786388Y89900D03*
Y71199D03*
Y87300D03*
X761650Y94550D03*
X769500Y84700D03*
X763400Y78300D03*
X766824Y85943D03*
X763930Y85100D03*
X786414Y65950D03*
X786388Y73799D03*
X786364Y92500D03*
X786388Y84698D03*
X730038Y88408D03*
X732599D03*
X735241Y88329D03*
X763350Y81220D03*
X732734Y82626D03*
X769881Y46957D03*
X746600Y103900D03*
X730600Y154984D03*
X746000Y150500D03*
X740718Y150957D03*
X741700Y102000D03*
X752900Y101000D03*
X744200Y102800D03*
X769100Y102900D03*
X766500D03*
X764000Y95750D03*
X756800Y99400D03*
Y102000D03*
X758400Y156200D03*
X747600Y161450D03*
X740650Y164800D03*
X735600Y164900D03*
X740650Y158800D03*
X727776Y188811D03*
X733564Y189288D03*
X742091Y188333D03*
X747469Y188368D03*
X755248D03*
X739641Y190634D03*
X752708Y188455D03*
X750167Y188490D03*
X744928Y188438D03*
X737319Y189766D03*
X739359Y188125D03*
X735626Y187965D03*
X731155Y189256D03*
X754726Y205037D03*
X752226D03*
X749726D03*
X754726Y207537D03*
X752226D03*
X749726D03*
X742937Y218574D03*
X737536Y192392D03*
X771232Y214033D03*
X777182Y212033D03*
X766368Y183636D03*
X765227Y186164D03*
X765007Y188583D03*
X762667Y186186D03*
X762533Y188626D03*
X763881Y184103D03*
X760084Y188508D03*
X760258Y186077D03*
X767692Y185654D03*
X767476Y188323D03*
X757654Y188464D03*
X758400Y159200D03*
X774582Y212033D03*
X770200Y208600D03*
X765116Y216512D03*
X779932Y212033D03*
X770300Y204930D03*
X769044Y191348D03*
X775171Y218616D03*
X787371Y215216D03*
Y217716D03*
X777700Y218600D03*
X765144Y213508D03*
X727969Y236770D03*
X736612Y237908D03*
X727997Y239195D03*
X736625Y240308D03*
X737837Y222364D03*
Y224964D03*
X740300Y228100D03*
X742897Y229573D03*
X731662Y247716D03*
X742937Y221174D03*
Y223774D03*
X740437Y224964D03*
Y222364D03*
X748700Y254000D03*
X751363Y254207D03*
X754758Y273356D03*
X749100Y279500D03*
X746303Y243122D03*
X746321Y240569D03*
X777000Y243500D03*
X766732Y225189D03*
X761580Y220160D03*
X760304Y235827D03*
X768560Y244055D03*
X765116Y248512D03*
X779932Y244033D03*
X766632Y222589D03*
X771650Y246451D03*
X765116Y280512D03*
X779400Y276200D03*
X766532Y254652D03*
X771650Y278451D03*
X766632Y257252D03*
X776700Y275500D03*
X748990Y267450D03*
X765007Y252363D03*
X769019Y276400D03*
X762616Y270113D03*
X761480Y242720D03*
X726328Y249979D03*
X731100Y269300D03*
Y279300D03*
X775200Y230500D03*
X775171Y227116D03*
Y234316D03*
X787371Y247216D03*
Y249716D03*
X775232Y221133D03*
X777700Y250600D03*
X775232Y223633D03*
X775171Y250616D03*
X775271Y262716D03*
X775171Y259116D03*
Y266316D03*
X775232Y253133D03*
Y255633D03*
X787371Y279216D03*
X748700Y257500D03*
X759700Y232000D03*
X739500Y247500D03*
X749126Y220843D03*
X742897Y226773D03*
X739400Y253400D03*
X730000Y254675D03*
X754263Y254207D03*
X754846Y276340D03*
X765144Y245508D03*
X749090Y270250D03*
X765144Y277508D03*
X774347Y339983D03*
X762760Y339500D03*
X736000Y303400D03*
X741250Y298856D03*
X727300Y302910D03*
X727474Y338363D03*
Y335363D03*
X732474D03*
Y338363D03*
X756114Y316209D03*
X741512Y315538D03*
X729974Y338363D03*
Y335363D03*
X767310Y286530D03*
X779100Y307900D03*
X771600Y310600D03*
X776270Y307100D03*
X765007Y284363D03*
X771278Y307918D03*
X762842Y302434D03*
X765116Y312512D03*
X767000Y318500D03*
X779932Y340033D03*
X777182D03*
X766732Y321189D03*
X765007Y316363D03*
X765730Y335064D03*
X775271Y294716D03*
X775171Y291116D03*
Y298316D03*
X777700Y282600D03*
X775232Y287633D03*
Y285133D03*
X775171Y282616D03*
X787371Y281716D03*
Y311216D03*
X775271Y326716D03*
X775171Y323116D03*
Y330316D03*
X777800Y314700D03*
X775171Y314616D03*
X787371Y313716D03*
X775232Y317133D03*
Y319633D03*
X749800Y282300D03*
X757956Y328095D03*
X729405Y290725D03*
X743600Y304100D03*
X737750Y298894D03*
X737912Y315500D03*
X764980Y287980D03*
X765144Y309508D03*
Y341508D03*
X727474Y344663D03*
Y367463D03*
X732474D03*
X729974D03*
X727474Y364863D03*
X732474D03*
X729974D03*
Y347663D03*
X727474D03*
X732474D03*
Y344663D03*
X732000Y380000D03*
X727574Y373463D03*
X732574D03*
X730074D03*
X732574Y376063D03*
X730074D03*
X729974Y344663D03*
X731100Y362300D03*
X772443Y371976D03*
X765116Y344512D03*
X779882Y372033D03*
X767477Y350708D03*
X771700Y342501D03*
X766732Y353189D03*
X777100Y372000D03*
X765007Y348363D03*
X760140Y362819D03*
X758952Y384100D03*
X763333Y400212D03*
X772300Y403520D03*
X764131Y376747D03*
X766643Y382724D03*
X771400Y374400D03*
X764957Y380363D03*
X775171Y346616D03*
Y362316D03*
X775271Y358716D03*
X775171Y355116D03*
X787371Y343216D03*
Y345716D03*
X775232Y349133D03*
X777600Y346600D03*
X775232Y351633D03*
X787321Y374916D03*
Y377316D03*
X775182Y383633D03*
Y381133D03*
X778000Y378700D03*
X775121Y378616D03*
Y394316D03*
X775221Y390716D03*
X775121Y387116D03*
X760500Y359800D03*
X767155Y385550D03*
X764159Y373743D03*
X755487Y409903D03*
Y412403D03*
X748085Y412338D03*
X750585D03*
X753085D03*
Y409838D03*
X750585D03*
X748085D03*
X749640Y431797D03*
X739933Y447401D03*
X747950Y441600D03*
X748500Y438900D03*
X728940Y457806D03*
X746151Y433077D03*
X766200Y417005D03*
X775417Y435799D03*
X777979Y436516D03*
X760326Y414167D03*
Y411667D03*
X757826D03*
Y414167D03*
X762989Y411728D03*
X763069Y414441D03*
X768080Y418780D03*
X766394Y414397D03*
X763706Y514250D03*
X728373Y488356D03*
X731339Y489319D03*
X743483Y492937D03*
X752496Y515974D03*
X732522Y526808D03*
Y524308D03*
X750518Y522108D03*
X734922Y526808D03*
X756000Y525950D03*
X729000Y511500D03*
X731600Y511600D03*
X748524Y502174D03*
X743524D03*
X748524Y499674D03*
X750931Y499916D03*
X746024Y499674D03*
X743524D03*
X746024Y502174D03*
X786388Y515300D03*
Y512700D03*
X769500Y510100D03*
X763950Y508540D03*
X766535Y517900D03*
X763950Y506040D03*
Y511040D03*
X776224Y515714D03*
X779771Y510114D03*
X773228D03*
X769881Y517900D03*
X782567Y515814D03*
X786388Y510098D03*
X786364Y517900D03*
X779921Y518157D03*
X782567Y513114D03*
X773228Y518157D03*
X776274Y513114D03*
X738648Y492050D03*
X752900Y521121D03*
Y518621D03*
X763544Y522236D03*
X732442Y529300D03*
X734842D03*
X736300Y541500D03*
X756000Y537000D03*
X737400Y529400D03*
X734900Y531800D03*
X732400D03*
X726200Y551750D03*
X732098Y550000D03*
X729550D03*
X732098Y553000D03*
X729550D03*
X736000Y537700D03*
Y535200D03*
X733500Y537700D03*
Y535200D03*
X728000Y533750D03*
X754910Y556400D03*
X726200Y554750D03*
X727400Y571300D03*
X755000Y574800D03*
X752500Y585150D03*
X727106Y586550D03*
X732098Y556000D03*
X729550D03*
X755000Y566000D03*
X732600Y573950D03*
X786414Y531750D03*
X786388Y534399D03*
X782567Y550914D03*
X776274D03*
X786388Y553100D03*
Y550500D03*
X764400Y528600D03*
X769500Y536983D03*
X765100Y537110D03*
X773228Y536999D03*
X763677Y547783D03*
X776188Y530949D03*
X782567Y531100D03*
X769818Y529200D03*
X779921Y537049D03*
X782567Y553614D03*
X773228Y547914D03*
X779771D03*
X776224Y553514D03*
X786388Y536999D03*
X786414Y529150D03*
X786388Y547898D03*
X779921Y528899D03*
X776188Y534700D03*
X786414Y569550D03*
X786388Y572199D03*
X782567Y588714D03*
X776274D03*
X786388Y588300D03*
X763300Y566000D03*
X769500Y585700D03*
X764117Y575658D03*
X766535Y555700D03*
X763450Y585200D03*
X765900Y587300D03*
X786364Y555700D03*
X769881D03*
X773228Y574799D03*
X782567Y568900D03*
X769700Y566900D03*
X776188Y568749D03*
X779921Y574849D03*
X773228Y585714D03*
X779771D03*
X786388Y574799D03*
Y585698D03*
X786414Y566950D03*
X779921Y555957D03*
X782567Y572500D03*
X779921Y566699D03*
X773228Y555957D03*
X776188Y572500D03*
X773228Y566699D03*
X769500Y547900D03*
Y574700D03*
X782567Y534700D03*
X773228Y528899D03*
X733032Y604000D03*
X779921Y612649D03*
X773228Y612599D03*
X786388D03*
X769500Y612583D03*
X755000Y614500D03*
X728000Y623500D03*
X727000Y606600D03*
X739307Y598850D03*
X755800Y604600D03*
X726857Y610871D03*
X729616Y610863D03*
X753300Y593600D03*
X732500Y611000D03*
X782567Y610300D03*
X779921Y593757D03*
Y604499D03*
X776188Y610300D03*
X773228Y593757D03*
Y604499D03*
X786414Y607350D03*
X786388Y590900D03*
Y609999D03*
X764400Y604600D03*
X766535Y593500D03*
X766600Y590700D03*
X769700Y604900D03*
X776188Y606549D03*
X782567Y606700D03*
Y591414D03*
X776224Y591314D03*
X786414Y604750D03*
X786364Y593500D03*
X755900Y593650D03*
X803346Y-1751D03*
X810039Y-1801D03*
X791514Y-2050D03*
X791501Y-9864D03*
X812999Y-7851D03*
X806692D03*
X799999D03*
X816582Y9114D03*
X796653D03*
X791464Y9100D03*
X810039Y9114D03*
X803346D03*
X816732Y-1751D03*
X796653D03*
X799999Y29949D03*
X812999Y33700D03*
X810039Y27899D03*
X803346D03*
X796653D03*
X816732D03*
X791488Y30540D03*
Y33149D03*
X806692Y29949D03*
X812999D03*
X791501Y27936D03*
X791488Y17114D03*
X799999Y14814D03*
X813035Y14714D03*
X806692Y14814D03*
X828275Y9100D03*
X833464Y9114D03*
X840157D03*
X819378Y-7700D03*
X823199Y9098D03*
Y-1801D03*
X823225Y-9650D03*
X828312Y-9864D03*
X843503Y-7851D03*
X836810D03*
X846850Y-1801D03*
X828325Y-2050D03*
X833464Y-1751D03*
X840157D03*
X846850Y9114D03*
X833464Y27899D03*
X846850D03*
X819378Y33700D03*
X823225Y30750D03*
X828299Y30540D03*
X823199Y33399D03*
X828299Y33149D03*
X819378Y14814D03*
Y30100D03*
X843503Y14814D03*
X823175Y16900D03*
X823225Y28150D03*
X828312Y27936D03*
X836810Y29949D03*
X828299Y17114D03*
X836810Y14814D03*
X843503Y29949D03*
X840157Y27899D03*
X796653Y-9901D03*
X833464D03*
X840157D03*
X843503Y-3700D03*
X799999Y12114D03*
X836810D03*
X843503D03*
X840157Y17157D03*
X828299Y-4651D03*
Y11914D03*
X823199Y-4401D03*
Y11700D03*
X791488Y-4651D03*
Y11914D03*
X828299Y14514D03*
Y-7260D03*
X823199Y14300D03*
X823225Y-7050D03*
X791488Y-7260D03*
Y14514D03*
X819378Y12114D03*
X816732Y-9901D03*
Y17157D03*
X819378Y-4100D03*
X799999Y-3700D03*
X796653Y17157D03*
X803346Y-9901D03*
X806692Y12114D03*
Y-3700D03*
X803346Y17157D03*
X846850Y-9901D03*
Y17157D03*
X833464D03*
X836810Y-3700D03*
X810039Y-9901D03*
X813085Y12114D03*
X812999Y-4100D03*
X810039Y17157D03*
X791488Y54914D03*
X799999Y52614D03*
X796653Y46914D03*
X810039Y65699D03*
X803346D03*
X796653D03*
X816732D03*
X791488Y68340D03*
X810039Y54957D03*
X813085Y49914D03*
X806692Y34100D03*
X803346Y54957D03*
X806692Y49914D03*
X799999Y34100D03*
X796653Y54957D03*
X799999Y49914D03*
X816732Y54957D03*
X791488Y52314D03*
Y49714D03*
X791464Y46900D03*
X810039Y35999D03*
X803346Y36049D03*
X799999Y90414D03*
X791488Y92714D03*
X806692Y90414D03*
X812999Y71500D03*
X810039Y92757D03*
X813085Y87714D03*
X806692Y71900D03*
X803346Y92757D03*
X806692Y87714D03*
X799999Y71900D03*
X796653Y92757D03*
X799999Y87714D03*
X816732Y92757D03*
X791488Y70949D03*
Y87514D03*
Y90114D03*
X816582Y46914D03*
X816732Y36049D03*
X799999Y67749D03*
X812999D03*
X806692D03*
X791501Y65736D03*
X803346Y46914D03*
X806692Y52614D03*
X813035Y52514D03*
X810039Y46914D03*
X791514Y35750D03*
X796653Y36049D03*
X816582Y73849D03*
X791514Y73550D03*
X796653Y73849D03*
X810039Y73799D03*
X803346Y73849D03*
X816582Y84714D03*
X813035Y90314D03*
X803346Y84714D03*
X810039D03*
X796653D03*
X791464Y84700D03*
X846850Y65699D03*
X823225Y68550D03*
X828299Y68340D03*
X843503Y34100D03*
X833464Y54957D03*
X836810Y34100D03*
Y49914D03*
X846850Y54957D03*
X819378Y49914D03*
X823199Y52100D03*
X828299Y52314D03*
X823199Y49500D03*
X828299Y49714D03*
X819378Y67900D03*
Y52614D03*
X846850Y35999D03*
X833464Y36049D03*
X840157D03*
X823225Y65950D03*
X823175Y54700D03*
X823199Y46898D03*
Y35999D03*
X828299Y54914D03*
X828275Y46900D03*
X828325Y35750D03*
X833464Y46914D03*
X836810Y52614D03*
X840157Y46914D03*
X828312Y65736D03*
X836810Y67749D03*
X843503D03*
X846850Y46914D03*
X843503Y52614D03*
X840157Y65699D03*
X833464D03*
X823175Y92500D03*
X823199Y84698D03*
X846850Y73799D03*
X843503Y90414D03*
X846850Y84714D03*
X828325Y73550D03*
X840157Y73849D03*
X833464D03*
X828299Y92714D03*
X836810Y90414D03*
X840157Y84714D03*
X833464D03*
X828275Y84700D03*
X843503Y71900D03*
X840157Y92757D03*
X843503Y87714D03*
X836810Y71900D03*
X833464Y92757D03*
X836810Y87714D03*
X846850Y92757D03*
X819378Y71500D03*
Y87714D03*
X823199Y89900D03*
X828299Y70949D03*
Y87514D03*
X823199Y71199D03*
Y87300D03*
X828299Y90114D03*
X840157Y54957D03*
X843503Y49914D03*
X819378Y90364D03*
X823199Y73799D03*
X822400Y212400D03*
X799300Y195600D03*
Y199100D03*
X813700Y195600D03*
X790871Y215216D03*
Y217716D03*
X799620Y186547D03*
X798337Y181216D03*
X813700Y198900D03*
X804470Y186814D03*
X845100Y268200D03*
X847600D03*
X842600D03*
X847600Y243400D03*
X841400Y243300D03*
X847600Y238400D03*
X841400Y238300D03*
X847600Y240900D03*
X841400Y240800D03*
X789500Y231800D03*
X790900Y234000D03*
Y229700D03*
X790846Y225774D03*
X790882Y221723D03*
X790871Y247216D03*
Y249716D03*
X789471Y227742D03*
X789576Y223737D03*
X789554Y219723D03*
X790900Y253900D03*
X789432Y252000D03*
X790871Y266216D03*
X789432Y255800D03*
X790867Y257724D03*
X789432Y259800D03*
X789500Y263900D03*
X790885Y261711D03*
X790871Y279216D03*
X842600Y299900D03*
X845100D03*
X847600D03*
X845100Y331500D03*
X842600D03*
X847600D03*
X790871Y311216D03*
X789432Y284200D03*
Y288300D03*
Y292400D03*
X789400Y296200D03*
X790871Y298216D03*
X790937Y294270D03*
X790900Y290300D03*
Y286200D03*
X790871Y281716D03*
Y313716D03*
X789432Y319900D03*
Y323900D03*
X790900Y322000D03*
Y326000D03*
X790871Y330216D03*
X789500Y328000D03*
X789478Y315671D03*
X790800Y317700D03*
X805600Y403900D03*
X847600Y363000D03*
X845100D03*
X842600D03*
X847577Y381842D03*
X824000Y402863D03*
X840871Y391380D03*
X837272Y391420D03*
X827800Y402863D03*
X832300D03*
X789432Y348100D03*
Y352100D03*
X789597Y356105D03*
X789500Y360200D03*
X790900Y358200D03*
X790835Y354048D03*
X790867Y350024D03*
X790871Y345716D03*
Y343216D03*
Y362216D03*
X790821Y374916D03*
X790900Y389300D03*
X789500Y391300D03*
X790900Y393400D03*
Y381100D03*
X789582Y383200D03*
X790900Y385300D03*
X789500Y387300D03*
X790821Y377316D03*
X789282Y379200D03*
X797000Y404700D03*
X797200Y409830D03*
X805367Y407400D03*
X797780Y423484D03*
X800610Y415000D03*
X798500Y412600D03*
X799999Y513114D03*
X791488Y512914D03*
Y515514D03*
X816582Y510114D03*
X806692Y515814D03*
X813035Y515714D03*
X810039Y510114D03*
X791488Y518114D03*
X791464Y510100D03*
X799999Y515814D03*
X796653Y510114D03*
X803346D03*
Y518157D03*
X806692Y513114D03*
X796653Y518157D03*
X819378Y515764D03*
X843503Y515814D03*
X846850Y510114D03*
X823175Y517900D03*
X823199Y510098D03*
X828299Y518114D03*
X840157Y510114D03*
X833464D03*
X836810Y515814D03*
X846850Y518157D03*
X813085Y513114D03*
X810039Y518157D03*
X823199Y512700D03*
Y515300D03*
X819378Y513114D03*
X816732Y518157D03*
X828299Y515514D03*
Y512914D03*
X836810Y513114D03*
X833464Y518157D03*
X843503Y513114D03*
X840157Y518157D03*
X796653Y528899D03*
X791488Y534149D03*
Y531540D03*
X813085Y550914D03*
X806692D03*
X799999D03*
X791488Y550714D03*
Y553314D03*
X816582Y537049D03*
Y547914D03*
X810039Y536999D03*
X806692Y530949D03*
X812999D03*
X803346Y537049D03*
X796653D03*
X799999Y530949D03*
X791501Y528936D03*
X791514Y536750D03*
X799999Y553614D03*
X810039Y547914D03*
X796653D03*
X803346D03*
X791464Y547900D03*
X806692Y553614D03*
X813035Y553514D03*
X806692Y535100D03*
X803346Y528899D03*
X799999Y535100D03*
X816732Y555957D03*
Y566699D03*
X791488Y571949D03*
X813085Y588714D03*
X806692D03*
X799999D03*
X791488Y588514D03*
Y555914D03*
X810039Y585714D03*
X806692Y568749D03*
X810039Y574799D03*
X812999Y568749D03*
X803346Y585714D03*
X796653D03*
X791514Y574550D03*
X791464Y585700D03*
X799999Y568749D03*
X796653Y574849D03*
X803346D03*
X791501Y566736D03*
X816582Y585714D03*
Y574849D03*
X810039Y555957D03*
X812999Y572500D03*
X810039Y566699D03*
X803346Y555957D03*
X806692Y572900D03*
X803346Y566699D03*
X796653Y555957D03*
X799999Y572900D03*
X796653Y566699D03*
X846850Y528899D03*
X843503Y550914D03*
X836810D03*
X819378D03*
X823199Y553100D03*
X828299Y550714D03*
X823199Y550500D03*
X828299Y553314D03*
X819378Y553564D03*
Y531100D03*
X836810Y530949D03*
X833464Y537049D03*
X846850Y547914D03*
X833464D03*
X840157D03*
X828275Y547900D03*
X843503Y553614D03*
X836810D03*
X846850Y536999D03*
X843503Y530949D03*
X823199Y547898D03*
Y536999D03*
X823225Y529150D03*
X828325Y536750D03*
X840157Y537049D03*
X828312Y528936D03*
X840157Y555957D03*
X843503Y572900D03*
X840157Y566699D03*
X833464Y555957D03*
Y566699D03*
X846850Y555957D03*
Y566699D03*
X823225Y569550D03*
X828299Y571949D03*
X823199Y572199D03*
X828299Y569340D03*
X843503Y588714D03*
X836810D03*
X819378D03*
X828299Y588514D03*
X823199Y588300D03*
X819378Y568900D03*
X823175Y555700D03*
X828299Y555914D03*
X828275Y585700D03*
X823225Y566950D03*
X823199Y585698D03*
Y574799D03*
X828312Y566736D03*
X840157Y585714D03*
X833464D03*
X828325Y574550D03*
X840157Y574849D03*
X833464D03*
X836810Y568749D03*
X846850Y585714D03*
Y574799D03*
X843503Y568749D03*
X812999Y534700D03*
X823225Y531750D03*
X816732Y528899D03*
X819378Y534700D03*
X828299Y534149D03*
X836810Y535100D03*
X840157Y528899D03*
X843503Y535100D03*
X791488Y569340D03*
X836810Y572900D03*
X819378Y572500D03*
X810039Y528899D03*
X823199Y534399D03*
X828299Y531540D03*
X833464Y528899D03*
X846850Y612599D03*
X840157Y612649D03*
X833464D03*
X823199Y612599D03*
X810039D03*
X803346Y612649D03*
X796653D03*
X816582D03*
X812999Y610300D03*
X810039Y593757D03*
Y604499D03*
X806692Y610700D03*
X803346Y593757D03*
Y604499D03*
X799999Y610700D03*
X796653Y593757D03*
Y604499D03*
X816732Y593757D03*
Y604499D03*
X791488Y609749D03*
Y591114D03*
X791514Y612350D03*
X806692Y606549D03*
X812999D03*
X799999D03*
X791501Y604536D03*
X806692Y591414D03*
X813035Y591314D03*
X799999Y591414D03*
X791488Y593714D03*
X840157Y593757D03*
X843503Y610700D03*
X840157Y604499D03*
X833464Y593757D03*
X836810Y610700D03*
X833464Y604499D03*
X846850Y593757D03*
X819378Y610300D03*
X823199Y590900D03*
X828299Y609749D03*
X823199Y609999D03*
X828299Y591114D03*
Y607140D03*
X819378Y606700D03*
Y591364D03*
X823225Y604750D03*
X823175Y593500D03*
X843503Y591414D03*
X828312Y604536D03*
X843503Y606549D03*
X836810D03*
X828325Y612350D03*
X836810Y591414D03*
X828299Y593714D03*
X791488Y607140D03*
X846850Y604499D03*
X823225Y607350D03*
X870275Y9114D03*
X865086Y9100D03*
X860010Y9098D03*
X876968Y9114D03*
Y-1751D03*
X873621Y-7851D03*
X865123Y-9864D03*
X860036Y-9650D03*
X849810Y-7851D03*
X856189Y-7700D03*
X860010Y-1801D03*
X865136Y-2050D03*
X853543Y-1751D03*
X870275D03*
X853393Y9114D03*
X856189Y33700D03*
X853543Y27899D03*
X876968D03*
X849810Y33700D03*
X870275Y27899D03*
X860036Y30750D03*
X865110Y30540D03*
X860010Y33399D03*
X865110Y33149D03*
X860036Y28150D03*
X859986Y16900D03*
X865110Y17114D03*
X856189Y14814D03*
X849846Y14714D03*
X873621Y14814D03*
Y29949D03*
X865123Y27936D03*
X849810Y29949D03*
X856189Y30100D03*
X896847Y-9650D03*
X910432Y-7851D03*
X883661Y-1801D03*
X880314Y-7851D03*
X886621D03*
X907086Y-1751D03*
X890354D03*
X896821Y-1801D03*
X901947Y-2050D03*
X901934Y-9864D03*
X893000Y-7700D03*
X883661Y9114D03*
X907086D03*
X896821Y9098D03*
X901897Y9100D03*
X890204Y9114D03*
X886621Y33700D03*
X883661Y27899D03*
X907086D03*
X896847Y30750D03*
X901921Y33149D03*
X896821Y33399D03*
X901921Y30540D03*
X910432Y29949D03*
X896797Y16900D03*
X893000Y14814D03*
X901921Y17114D03*
X901934Y27936D03*
X893000Y30100D03*
X880314Y14814D03*
X886657Y14714D03*
X886621Y29949D03*
X880314D03*
X896847Y28150D03*
X910432Y14814D03*
X893000Y33700D03*
X890354Y27899D03*
X870275Y-9901D03*
X876968D03*
X880314Y-3700D03*
X907086Y-9901D03*
X873621Y12114D03*
X880314D03*
X876968Y17157D03*
X910432Y12114D03*
X901921Y11914D03*
Y-4651D03*
X865110Y11914D03*
Y-4651D03*
X896821Y-4401D03*
Y11700D03*
X860010D03*
Y-4401D03*
X901921Y-7260D03*
Y14514D03*
X865110Y-7260D03*
Y14514D03*
X896847Y-7050D03*
X896821Y14300D03*
X860036Y-7050D03*
X860010Y14300D03*
X907086Y17157D03*
X886707Y12114D03*
X883661Y-9901D03*
Y17157D03*
X886621Y-4100D03*
X893000Y12114D03*
X890354Y-9901D03*
X893000Y-4100D03*
X890354Y17157D03*
X873621Y-3700D03*
X870275Y17157D03*
X849896Y12114D03*
X849810Y-4100D03*
X853543Y-9901D03*
X856189Y12114D03*
Y-4100D03*
X853543Y17157D03*
X910432Y-3700D03*
X870275Y65699D03*
X860036Y68550D03*
X865110Y68340D03*
X853543Y54957D03*
X856189Y49914D03*
X876968Y54957D03*
X849896Y49914D03*
X873621Y34100D03*
X870275Y54957D03*
X873621Y49914D03*
X860010Y52100D03*
X865110Y52314D03*
X860010Y49500D03*
X865110Y49714D03*
X859986Y54700D03*
X870275Y36049D03*
X865136Y35750D03*
X865086Y46900D03*
X876968Y46914D03*
Y36049D03*
X873621Y67749D03*
Y52614D03*
X860010Y46898D03*
X860036Y65950D03*
X865123Y65736D03*
X849810Y67749D03*
X856189Y67900D03*
X853393Y46914D03*
X870275D03*
X865110Y54914D03*
X860010Y35999D03*
X856189Y52614D03*
X853543Y36049D03*
X849846Y52514D03*
X853543Y65699D03*
X876968D03*
Y84714D03*
Y73849D03*
X873621Y90414D03*
X870275Y73849D03*
X853543D03*
X860010Y73799D03*
X849846Y90314D03*
X856189Y90414D03*
X865110Y92714D03*
X870275Y84714D03*
X865086Y84700D03*
X853393Y84714D03*
X860010Y84698D03*
X859986Y92500D03*
X865136Y73550D03*
X856189Y71500D03*
X853543Y92757D03*
X856189Y87714D03*
X876968Y92757D03*
X849810Y71500D03*
X849896Y87714D03*
X873621Y71900D03*
X870275Y92761D03*
X873621Y87714D03*
X860010Y89900D03*
X865110Y70949D03*
Y87514D03*
X860010Y71199D03*
Y87300D03*
X865110Y90114D03*
X883661Y54957D03*
X886707Y49914D03*
X910432Y34100D03*
X907086Y54957D03*
X910432Y49914D03*
X896821Y52100D03*
X901921Y49714D03*
X896821Y49500D03*
X901921Y52314D03*
X910432Y67749D03*
X893000Y67900D03*
X901934Y65736D03*
X896847Y65950D03*
X910432Y52614D03*
X890204Y46914D03*
X896821Y35999D03*
X901921Y54914D03*
X896797Y54700D03*
X883661Y35999D03*
X886621Y67749D03*
X880314D03*
X883661Y46914D03*
X880314Y52614D03*
X886657Y52514D03*
X901947Y35750D03*
X901897Y46900D03*
X896821Y46898D03*
X893000Y52614D03*
X890354Y36049D03*
X907086D03*
X883661Y73799D03*
X910432Y90414D03*
X907086Y84714D03*
X901897Y84700D03*
X880314Y71900D03*
Y87714D03*
X893000Y71500D03*
X890354Y92757D03*
X893000Y87714D03*
X886621Y71500D03*
X883661Y92757D03*
X886707Y87714D03*
X910432Y71900D03*
X907086Y92757D03*
X910432Y87714D03*
X896821Y89900D03*
X901921Y70949D03*
Y87514D03*
X896821Y71199D03*
Y87300D03*
X901921Y90114D03*
X907086Y46914D03*
X890354Y65699D03*
X883661D03*
X907086D03*
X896847Y68550D03*
X901921Y68340D03*
X880314Y34100D03*
Y49914D03*
X890354Y54957D03*
X893000Y49914D03*
X896821Y84698D03*
X893000Y90414D03*
X890204Y84714D03*
X896797Y92500D03*
X901921Y92714D03*
X890354Y73849D03*
X896821Y73799D03*
X901947Y73550D03*
X907086Y73849D03*
X883661Y84714D03*
X886657Y90314D03*
X880314Y90414D03*
X886657Y109884D03*
X907086Y104284D03*
X901934Y105051D03*
X896847Y105265D03*
X890354Y112327D03*
X893000Y106934D03*
X883661Y112327D03*
X886707Y107284D03*
X907086Y112327D03*
X910432Y107284D03*
X896821Y110514D03*
X901921Y107655D03*
X896847Y107865D03*
X901947Y110264D03*
X890204Y104284D03*
X893000Y109534D03*
X896821Y113114D03*
X901947Y112865D03*
X910432Y109984D03*
X883661Y104284D03*
X882008Y321100D03*
X851430Y367468D03*
X849896Y513114D03*
X870275Y518161D03*
X873621Y513114D03*
X860010Y515300D03*
X865110Y512914D03*
X860010Y512700D03*
X865110Y515514D03*
X873621Y515814D03*
X876968Y510114D03*
X870275D03*
X859986Y517900D03*
X865086Y510100D03*
X860010Y510098D03*
X865110Y518114D03*
X853393Y510114D03*
X856189Y515814D03*
X849846Y515714D03*
X853543Y518157D03*
X856189Y513114D03*
X876968Y518157D03*
X910432Y513114D03*
X896821Y515300D03*
X901921Y512914D03*
X896821Y512700D03*
X901921Y515514D03*
X907000Y495800D03*
X882900Y495900D03*
X893000Y493094D03*
X886500Y493400D03*
X910432Y491044D03*
X901921Y490514D03*
X896785D03*
X901921Y498514D03*
X896785D03*
X889100Y498500D03*
X901897Y510100D03*
X893000Y515814D03*
X890204Y510114D03*
X896821Y510098D03*
X901921Y518114D03*
X896797Y517900D03*
X880314Y515814D03*
X886657Y515714D03*
X883661Y510114D03*
X910432Y515814D03*
X907086Y510114D03*
X880314Y513114D03*
X890354Y518157D03*
X893000Y513114D03*
X883661Y518157D03*
X907086D03*
X886500Y490800D03*
X882900Y498500D03*
X896836Y493209D03*
X901921Y493214D03*
X910432Y493744D03*
X901921Y495814D03*
X896836Y495909D03*
X907086Y498487D03*
X893000Y495694D03*
X889200Y495900D03*
X886707Y513114D03*
X849810Y534700D03*
X873621Y535100D03*
X860036Y531750D03*
X865110Y534149D03*
Y531540D03*
X856189Y550914D03*
X849896D03*
X873621D03*
X860010Y553100D03*
X865110Y550714D03*
X860010Y550500D03*
X865110Y553314D03*
X860010Y536999D03*
X865123Y528936D03*
X873621Y530949D03*
Y553614D03*
X876968Y537049D03*
Y547914D03*
X860010Y547898D03*
X870275Y547914D03*
X853393D03*
X865086Y547900D03*
X856189Y553614D03*
X849846Y553514D03*
X870275Y537049D03*
X853543D03*
X856189Y531100D03*
X849810Y530949D03*
X865136Y536750D03*
X860036Y529150D03*
X856189Y534700D03*
X853543Y528899D03*
X876968D03*
X849810Y568749D03*
X865086Y585700D03*
X860010Y585698D03*
X865136Y574550D03*
X853543Y555957D03*
X856189Y572500D03*
X853543Y566699D03*
X876968Y555957D03*
Y566699D03*
X870275Y555961D03*
X873621Y572900D03*
X870275Y566699D03*
X860036Y569550D03*
X865110Y571949D03*
Y569340D03*
X856189Y588714D03*
X849896D03*
X873621D03*
X865110Y588514D03*
X860010Y588300D03*
X859986Y555700D03*
X865110Y555914D03*
X860010Y574799D03*
X853393Y585714D03*
X870275D03*
X873621Y568749D03*
X876968Y574849D03*
Y585714D03*
X860036Y566950D03*
X865123Y566736D03*
X870275Y574849D03*
X853543D03*
X856189Y568900D03*
X907086Y528899D03*
X896847Y531750D03*
X896821Y534399D03*
X901921Y531540D03*
X880314Y550914D03*
X890354Y537049D03*
X893000Y531100D03*
X896821Y536999D03*
X901934Y528936D03*
X901947Y536750D03*
X910432Y530949D03*
X907086Y537049D03*
X886621Y530949D03*
X883661Y536999D03*
X880314Y530949D03*
Y553614D03*
X886657Y553514D03*
X883661Y547914D03*
X893000Y553614D03*
X910432D03*
X890204Y547914D03*
X896821Y547898D03*
X901897Y547900D03*
X907086Y547914D03*
X880314Y535100D03*
X893000Y534700D03*
X890354Y528899D03*
X886621Y534700D03*
X880314Y568749D03*
X886621D03*
X883661Y574799D03*
Y585714D03*
X880314Y572900D03*
Y588714D03*
X893000D03*
X886707D03*
X896821Y588300D03*
X901921Y555914D03*
X896797Y555700D03*
X901934Y566736D03*
X896847Y566950D03*
X901897Y585700D03*
X890354Y574849D03*
X896821Y574799D03*
X893000Y568900D03*
X901947Y574550D03*
X896821Y585698D03*
X890204Y585714D03*
X910432Y568749D03*
X907086Y574849D03*
Y585714D03*
X901921Y588514D03*
X910432Y588714D03*
X886707Y550914D03*
X883661Y566699D03*
Y555957D03*
X901921Y553314D03*
X896821Y550500D03*
X901921Y550714D03*
X896821Y553100D03*
X910432Y550914D03*
X893000D03*
X901921Y571949D03*
X896847Y569550D03*
X907086Y566699D03*
X910432Y572900D03*
X907086Y555957D03*
X890354Y566699D03*
X893000Y572500D03*
X890354Y555957D03*
X883661Y528899D03*
X870275D03*
X860010Y534399D03*
X849810Y572500D03*
X860010Y572199D03*
X910432Y535100D03*
X901921Y534149D03*
X886621Y572500D03*
X901921Y569340D03*
X896821Y572199D03*
X890354Y612649D03*
X896821Y612599D03*
X883661D03*
X907086Y612649D03*
X870275D03*
X876968D03*
X860010Y612599D03*
X853543Y612649D03*
Y593757D03*
X856189Y610300D03*
X853543Y604499D03*
X876968Y593757D03*
Y604499D03*
X849810Y610300D03*
X870275Y593761D03*
X873621Y610700D03*
X870275Y604499D03*
X860010Y590900D03*
X860036Y607350D03*
X865110Y609749D03*
X860010Y609999D03*
X865110Y591114D03*
X859986Y593500D03*
X865110Y593714D03*
X856189Y591414D03*
X849846Y591314D03*
X860036Y604750D03*
X865123Y604536D03*
X856189Y606700D03*
X849810Y606549D03*
X865136Y612350D03*
X873621Y606549D03*
Y591414D03*
X886657Y591314D03*
X896847Y604750D03*
X901934Y604536D03*
X880314Y610700D03*
X893000Y610300D03*
X890354Y593757D03*
Y604499D03*
X886621Y610300D03*
X883661Y593757D03*
X896847Y607350D03*
X896821Y590900D03*
Y609999D03*
X901921Y591114D03*
X901947Y612350D03*
X896797Y593500D03*
X901921Y593714D03*
X893000Y591414D03*
X910432D03*
Y606549D03*
X893000Y606700D03*
X880314Y606549D03*
X886621D03*
X880314Y591414D03*
X901921Y609749D03*
X907086Y604499D03*
Y593757D03*
X910432Y610700D03*
X865110Y607140D03*
X883661Y604499D03*
X901921Y607140D03*
X923432Y-7851D03*
X929811Y-7700D03*
X933658Y-9650D03*
X917125Y-7851D03*
X913779Y-1751D03*
X933632Y-1801D03*
X927165Y-1751D03*
X920472Y-1801D03*
X927015Y9114D03*
X933632Y9098D03*
X913779Y9114D03*
X920472D03*
X933658Y-7050D03*
X933632Y-4401D03*
X929811Y-4100D03*
X927165Y-9901D03*
X923432Y-4100D03*
X920472Y-9901D03*
X933658Y30750D03*
X933632Y33399D03*
X929811Y33700D03*
X927165Y27899D03*
X923432Y33700D03*
X920472Y27899D03*
X933632Y14300D03*
Y11700D03*
X927165Y17157D03*
X929811Y12114D03*
X920472Y17157D03*
X923518Y12114D03*
X923432Y29949D03*
X917125D03*
Y14814D03*
X929811D03*
X933608Y16900D03*
X923468Y14714D03*
X933658Y28150D03*
X929811Y30100D03*
X913779Y27899D03*
X938745Y-9864D03*
X938758Y-2050D03*
X938708Y9100D03*
X947243Y-7851D03*
X950590Y-1751D03*
X957283Y-1843D03*
X953936Y-7851D03*
X943897Y-1751D03*
Y9114D03*
X950590D03*
X957765Y-7180D03*
X938732Y-7260D03*
Y-4651D03*
X953936Y-3700D03*
X950590Y-9901D03*
X947243Y-3700D03*
X943897Y-9901D03*
X960629Y-9786D03*
X963976Y-1843D03*
X970669Y-1743D03*
X967322Y-9786D03*
X963976Y9114D03*
X970669D03*
X967322Y-4536D03*
X938732Y33149D03*
Y30540D03*
X950590Y27899D03*
X943897D03*
X938732Y14514D03*
Y11914D03*
X950590Y17157D03*
X953936Y12114D03*
X943897Y17157D03*
X947243Y12114D03*
X967322Y28014D03*
X960629Y17057D03*
Y28014D03*
X967322Y17057D03*
X938745Y27936D03*
X938732Y17114D03*
X957283Y9300D03*
X953936Y14814D03*
Y29949D03*
X957600Y13200D03*
X957700Y32100D03*
X970800Y13200D03*
X970942Y32100D03*
X947243Y29949D03*
Y14814D03*
X913779Y-9901D03*
X917125Y-3700D03*
Y12114D03*
X913779Y17157D03*
X960629Y-4536D03*
X963976Y-7108D03*
X970669D03*
X933632Y52100D03*
Y49500D03*
X927165Y54957D03*
X929811Y49914D03*
X920472Y54957D03*
X923518Y49914D03*
X933658Y65950D03*
X923432Y67749D03*
X929811Y67900D03*
X917125Y67749D03*
X920472Y35999D03*
X917125Y52614D03*
X913779Y46914D03*
Y36049D03*
X927015Y73849D03*
X913779D03*
X920472Y73799D03*
X933632D03*
X913779Y84714D03*
X920472D03*
X933608Y92500D03*
X917125Y71900D03*
X913779Y92757D03*
X917125Y87714D03*
X933632Y89900D03*
Y71199D03*
Y87300D03*
X929811Y71500D03*
X927165Y92757D03*
X920472Y46914D03*
X933632Y35999D03*
X927165Y36049D03*
X927015Y46914D03*
X933608Y54700D03*
X933632Y46898D03*
X929811Y52614D03*
X913779Y65699D03*
X933658Y68550D03*
X927165Y65699D03*
X920472D03*
X913779Y54957D03*
X917125Y34100D03*
Y49914D03*
X929811Y87714D03*
X923432Y71500D03*
X920472Y92757D03*
X923518Y87714D03*
X933632Y84698D03*
X927015Y84714D03*
X923468Y90314D03*
X929811Y90414D03*
X917125D03*
X953936Y52614D03*
X957558Y50729D03*
X938732Y68340D03*
X950590Y65699D03*
X943897D03*
X938732Y49714D03*
Y52314D03*
X953936Y34100D03*
X950590Y54957D03*
X953936Y49914D03*
X947243Y34100D03*
X943897Y54957D03*
X947243Y49914D03*
X967322Y65814D03*
X960629D03*
X970669Y35957D03*
Y46914D03*
X967322Y54857D03*
X963976Y35957D03*
Y46914D03*
X960629Y54857D03*
X938758Y35750D03*
X938708Y46900D03*
X938732Y54914D03*
X938745Y65736D03*
X950590Y36049D03*
X953936Y67749D03*
X950590Y46914D03*
X970800Y50860D03*
X947243Y67749D03*
X943897Y36049D03*
Y46914D03*
X947243Y52614D03*
X957283Y35957D03*
X947243Y87714D03*
X963976Y73757D03*
X960629Y89964D03*
X963976Y87392D03*
X967322Y89964D03*
X970669Y87392D03*
Y73757D03*
X967322Y84714D03*
X938708Y84700D03*
X938732Y92714D03*
X938758Y73550D03*
X957600Y70400D03*
X970942Y69900D03*
X943897Y84714D03*
X947243Y90414D03*
X943897Y73849D03*
X950590D03*
X953886Y90414D03*
X950590Y84714D03*
X957774Y87394D03*
X957200Y73800D03*
X957283Y92657D03*
X938732Y70949D03*
Y87514D03*
Y90114D03*
X953936Y71900D03*
X950590Y92757D03*
X953936Y87714D03*
X947243Y71900D03*
X943897Y92757D03*
X960629Y84714D03*
X963976Y92657D03*
X970669Y92757D03*
X933658Y105265D03*
X913779Y112327D03*
X917125Y107284D03*
X933632Y110514D03*
X933658Y107865D03*
X927165Y112327D03*
X929811Y106934D03*
X920472Y112327D03*
X923518Y107284D03*
X929811Y109534D03*
X933632Y113114D03*
X923468Y109884D03*
X917125Y109984D03*
X920472Y104284D03*
X913779D03*
X927015D03*
X938732Y107655D03*
X938758Y110264D03*
X950590Y109700D03*
X953786Y107684D03*
X944497Y110927D03*
X947243Y105084D03*
X963245Y105725D03*
X938758Y112865D03*
X938745Y105051D03*
X947250Y107700D03*
X950600Y112300D03*
X953800Y105000D03*
X937747Y213009D03*
Y205210D03*
X917467Y209109D03*
X920847Y203260D03*
X927607D03*
Y207159D03*
X934367D03*
Y199360D03*
X930987Y201309D03*
X934367Y214960D03*
X930987Y213009D03*
X920847Y211060D03*
X927607Y214960D03*
Y211060D03*
X937747Y216909D03*
X924227D03*
Y213009D03*
X920847Y207159D03*
X927607Y218860D03*
X934367D03*
X930987Y205210D03*
X968166Y218860D03*
X951256Y194841D03*
X958026Y201309D03*
X967036Y193507D03*
X947887Y203260D03*
Y207159D03*
X944507Y213009D03*
Y201309D03*
X947887Y199360D03*
X941127D03*
Y207159D03*
X947887Y211060D03*
Y218860D03*
X941127D03*
Y214960D03*
X947887D03*
X954647D03*
X962526Y205210D03*
X961406Y214960D03*
Y211060D03*
Y218860D03*
X951267Y209109D03*
X958026Y213009D03*
X954647Y211060D03*
Y218860D03*
X941127Y203260D03*
Y211060D03*
X964786Y213009D03*
Y216909D03*
Y209109D03*
X937747Y240309D03*
X930987Y244209D03*
X934367Y226660D03*
X924227Y236409D03*
X920847Y238360D03*
X913787Y226660D03*
X913700Y222710D03*
X913787Y238360D03*
X924227Y232509D03*
X927607Y230559D03*
Y234460D03*
X930987Y232509D03*
X934367Y234460D03*
X924227Y228610D03*
X930987Y220809D03*
X924227Y224709D03*
X937747Y232509D03*
Y236409D03*
X924227Y240309D03*
X917467D03*
X930987D03*
X924227Y248109D03*
Y244209D03*
X917467D03*
X913787Y250060D03*
X934367Y246160D03*
X927607Y250060D03*
X924227Y220809D03*
X937747Y224709D03*
X934367Y230559D03*
X913787Y246160D03*
X920847D03*
X937747Y220809D03*
X930987Y224709D03*
Y236409D03*
X937747Y248109D03*
X927607Y242260D03*
X937747Y279310D03*
X917000Y276000D03*
X920847Y277360D03*
X924227Y279310D03*
X913787Y273460D03*
Y253960D03*
X927607D03*
X934367D03*
X937747Y252009D03*
X930987D03*
X924227D03*
X917467D03*
Y259809D03*
X924227D03*
X930987D03*
X920847Y265660D03*
X930987Y275409D03*
X937747D03*
Y271509D03*
Y255909D03*
X934367Y277360D03*
X930987Y271509D03*
X934367Y273460D03*
X927607Y269560D03*
X917467Y263709D03*
X913787Y265660D03*
X924227Y267609D03*
X934367Y265660D03*
X924227Y263709D03*
Y275409D03*
X927607Y277360D03*
X920847Y273460D03*
Y269560D03*
X924227Y255909D03*
X920847Y257860D03*
X913787Y261760D03*
X917467Y255909D03*
X930987Y267609D03*
X937747Y263709D03*
X927607Y257860D03*
X934367D03*
X927607Y265660D03*
X916967Y279310D03*
X930987D03*
X951267Y248109D03*
X958026Y244209D03*
X968166Y242260D03*
X944507Y228610D03*
Y224709D03*
Y244209D03*
Y248109D03*
X941127Y242260D03*
Y250060D03*
Y246160D03*
X947887D03*
X941127Y222760D03*
X947887Y226660D03*
Y234460D03*
X941127Y238360D03*
Y234460D03*
Y230559D03*
Y226660D03*
X971546Y248109D03*
X968166Y246160D03*
X958026Y220809D03*
X944507D03*
X951267Y224709D03*
Y240309D03*
X958026D03*
X964786D03*
X954647Y246160D03*
Y250060D03*
X958026Y228610D03*
Y236409D03*
X961406Y238360D03*
X951267Y228610D03*
X954647Y226660D03*
X958026Y224709D03*
Y232509D03*
X954647Y230559D03*
X961406Y222760D03*
X968166Y226660D03*
X971546Y236409D03*
X968166Y238360D03*
X971546Y220809D03*
X964786Y232509D03*
Y220809D03*
X944507Y279310D03*
X947887Y253960D03*
X941127D03*
X958026Y252009D03*
X968166Y277360D03*
X951267Y275409D03*
X961406Y277360D03*
X958026Y263709D03*
X968166Y269560D03*
X961406Y261760D03*
X958026Y255909D03*
X951267Y259809D03*
X958026D03*
X954647Y277360D03*
Y265660D03*
X951267Y267609D03*
X954647Y273460D03*
X958026Y275409D03*
X954647Y269560D03*
X961406D03*
X971546Y275409D03*
Y263709D03*
X941127Y277360D03*
Y265660D03*
X944507Y275409D03*
Y263709D03*
X941127Y269560D03*
Y257860D03*
Y261760D03*
X947887Y277360D03*
Y265660D03*
X971546Y259809D03*
Y255909D03*
X964786Y279310D03*
Y267609D03*
Y271509D03*
X961406Y273460D03*
X971546Y267609D03*
X958026D03*
Y279310D03*
X951267D03*
X947887Y230559D03*
X971546Y224709D03*
X944507Y236409D03*
X954647Y242260D03*
X947887Y261760D03*
X951267Y236409D03*
X947887Y238360D03*
X951267Y255909D03*
X971546Y232509D03*
X947887Y242260D03*
X944507Y255909D03*
X964786Y224709D03*
X961406Y230559D03*
X937747Y287109D03*
X920500Y304660D03*
Y300760D03*
X930987Y302709D03*
X924227D03*
X920500Y311960D03*
X927607Y304660D03*
X924227Y306609D03*
X930987D03*
Y310509D03*
X934367Y304660D03*
X924227Y310509D03*
X920500Y308560D03*
Y289060D03*
X934367Y296860D03*
X930987Y294909D03*
X920500Y296860D03*
Y292959D03*
X927607Y296860D03*
X924227Y298809D03*
X930987D03*
X924227Y283209D03*
X927607Y281260D03*
X920500Y285500D03*
X924227Y287109D03*
X920847Y281260D03*
X930987Y287109D03*
X934367Y289060D03*
Y285160D03*
Y300760D03*
X927607D03*
Y308560D03*
X934367D03*
X927607Y285160D03*
Y292959D03*
X934367D03*
Y281260D03*
X930987Y283209D03*
X924227Y291009D03*
X930987D03*
X927607Y289060D03*
X937747Y302709D03*
Y306609D03*
Y310509D03*
Y283209D03*
Y291009D03*
Y294909D03*
Y298809D03*
X920847Y335860D03*
X913787Y331960D03*
X917467Y337809D03*
X937747Y333909D03*
X927607Y339760D03*
X934367Y328060D03*
Y339760D03*
X927607Y331960D03*
X930987Y333909D03*
X937747Y337809D03*
Y314409D03*
X924227D03*
X930987D03*
X934367Y312460D03*
X927607D03*
X920847Y324160D03*
X924227Y318309D03*
X920547Y316160D03*
X917167Y318309D03*
Y322209D03*
X917467Y326110D03*
X920847Y320260D03*
X937747Y318309D03*
Y341709D03*
Y326110D03*
X917467Y333909D03*
Y341709D03*
X913787Y339760D03*
X924227Y333909D03*
Y337809D03*
Y341709D03*
X913787Y328060D03*
X924227Y330009D03*
X920847Y328060D03*
X917467Y330009D03*
X930987Y326110D03*
X934367Y331960D03*
X927607Y328060D03*
X934367Y324160D03*
X924227Y322209D03*
X927607Y320260D03*
X930987Y318309D03*
X934367Y316360D03*
X927607D03*
X930987Y337809D03*
X924227Y326110D03*
X971546Y294909D03*
X944507Y283209D03*
X961406Y292959D03*
Y285160D03*
X954647Y292959D03*
Y285160D03*
X968166Y292959D03*
Y300760D03*
X971546Y310509D03*
X964786D03*
X954647Y308560D03*
X961406D03*
X954647Y300760D03*
X961406D03*
X964786Y283209D03*
X971546D03*
X947887Y308560D03*
X941127D03*
Y300760D03*
X947887D03*
X941127Y285160D03*
Y292959D03*
X947887D03*
Y285160D03*
X968166Y281260D03*
X964786Y291009D03*
X954647Y281260D03*
X958026Y283209D03*
X951267Y287109D03*
X958026D03*
X951267Y283209D03*
X961406Y281260D03*
Y296860D03*
X964786Y298809D03*
Y302709D03*
X971546D03*
X961406Y304660D03*
X958026Y302709D03*
X951267D03*
X968166Y308560D03*
X964786Y306609D03*
X968166Y304660D03*
X971546Y306609D03*
X951267Y310509D03*
X954647Y304660D03*
X958026Y306609D03*
Y310509D03*
X951267Y306609D03*
X944507Y302709D03*
Y306609D03*
Y310509D03*
X941127Y304660D03*
X947887D03*
X944507Y294909D03*
Y287109D03*
X971546Y298809D03*
X968166Y285160D03*
X964786Y287109D03*
X944507Y291009D03*
X941127Y281260D03*
Y289060D03*
Y296860D03*
X944507Y298809D03*
X947887Y289060D03*
Y296860D03*
Y281260D03*
X968166Y296860D03*
X964786Y294909D03*
X971546Y291009D03*
Y287109D03*
X968166Y289060D03*
X961406D03*
X958026Y298809D03*
X951267D03*
Y291009D03*
X958026D03*
X954647Y289060D03*
Y296860D03*
X958026Y294909D03*
X951267D03*
X958026Y333909D03*
Y337809D03*
Y341709D03*
Y318309D03*
X951267D03*
X954647Y316360D03*
X961406D03*
Y324160D03*
X971546Y337809D03*
X964786Y330009D03*
X971546D03*
X951267D03*
X958026D03*
X954647Y339760D03*
X951267Y333909D03*
X944507Y337809D03*
X968166Y312460D03*
X964786Y314409D03*
X951267Y337809D03*
X954647Y331960D03*
Y328060D03*
X971546Y322209D03*
X968166Y320260D03*
X964786Y322209D03*
X968166Y335860D03*
X947887Y339760D03*
X944507Y314409D03*
X951267D03*
X958026D03*
X961406Y312460D03*
X954647D03*
X941127D03*
X947887D03*
X971546Y314409D03*
Y318309D03*
X964786D03*
X951267Y322209D03*
X954647Y324160D03*
X961406Y320260D03*
X954647D03*
X958026Y322209D03*
X951267Y326110D03*
X968166Y316360D03*
X958026Y326110D03*
X947887Y316360D03*
X941127D03*
X944507Y322209D03*
Y318309D03*
X947887Y331960D03*
Y328060D03*
X941127Y331960D03*
Y328060D03*
Y339760D03*
Y335860D03*
X944507Y333909D03*
X968166Y328060D03*
Y324160D03*
X964786Y333909D03*
X961406Y328060D03*
X971546Y333909D03*
X930987Y369010D03*
X937747D03*
X913787Y347560D03*
X920847Y343660D03*
X934367Y359260D03*
X930987Y361209D03*
X937747Y349509D03*
X927607Y355360D03*
X937747Y353409D03*
X930987Y349509D03*
X937747Y357309D03*
X930987Y353409D03*
X937747Y365109D03*
Y345609D03*
Y361209D03*
X924227Y365109D03*
X930987D03*
X927607Y367060D03*
X934367Y370959D03*
Y363160D03*
X927607D03*
X924227Y369010D03*
X913787Y343660D03*
X934367D03*
X927607D03*
Y347560D03*
X934367Y351460D03*
X930987Y357309D03*
Y345609D03*
X917467Y353409D03*
Y349509D03*
X913787Y355360D03*
X924227Y349509D03*
Y345609D03*
Y353409D03*
Y361209D03*
Y357309D03*
X920847Y355360D03*
X917167Y361209D03*
Y369010D03*
X920847Y347560D03*
X934367Y382660D03*
X930987Y384609D03*
Y376809D03*
X934367Y390460D03*
X927607Y386560D03*
Y390460D03*
X930987Y396309D03*
X934367Y398260D03*
X927607Y394359D03*
X917467Y388509D03*
X924227Y392410D03*
X920847Y390460D03*
X930987Y380709D03*
X927607Y374860D03*
X934367D03*
X937747Y376809D03*
X930987Y372909D03*
X934367Y394359D03*
X930987Y388509D03*
X937747D03*
Y384609D03*
Y392410D03*
X924227Y400209D03*
X920847Y394359D03*
Y398260D03*
X927607D03*
X924227Y372909D03*
X937747Y400209D03*
X917100Y380709D03*
X937747D03*
X924227D03*
X920847Y382660D03*
X924227Y376809D03*
X927607Y382660D03*
X968166Y370959D03*
X958026Y361209D03*
X954647Y347560D03*
X961406Y359260D03*
X958026Y357309D03*
X951267D03*
X941127Y355360D03*
Y347560D03*
Y351460D03*
X958026Y345609D03*
X951267Y349509D03*
X954647Y351460D03*
X958026Y353409D03*
X968166Y355360D03*
Y351460D03*
X971546Y353409D03*
X947887Y367060D03*
X954647Y355360D03*
X944507Y361209D03*
X968166Y363160D03*
X961406D03*
X971546Y369010D03*
X944507Y345609D03*
X951267D03*
X947887Y355360D03*
X951267Y361209D03*
X968166Y367060D03*
X964786Y357309D03*
X971546Y361209D03*
X968166Y359260D03*
X958026Y365109D03*
X964786D03*
X954647Y370959D03*
Y367060D03*
X958026Y369010D03*
X951267D03*
X961406Y370959D03*
X954647Y363160D03*
X947887Y359260D03*
X964786Y369010D03*
X954647Y343660D03*
X971546Y349509D03*
X947887Y363160D03*
X941127D03*
X947887Y370959D03*
X941127D03*
Y367060D03*
X944507Y369010D03*
X947887Y343660D03*
X941127Y359260D03*
X944507Y349509D03*
Y353409D03*
X941127Y343660D03*
X947887Y351460D03*
X964786Y349509D03*
Y353409D03*
X961406Y355360D03*
Y347560D03*
Y351460D03*
X958026Y380709D03*
X954647Y374860D03*
X951267Y376809D03*
Y384609D03*
Y380709D03*
X944507Y388509D03*
X941127Y394359D03*
X968166Y374860D03*
X958026Y372909D03*
X941127Y374860D03*
X961406D03*
X944507Y372909D03*
X941127Y382660D03*
Y378760D03*
X947887D03*
X944507Y384609D03*
X947887Y390460D03*
Y386560D03*
X941127Y390460D03*
X947887Y398260D03*
X941127D03*
X944507Y396309D03*
X947887Y394359D03*
X964786Y376809D03*
X971546D03*
X968166Y378760D03*
Y386560D03*
X964786Y392410D03*
X968166Y390460D03*
Y394359D03*
X964786Y388509D03*
X961406Y378760D03*
X954647D03*
X958026Y384609D03*
X961406Y382660D03*
X951267Y388509D03*
X958026D03*
X954647Y394359D03*
X961406Y386560D03*
X952216Y402421D03*
X970416Y401941D03*
X971546Y380709D03*
X968166Y382660D03*
X947887Y374860D03*
X944507Y380709D03*
X933632Y515300D03*
Y512700D03*
X927165Y518157D03*
X929811Y513114D03*
X920472Y518157D03*
X923518Y513114D03*
X920700Y495944D03*
X913800Y495800D03*
X927165Y495944D03*
X929811Y515814D03*
X933632Y510098D03*
X923600Y491144D03*
X917192Y491219D03*
X933632Y490644D03*
X929811D03*
X933632Y498644D03*
X933608Y517900D03*
X913779Y510114D03*
X917125Y515814D03*
X923468Y515714D03*
X920472Y510114D03*
X927015D03*
X913779Y518157D03*
X917125Y513114D03*
X938732Y490644D03*
X950700Y490700D03*
X943897Y490444D03*
X970669Y512792D03*
X967322Y515364D03*
X963976Y512792D03*
X960629Y515364D03*
X967322Y510114D03*
X938708Y510100D03*
X938732Y518114D03*
Y498644D03*
X954000Y497300D03*
X953886Y515814D03*
X950590Y510114D03*
X943897D03*
X947243Y515814D03*
X947443Y497644D03*
X957774Y512794D03*
X957283Y518057D03*
X938732Y512914D03*
Y515514D03*
X943897Y518157D03*
X947243Y513114D03*
X961309Y499136D03*
X947443Y494944D03*
X944000Y493100D03*
X923600Y493744D03*
X929811Y493244D03*
X933647Y493344D03*
X938732D03*
X917192Y493919D03*
X920700Y498644D03*
X927165D03*
X938732Y495944D03*
X933647D03*
X913779Y498487D03*
X954000Y494700D03*
X950700Y493300D03*
X960629Y510114D03*
X963976Y518057D03*
X970669Y518157D03*
X953936Y513114D03*
X950590Y518157D03*
X933658Y531750D03*
X929811Y534700D03*
X927165Y528899D03*
X923432Y534700D03*
X920472Y528899D03*
X933632Y536999D03*
X929811Y531100D03*
X933658Y529150D03*
X913779Y537049D03*
X917125Y530949D03*
X927015Y537049D03*
X923432Y530949D03*
X920472Y536999D03*
X923468Y553514D03*
X917125Y553614D03*
X913779Y547914D03*
X927015D03*
X920472D03*
X933632Y547898D03*
X929811Y553614D03*
X917125Y535100D03*
X913779Y528899D03*
X933608Y555700D03*
X933632Y585698D03*
X933658Y566950D03*
X929811Y568900D03*
X933632Y574799D03*
X920472D03*
X927015Y585714D03*
X920472D03*
X913779Y574849D03*
X917125Y568749D03*
X913779Y585714D03*
X923432Y568749D03*
X927015Y574849D03*
X960629Y529014D03*
X963976Y536957D03*
X970669D03*
X967322Y529014D03*
X963976Y547914D03*
X970669D03*
X938745Y528936D03*
X938758Y536750D03*
X938708Y547900D03*
X957600Y533100D03*
X970942D03*
X957701Y552000D03*
X970731D03*
X950590Y537049D03*
X957283Y536957D03*
X953936Y530949D03*
X957283Y548200D03*
X953886Y553614D03*
X950590Y547914D03*
X947243Y530949D03*
X943897Y537049D03*
Y547914D03*
X947243Y553614D03*
X938732Y534149D03*
Y531540D03*
X947243Y535100D03*
X953936Y588714D03*
X967322Y555857D03*
X960629D03*
X970669Y585714D03*
Y574757D03*
X960629Y566814D03*
X963976Y585714D03*
Y574757D03*
X967322Y566814D03*
X938732Y555914D03*
X938745Y566736D03*
X938758Y574550D03*
X938708Y585700D03*
X957600Y570900D03*
X970942D03*
X950590Y574849D03*
Y585714D03*
X957283Y574757D03*
X957456Y588334D03*
X953936Y568749D03*
X943897Y574849D03*
X947243Y568749D03*
X943897Y585714D03*
X938732Y588514D03*
X933632Y588300D03*
X929811Y588714D03*
X923518D03*
X947243D03*
Y550914D03*
X923518D03*
X929811D03*
X938732Y553314D03*
X933632Y550500D03*
X938732Y550714D03*
X933632Y553100D03*
X917125Y550914D03*
X943897Y566699D03*
X947243Y572900D03*
X943897Y555957D03*
X920472Y566699D03*
X923432Y572500D03*
X920472Y555957D03*
X927165Y566699D03*
X929811Y572500D03*
X927165Y555957D03*
X938732Y571949D03*
X933658Y569550D03*
X913779Y555957D03*
X953936Y550914D03*
Y572900D03*
X950590Y555957D03*
X917125Y588714D03*
X950590Y528899D03*
X953936Y535100D03*
X933632Y534399D03*
X943897Y528899D03*
X938732Y569340D03*
X933632Y572199D03*
X913779Y566699D03*
X917125Y572900D03*
X950590Y566699D03*
X933632Y612599D03*
X923432Y606549D03*
X917125D03*
X933658Y604750D03*
X917125Y610700D03*
X913779Y593757D03*
X929811Y610300D03*
X927165Y593757D03*
X923468Y591314D03*
X917125Y591414D03*
X933608Y593500D03*
X929811Y591414D03*
X927015Y612449D03*
X920472Y612399D03*
X913779Y612449D03*
X929811Y606700D03*
X950590Y604499D03*
X967322Y593657D03*
X963976Y612457D03*
X970669D03*
X960629Y604614D03*
X967322D03*
X960629Y593657D03*
X967322Y609864D03*
X938758Y612350D03*
X938745Y604536D03*
X938732Y593714D03*
X957500Y591000D03*
X970731Y589800D03*
X953936Y606549D03*
X957283Y611600D03*
X950590Y612249D03*
X953886Y591414D03*
X947243Y606549D03*
X943897Y612249D03*
X947243Y591414D03*
X957765Y607220D03*
X938732Y609749D03*
Y607140D03*
Y591114D03*
X953936Y610700D03*
X950590Y593757D03*
X933632Y590900D03*
Y609999D03*
X927165Y604499D03*
X923432Y610300D03*
X920472Y593757D03*
Y604499D03*
X947243Y610700D03*
X943897Y593757D03*
Y604499D03*
X963976Y607292D03*
X970669D03*
X913779Y604499D03*
X933658Y607350D03*
X960629Y609864D03*
X1025670Y6640D03*
X1023740Y18150D03*
X980708Y-4536D03*
X987401Y-9901D03*
X997441Y-7108D03*
X990748Y-1743D03*
X977362Y-7108D03*
X980708Y9114D03*
X990748Y9122D03*
X977362Y28014D03*
X987401D03*
Y17057D03*
X977362D03*
X997441Y28022D03*
Y17057D03*
X983900Y13200D03*
Y32100D03*
X1028400Y6500D03*
X1030407Y-8938D03*
X1000787Y-4536D03*
Y9122D03*
X1017519Y-1858D03*
Y-9786D03*
X1007480Y-1858D03*
X1007280Y9114D03*
X1017519D03*
X1007480Y-9786D03*
X1020866Y-1858D03*
X1027202Y-11005D03*
X1028639Y-6615D03*
X1008200Y30736D03*
X1014173Y28014D03*
X1010826D03*
X1007480Y17014D03*
Y28014D03*
X1017519D03*
Y17042D03*
X1025291Y20734D03*
X1007100Y11714D03*
X1008227Y33342D03*
X1030400Y26150D03*
X1030450Y23150D03*
X1007100Y14314D03*
X1026700Y1700D03*
X984055Y-7108D03*
X990748D03*
X987401Y-4536D03*
X994094Y-9786D03*
Y-4536D03*
X997441Y-1743D03*
X1000787Y-9901D03*
X1004133Y-1742D03*
X1004134Y-7108D03*
X980708Y-9786D03*
X984055Y-1743D03*
X1010826Y9114D03*
Y-1858D03*
X1012270Y17014D03*
X1010826Y-9786D03*
X1014173Y9114D03*
Y-1858D03*
X1014919Y17042D03*
X1014173Y-9786D03*
X974015Y-4536D03*
Y-9901D03*
X977362Y-1743D03*
X1020650Y46900D03*
X987401Y65814D03*
X977362D03*
X987401Y54857D03*
X977362D03*
X990748Y46922D03*
Y35957D03*
X980708D03*
Y46914D03*
X997441Y65822D03*
Y54857D03*
X983900Y51000D03*
X997441Y92757D03*
X990748Y73757D03*
Y87392D03*
X977362Y92757D03*
X987401Y89964D03*
X980708Y84714D03*
Y73757D03*
X983900Y69900D03*
X1007370Y52333D03*
Y49659D03*
X1014173Y54842D03*
Y35942D03*
X1013873Y46914D03*
X1010826Y54842D03*
Y35942D03*
X1011126Y46914D03*
X1000787Y35957D03*
Y46922D03*
X1017519Y54842D03*
X1007480Y46914D03*
X1008226Y54842D03*
X1008217Y35942D03*
X1007480Y65736D03*
X1016600Y65950D03*
X1017519Y35942D03*
Y46914D03*
X1030300Y63200D03*
X1014350Y73000D03*
X1017919Y92500D03*
X1017519Y87500D03*
X1000787Y84599D03*
Y73757D03*
X1007480Y87500D03*
X1007573Y92500D03*
X1008099Y73479D03*
X1017350Y73450D03*
X1024945Y86377D03*
Y83877D03*
X1007380Y68335D03*
X1030400Y56500D03*
X1031600Y42900D03*
X1007380Y70935D03*
X1023900Y74100D03*
Y77200D03*
X984055Y92757D03*
X990748D03*
X987401Y84599D03*
X994094Y89964D03*
Y84714D03*
X997441Y87392D03*
X1000787Y89964D03*
X1004023Y87392D03*
Y92757D03*
X980708Y89964D03*
X984055Y87392D03*
X974015Y84599D03*
Y89964D03*
X977362Y87392D03*
X1012043Y87500D03*
X1012400Y92500D03*
X1014842Y87500D03*
X1015215Y92500D03*
X976200Y105600D03*
X974100Y103500D03*
X976700Y103021D03*
X983936Y199108D03*
X973808Y201308D03*
X998586Y209109D03*
Y216909D03*
X995206Y203260D03*
X988446Y218860D03*
X995206Y214960D03*
X981686Y218860D03*
X974926Y211060D03*
X985066Y216909D03*
X988446Y211058D03*
X979426Y214958D03*
X1012105Y216909D03*
X1008725Y211060D03*
X1001965Y214960D03*
X1027875Y193507D03*
X1032385Y201309D03*
X1015485Y203260D03*
Y214960D03*
X1022245D03*
X1012105Y205210D03*
X1025625Y205211D03*
X1029005Y214960D03*
X1007595Y193507D03*
X1005345Y205210D03*
X1008725Y214960D03*
X1005345Y209109D03*
X1001965Y211060D03*
X1025625Y209109D03*
X1012105D03*
X1032385D03*
X998586Y205210D03*
X991826D03*
X1022245Y211060D03*
X1018865Y216909D03*
X1032385D03*
X995206Y238360D03*
X988446Y234460D03*
X998586Y248109D03*
Y220809D03*
X985066Y248109D03*
X981686Y250060D03*
X974926D03*
X988446Y246160D03*
Y250060D03*
Y230560D03*
X978306Y248109D03*
X974926Y238360D03*
X985066Y244209D03*
X981686Y238360D03*
X995206Y230559D03*
X981686Y242260D03*
X974926D03*
X988446D03*
X998586Y244209D03*
Y232509D03*
X991826Y244209D03*
Y232509D03*
X995206Y226660D03*
X991826Y248109D03*
X988446Y238360D03*
X985066Y236409D03*
X981686Y234460D03*
X974926Y226660D03*
X991826Y220809D03*
X974926Y230559D03*
Y234460D03*
Y222760D03*
X985066Y224709D03*
X978306Y232509D03*
Y220809D03*
X974926Y253960D03*
X988446D03*
X978306Y252009D03*
X985066D03*
X974926Y265660D03*
X991826Y259809D03*
X985066D03*
X981686Y269560D03*
X995206D03*
X985066Y267609D03*
X991826Y263709D03*
X988446Y265660D03*
X998586Y263709D03*
X991826Y271509D03*
X995206Y273460D03*
X991826Y279310D03*
Y275409D03*
X974926Y269560D03*
X978306Y267609D03*
Y259809D03*
X991826Y255909D03*
X995206Y265660D03*
X991826Y252009D03*
Y267609D03*
X974926Y273460D03*
X995206Y277360D03*
X998586Y267609D03*
Y271509D03*
Y275409D03*
Y279310D03*
X1029005Y238360D03*
X1015485Y222760D03*
X1008725D03*
X1032385Y232509D03*
X1018865Y244209D03*
X1012105D03*
X1018865Y232509D03*
X1015485Y226660D03*
X1022245D03*
X1012105Y232509D03*
X1025625D03*
X1029005Y226660D03*
X1005345Y244209D03*
X1008725Y226660D03*
X1005345Y232509D03*
X1001965Y226660D03*
X1005345Y248109D03*
X1008725Y238360D03*
X1001965D03*
X1005345Y220809D03*
X1029005Y250060D03*
X1032385Y248109D03*
X1025625D03*
X1022245Y250060D03*
X1025625Y220809D03*
X1012105D03*
X1015485Y238360D03*
X1022245D03*
X1018865Y220809D03*
X1032385D03*
X1001965Y261760D03*
X1012105Y255909D03*
X1022245Y253960D03*
X1025625Y252009D03*
X1017735Y264300D03*
X1014355Y266300D03*
X1021115Y262300D03*
X1024495Y260300D03*
X1027875Y258400D03*
X1031255Y256400D03*
X1005345Y263709D03*
X1001965Y265660D03*
X1009256Y269777D03*
X1008725Y261760D03*
X1006665Y277360D03*
X1006700Y270700D03*
X1006665Y273460D03*
X1011100Y268100D03*
X1015485Y257860D03*
X1018865Y255909D03*
X1012105Y259809D03*
X1015485Y253960D03*
X1018865Y252009D03*
X1005345Y259809D03*
X1008725Y257860D03*
X988446Y261760D03*
X1012105Y228610D03*
X1015485Y234460D03*
X1001965D03*
X998586Y240309D03*
X1001965Y222760D03*
X1025625Y228610D03*
X1005345Y240309D03*
Y228610D03*
X1012105Y240309D03*
X1029005Y234460D03*
X1025625Y240309D03*
X995206Y246160D03*
X1018865Y240309D03*
X981686Y261760D03*
X985066Y255909D03*
X978306D03*
X995206Y296860D03*
X985066Y294909D03*
X981686Y281260D03*
Y292959D03*
Y300760D03*
X988446D03*
X978306Y310509D03*
X991826D03*
X985066D03*
X974926Y300760D03*
X988446Y292959D03*
X991826Y283209D03*
X988446Y281260D03*
X985066Y283209D03*
X978306D03*
X974926Y292959D03*
Y281260D03*
X985066Y287109D03*
X988446Y285160D03*
X991826Y287109D03*
X995206Y281260D03*
X978306Y298809D03*
Y287109D03*
X981686Y285160D03*
X978306Y294909D03*
X981686Y296860D03*
Y289060D03*
X978306Y291009D03*
X998586Y302709D03*
Y306609D03*
Y310509D03*
Y287109D03*
Y294909D03*
Y291009D03*
Y298809D03*
Y283209D03*
X985066Y302709D03*
X978306D03*
X988446Y304660D03*
Y308560D03*
X985066Y306609D03*
X995206Y304660D03*
Y308560D03*
X991826Y306609D03*
X978306D03*
X981686Y308560D03*
Y304660D03*
X974926D03*
Y308560D03*
X995206Y300760D03*
X991826Y302709D03*
X974926Y285160D03*
Y296860D03*
Y289060D03*
X995206Y292959D03*
X988446Y296860D03*
X991826Y294909D03*
X995206Y289060D03*
X988446D03*
X991826Y291009D03*
X985066D03*
X995206Y285160D03*
X985066Y298809D03*
X991826D03*
Y333909D03*
X995206Y335860D03*
Y339760D03*
Y328060D03*
X991826Y326110D03*
X981686Y339760D03*
X978306Y333909D03*
Y330009D03*
Y326110D03*
X981686Y331960D03*
X985066Y330009D03*
X974926Y324160D03*
X988446Y339760D03*
X981686Y335860D03*
X978306Y341709D03*
X974926Y312460D03*
X981686D03*
X988446D03*
X991826Y314409D03*
Y330009D03*
X995206Y331960D03*
X988446D03*
X995206Y324160D03*
X988446Y316360D03*
X991826Y318309D03*
X995206Y320260D03*
X991826Y322209D03*
X998586Y333909D03*
X985066Y337809D03*
Y341709D03*
X974926Y328060D03*
X998586Y314409D03*
X995206Y312460D03*
X998586Y318309D03*
Y322209D03*
Y326110D03*
Y330009D03*
X995206Y316360D03*
X985066Y314409D03*
X978306D03*
Y318309D03*
Y322209D03*
X981686Y320260D03*
X974926Y316360D03*
Y320260D03*
X985066Y326110D03*
X981686Y328060D03*
X988446D03*
Y324160D03*
X985066Y318309D03*
Y322209D03*
X988446Y320260D03*
X981686Y324160D03*
X974926Y339760D03*
Y335860D03*
X981686Y316360D03*
X1006665Y300760D03*
Y304660D03*
Y308560D03*
Y285160D03*
Y296860D03*
Y289060D03*
Y281260D03*
Y292959D03*
X1008725Y335860D03*
X1005345Y333909D03*
X1001965Y331960D03*
X1007595Y327609D03*
X1021115Y335409D03*
X1018865Y341709D03*
X1017735Y333460D03*
X1015485Y339760D03*
X1024495Y337360D03*
X1012105Y337809D03*
X1016399Y324304D03*
X1022393Y326580D03*
X1024893D03*
X1017393D03*
X1028393Y329580D03*
X1019893Y326580D03*
X1027393D03*
X1017957Y312421D03*
X1025438Y312381D03*
X1022915Y312372D03*
X1020404Y312408D03*
X1028039Y312414D03*
X1025755Y328951D03*
X1008725Y339760D03*
X1005345Y337809D03*
X1001965Y335860D03*
X1012105Y341709D03*
X1006665Y312460D03*
X1014355Y331509D03*
X1010975Y329560D03*
X1027875Y339309D03*
X1031255Y341260D03*
X1006665Y324160D03*
Y316360D03*
Y320260D03*
X991826Y341709D03*
X988446Y335860D03*
X995206Y343660D03*
X985066Y361209D03*
X974926Y355360D03*
Y347560D03*
X978306Y353409D03*
Y349509D03*
Y357309D03*
X974926Y359260D03*
X981686D03*
X998586Y369010D03*
Y357309D03*
X981686Y347560D03*
X978306Y345609D03*
X981686Y355360D03*
X985066Y349509D03*
X998586D03*
X978306Y365109D03*
X981686Y363160D03*
X974926D03*
Y367060D03*
Y370959D03*
X988446Y367060D03*
X998586Y365109D03*
Y353409D03*
X991826Y365109D03*
X995206Y370959D03*
X991826Y353409D03*
X974926Y343660D03*
X995206Y359260D03*
X988446D03*
Y347560D03*
X991826Y345609D03*
X988446Y351460D03*
Y355360D03*
X998586Y388509D03*
X991826Y380709D03*
X998586D03*
X991826Y372909D03*
X988446Y374860D03*
X998586Y392410D03*
X988446Y382660D03*
X995206D03*
X985066Y372909D03*
X974926Y374860D03*
X985066Y384609D03*
X998586Y376809D03*
X991826Y388509D03*
X995206Y390460D03*
X974926Y386560D03*
X991826Y376809D03*
X974066Y399911D03*
X978306Y376809D03*
X974926Y378760D03*
X981686D03*
X985066Y380709D03*
X995206Y386560D03*
X1022245Y343660D03*
X1005345Y365109D03*
X1008725Y370959D03*
X1001965D03*
X1005345Y353409D03*
X1018865Y365109D03*
X1012105D03*
X1025625D03*
X1022245Y370959D03*
X1015485D03*
X1018865Y353409D03*
X1012105D03*
X1025625D03*
X1029005Y370959D03*
X1032385Y365109D03*
X1005345Y345609D03*
X1018865Y349509D03*
X1032385Y353409D03*
X1008725Y343660D03*
X1001965Y359260D03*
X1005345Y349509D03*
X1008725Y359260D03*
X1015485D03*
X1018865Y345609D03*
X1022245Y347560D03*
X1015485Y343660D03*
X1025625Y345609D03*
X1022245Y359260D03*
X1029005Y347560D03*
Y359260D03*
X1032385Y349509D03*
X1018865Y357309D03*
X1001965Y363160D03*
X1022245Y355360D03*
X1012105Y357309D03*
X1008725Y351460D03*
X1032385Y388509D03*
Y376809D03*
X1022245Y386560D03*
X1007595Y402800D03*
X1012105Y380709D03*
X1022245Y374860D03*
X1015485D03*
X1025625Y380709D03*
X1029005Y386560D03*
X1018865Y380709D03*
X1001965Y374860D03*
X1029005D03*
X1008725Y386560D03*
X1005345Y380709D03*
X1008725Y374860D03*
Y382660D03*
X1001965D03*
X1005345Y392410D03*
X1029005Y390460D03*
X1025625Y392410D03*
X1022245Y382660D03*
X1015485D03*
X1012105Y392410D03*
X1018865D03*
X1029005Y382660D03*
X1027875Y402800D03*
X1005345Y376809D03*
Y388509D03*
X1001965Y386560D03*
X1025625Y376809D03*
Y388509D03*
X1018865Y376809D03*
X1012105D03*
X1018865Y388509D03*
X1012105D03*
X985066Y345609D03*
X1025625Y357309D03*
X1032385Y380709D03*
X1025625Y369010D03*
X1015485Y363160D03*
X1022245D03*
X1012105Y369010D03*
X991826D03*
Y357309D03*
X995206Y351460D03*
X1005345Y357309D03*
Y369010D03*
X1008725Y363160D03*
X1029005D03*
X1001965Y351460D03*
X985066Y353409D03*
X987401Y515364D03*
X990748Y512792D03*
X997441Y518157D03*
X973795Y499793D03*
X977362Y512792D03*
X974015Y509999D03*
X984055Y512792D03*
X980708Y515364D03*
X984055Y518157D03*
X976421Y499768D03*
X980708Y510114D03*
X977362Y518157D03*
X1034200Y506956D03*
X1000490Y509999D03*
X1016473Y515152D03*
Y510114D03*
X1008650Y515200D03*
X1008526Y510114D03*
X1024800Y516356D03*
Y518856D03*
X976530Y497170D03*
X974015Y515364D03*
X990748Y518157D03*
X994094Y515364D03*
X997441Y512792D03*
X1000787Y515364D03*
X1003915Y512792D03*
X1004134Y518157D03*
X1011126Y510114D03*
X1013873Y515152D03*
X987401Y509999D03*
X994094Y510114D03*
X1011250Y515200D03*
X1013873Y510114D03*
X1026500Y581000D03*
X1019800Y555800D03*
X990748Y536957D03*
X977362Y529014D03*
X980708Y536957D03*
X987401Y529014D03*
X990748Y547922D03*
X980708Y547914D03*
X997441Y529022D03*
X983900Y533100D03*
Y552000D03*
X977362Y555857D03*
X987401D03*
X997441D03*
X977362Y566814D03*
X990748Y574757D03*
Y585722D03*
X980708Y585714D03*
Y574757D03*
X997441Y566822D03*
X987401Y566814D03*
X983900Y570900D03*
X1007147Y550511D03*
Y553111D03*
X1007207Y534137D03*
X1013500Y529200D03*
X1026500Y538500D03*
Y541000D03*
X1007207Y531537D03*
X1026500Y546400D03*
X1013873Y547914D03*
X1000787Y536957D03*
Y547922D03*
X1017300Y536200D03*
X1017519Y529057D03*
X1017300Y547914D03*
X1007518Y536727D03*
X1007480Y528942D03*
X1007280Y547914D03*
X1026400Y543700D03*
X1016800Y566814D03*
X1019277Y585714D03*
X1016800Y574742D03*
X1006406Y588366D03*
X1007332Y572010D03*
X1016473Y585714D03*
X1026500Y577500D03*
X1007332Y569410D03*
X1014173Y566814D03*
Y555842D03*
Y574742D03*
X1010928Y555842D03*
X1000787Y585722D03*
Y574757D03*
X1016819Y555842D03*
X1007518D03*
Y566814D03*
X1007480Y574742D03*
X1006633Y585714D03*
X1011126Y547914D03*
Y585714D03*
X1013873D03*
X1010826Y566814D03*
Y574742D03*
X1020800Y612600D03*
X1029777Y613581D03*
X980708Y604614D03*
X997441Y612357D03*
X977362Y593657D03*
X987401D03*
X997441D03*
Y607292D03*
X977362D03*
X990748Y612457D03*
X980708Y609864D03*
X987401Y604499D03*
X983900Y589800D03*
X977362Y612457D03*
X1016778Y611759D03*
X1017519Y604614D03*
Y593642D03*
X1007480Y612242D03*
X1020700Y604600D03*
X1020300Y593700D03*
X1023200Y610700D03*
X1022950Y593650D03*
X1025450D03*
X1006406Y590966D03*
X1004133Y612358D03*
X1000787Y609864D03*
X1007480Y604614D03*
X1006634Y593642D03*
X990748Y607292D03*
X987401Y609864D03*
X994094D03*
X1000787Y604499D03*
X1004134Y607292D03*
X984055Y612457D03*
X1011572Y593642D03*
X1010826Y604614D03*
X1014173Y612242D03*
X1014919Y593642D03*
X974015Y609864D03*
Y604499D03*
X984055Y607292D03*
X994094Y604614D03*
X1010826Y612242D03*
X1014173Y604614D03*
X1044290Y11792D03*
X1043800Y-9700D03*
X1047637Y-4536D03*
X1057676Y-1743D03*
X1047637Y9107D03*
X1057677D03*
X1050983Y-7108D03*
X1047637Y28007D03*
X1057677D03*
X1050984Y17042D03*
X1045525Y15357D03*
X1057792Y13200D03*
Y32100D03*
X1071062Y-1817D03*
X1061023Y-9786D03*
X1067716Y-4536D03*
Y-9901D03*
X1081102Y-4536D03*
X1074409D03*
X1084448Y-7108D03*
X1077755D03*
X1091141Y-1843D03*
X1067716Y9107D03*
X1091141D03*
X1074409D03*
X1081102D03*
X1061023Y-4536D03*
X1081102Y28007D03*
X1074409D03*
X1061024Y17057D03*
X1067716Y28007D03*
Y17042D03*
X1091141D03*
X1084450Y17057D03*
X1077757D03*
X1091141Y28007D03*
X1083116Y13200D03*
Y32100D03*
X1070976Y13200D03*
Y32100D03*
X1071062Y-7108D03*
X1094488Y-4536D03*
Y-9786D03*
X1081102Y-9901D03*
X1064369Y-7108D03*
X1087795Y-4536D03*
X1050983Y-1743D03*
X1054330Y-9901D03*
X1044291Y-2200D03*
X1087795Y-9786D03*
X1074409D03*
X1084448Y-1743D03*
X1057676Y-7108D03*
X1064369Y-1743D03*
X1077755D03*
X1054330Y-4536D03*
X1047637Y-9901D03*
X1044100Y54700D03*
X1044290Y49592D03*
X1050984Y54842D03*
X1047637Y35942D03*
Y46907D03*
X1057677Y35942D03*
Y46907D03*
X1044290Y68964D03*
X1057676Y87392D03*
X1050983Y92757D03*
X1047637Y84599D03*
X1035000Y81200D03*
X1057677Y73742D03*
X1047637D03*
X1057792Y51000D03*
Y69900D03*
X1061024Y54857D03*
X1067716Y54842D03*
Y35942D03*
Y46907D03*
Y65807D03*
X1091141Y54842D03*
Y35942D03*
X1084450Y54857D03*
X1081102Y35942D03*
X1074409D03*
X1077757Y54857D03*
X1081102Y46907D03*
X1074409D03*
X1091141D03*
Y65807D03*
X1083116Y51000D03*
X1070976D03*
X1083116Y69900D03*
X1070976D03*
X1067716Y89964D03*
Y84599D03*
X1081102D03*
X1091141Y87392D03*
Y92657D03*
X1077755Y92757D03*
X1074409Y84714D03*
X1084448Y92757D03*
X1061023Y89964D03*
X1067716Y73742D03*
X1074409D03*
X1081102D03*
X1091141D03*
X1061023Y84714D03*
X1057677Y65807D03*
X1047637D03*
X1044290Y87392D03*
X1057676Y92757D03*
X1071062D03*
X1064369Y87392D03*
X1054330Y84599D03*
X1047637Y89964D03*
X1064369Y92757D03*
X1050983Y87392D03*
X1054330Y89964D03*
X1074409Y65807D03*
X1081102D03*
Y89964D03*
X1087795Y84714D03*
Y89964D03*
X1074409D03*
X1084448Y87392D03*
X1077755D03*
X1094488Y84714D03*
Y89964D03*
X1050983Y105800D03*
X1057734Y105750D03*
X1035900Y98800D03*
X1077304Y105800D03*
X1071111D03*
X1064428D03*
X1071120Y103116D03*
X1057734D03*
X1064427D03*
X1050983D03*
X1077304Y103100D03*
X1057314Y209109D03*
X1045904D03*
X1035765Y211060D03*
X1039145Y216909D03*
X1035765Y214960D03*
X1042524D03*
X1042506Y195041D03*
X1045904Y197359D03*
X1054000Y199100D03*
X1035765Y207159D03*
X1042524Y203260D03*
X1049284Y214960D03*
Y203260D03*
X1039145Y209109D03*
X1068822Y218147D03*
X1072202Y216196D03*
X1065242Y208397D03*
X1068822Y214247D03*
X1065242Y212296D03*
Y204496D03*
X1071072Y199583D03*
X1095861Y218147D03*
X1089101Y214247D03*
Y210346D03*
X1092481Y216196D03*
X1095861Y206446D03*
X1091351Y199841D03*
X1075582Y206446D03*
Y218147D03*
X1082341D03*
X1078962Y216196D03*
X1078961Y212296D03*
X1082341Y214247D03*
X1085721Y212296D03*
Y216196D03*
X1084591Y198931D03*
X1045904Y220809D03*
X1057314D03*
X1049284Y222760D03*
X1042524Y226660D03*
X1039145Y232509D03*
X1035765Y226660D03*
X1057314Y240309D03*
X1049284Y226660D03*
X1045904Y232509D03*
X1057314D03*
Y244209D03*
X1049284Y246160D03*
X1035765Y238360D03*
Y250060D03*
X1057314Y248109D03*
X1039145D03*
X1042524Y250060D03*
X1049284D03*
X1045904Y248109D03*
X1042524Y238360D03*
X1039145Y220809D03*
X1038015Y256500D03*
X1041395Y254259D03*
X1048154D03*
X1051534Y256500D03*
X1044774Y256400D03*
X1054914Y254500D03*
X1034635Y254259D03*
X1050002Y264899D03*
X1047002D03*
X1043502D03*
X1040502D03*
X1089101Y222047D03*
Y225947D03*
X1065242Y220096D03*
X1075582Y225947D03*
X1095861Y229847D03*
X1068822Y233746D03*
X1065242Y235696D03*
Y223996D03*
X1068822Y237647D03*
Y249347D03*
X1065242Y247396D03*
X1068822Y241547D03*
X1072202Y243496D03*
Y251296D03*
X1092481Y223996D03*
Y231797D03*
X1089101Y233746D03*
X1068822Y229847D03*
X1095861Y233746D03*
X1092481Y247396D03*
X1089101Y245447D03*
X1085721Y247396D03*
X1089101Y249347D03*
X1092481Y251296D03*
X1095861Y249347D03*
X1089101Y237647D03*
X1095861D03*
Y245447D03*
X1078962Y251296D03*
X1082341Y245447D03*
Y249347D03*
X1078962Y247396D03*
X1092481Y243496D03*
X1075582Y245447D03*
X1085721Y251296D03*
X1075582Y249347D03*
X1085721Y243496D03*
X1089101Y241547D03*
X1085721Y223996D03*
X1075582Y229847D03*
X1082341D03*
X1078962Y227896D03*
Y220096D03*
Y223996D03*
X1085721Y231797D03*
X1082341Y237647D03*
X1075582D03*
X1072202Y231797D03*
Y223996D03*
X1065242Y239596D03*
X1068822Y245447D03*
X1085721Y227896D03*
X1095861Y222047D03*
X1082341D03*
X1079859Y265000D03*
X1089101Y253247D03*
X1092481Y255196D03*
X1095861Y257147D03*
X1089100Y264500D03*
X1092300Y267200D03*
X1095700Y268790D03*
X1089000Y267000D03*
X1067692Y254000D03*
X1071072Y255728D03*
X1087971Y257800D03*
X1091351Y259600D03*
X1094731Y261500D03*
X1084591Y255497D03*
X1081212Y257600D03*
X1095861Y253247D03*
X1092100Y264500D03*
X1078962Y239596D03*
X1082341Y233746D03*
X1085721Y239596D03*
X1075582Y233746D03*
X1039145Y228610D03*
X1049284Y238360D03*
X1072202Y239596D03*
X1057314Y224709D03*
X1047756Y338341D03*
X1044256D03*
X1050756D03*
X1053702Y338404D03*
X1095702Y309904D03*
X1071102Y292904D03*
X1068102D03*
X1063902D03*
X1075302Y309904D03*
X1082502D03*
X1092756Y309841D03*
X1089702Y309904D03*
X1085502D03*
X1078302D03*
X1071102D03*
X1068102D03*
X1063902D03*
X1060902D03*
Y292904D03*
X1085502D03*
X1082502D03*
X1078302D03*
X1075302D03*
X1089702D03*
X1092702D03*
X1076435Y343595D03*
X1052664Y357309D03*
X1049284Y370959D03*
X1035765D03*
X1042524D03*
X1045904Y365109D03*
X1039145D03*
X1052664D03*
X1035765Y355360D03*
X1042524Y359260D03*
X1049284Y351460D03*
X1045904Y353409D03*
X1035765Y351460D03*
Y359260D03*
X1039145Y353409D03*
X1042524Y351460D03*
X1054914Y347000D03*
X1042524Y355360D03*
X1045904Y357309D03*
X1039145D03*
X1045904Y369010D03*
X1049284Y359260D03*
X1034635Y343209D03*
X1038015Y345160D03*
X1041395Y347109D03*
X1048154D03*
X1044774Y345160D03*
X1051534D03*
X1039145Y388509D03*
X1045904D03*
X1052664D03*
X1039145Y376809D03*
X1045904D03*
X1042524Y386560D03*
X1045904Y380709D03*
X1035765Y374860D03*
Y386560D03*
X1052664Y380709D03*
X1049284Y374860D03*
X1042524D03*
X1039145Y380709D03*
X1052664Y392410D03*
X1040265Y394359D03*
X1049284Y382660D03*
X1035765D03*
X1042524D03*
Y390460D03*
X1056176Y402471D03*
X1041395Y402800D03*
X1052664Y376809D03*
X1060694Y351460D03*
X1086841Y358547D03*
X1094731Y346546D03*
X1086841Y354647D03*
X1090221Y352696D03*
X1091351Y348497D03*
X1073322Y354647D03*
X1076702Y356596D03*
X1080082Y354647D03*
X1083462Y368296D03*
X1076702Y372197D03*
Y368296D03*
X1073322Y362447D03*
X1086841D03*
X1090221Y372197D03*
Y364396D03*
X1093601Y366347D03*
X1090221Y368296D03*
X1076702Y360496D03*
X1083462D03*
Y352696D03*
X1076702D03*
X1093601Y358547D03*
X1086841Y366347D03*
X1073322D03*
X1083462Y372197D03*
X1093601Y362447D03*
X1090221Y356596D03*
X1080082Y366347D03*
Y362447D03*
X1071072Y348497D03*
X1087971Y346546D03*
X1074452D03*
X1081212D03*
X1077832Y348497D03*
X1084591D03*
X1090221Y379996D03*
X1073323Y401449D03*
X1078962Y399496D03*
X1093601Y401447D03*
Y389747D03*
X1090221Y383896D03*
X1073322Y389747D03*
X1083462Y387796D03*
X1073322Y381947D03*
X1080082D03*
X1076702Y391696D03*
Y387796D03*
X1060694Y390460D03*
Y374860D03*
X1073322Y374146D03*
X1086841D03*
X1073323Y397548D03*
X1073322Y385847D03*
X1080082Y393647D03*
X1083462Y391696D03*
X1080082Y385847D03*
X1083462Y376096D03*
X1080082Y378047D03*
X1083462Y379996D03*
X1076702Y376096D03*
X1090221Y395595D03*
X1086841Y389747D03*
X1093601Y393647D03*
X1090221Y391696D03*
X1093601Y385847D03*
X1086841D03*
X1093601Y397546D03*
Y378047D03*
X1086841Y381947D03*
X1080082Y370247D03*
X1052664Y353409D03*
X1060694Y355360D03*
X1061039Y359351D03*
X1039145Y369010D03*
X1042524Y363160D03*
X1035765D03*
X1052664Y369010D03*
X1049284Y363160D03*
X1076702Y379996D03*
X1093601Y405347D03*
X1077832Y407800D03*
X1035750Y503006D03*
X1050983Y512792D03*
X1054330Y509999D03*
X1044290Y512792D03*
X1047637Y509999D03*
X1057676Y512792D03*
X1035000Y521556D03*
X1050983Y518157D03*
X1067716Y509999D03*
X1074409Y510114D03*
X1061023Y515364D03*
X1091141Y518057D03*
X1077755Y518157D03*
X1081102Y509999D03*
X1084448Y518157D03*
X1082800Y497650D03*
X1091141Y512792D03*
X1067716Y515364D03*
X1061023Y510114D03*
X1087795D03*
X1077755Y512792D03*
X1071062Y518157D03*
X1084448Y512792D03*
X1057676Y518157D03*
X1064369Y512792D03*
X1047637Y515364D03*
X1064369Y518157D03*
X1054330Y515364D03*
X1087795D03*
X1074409D03*
X1094488Y510114D03*
Y515364D03*
X1081102D03*
X1084800Y499400D03*
X1057792Y552000D03*
Y533100D03*
X1044203Y537058D03*
X1044290Y550592D03*
X1057677Y547907D03*
Y536942D03*
X1047637Y547907D03*
Y536942D03*
X1044195Y529026D03*
X1057677Y574742D03*
Y585707D03*
X1047637Y574742D03*
Y585707D03*
X1044290Y569492D03*
X1057792Y570900D03*
X1047637Y566807D03*
X1057677D03*
X1050984Y555842D03*
X1074409Y547907D03*
X1081102D03*
X1091141D03*
Y529007D03*
Y536942D03*
X1074409D03*
X1081102D03*
X1067716D03*
Y529007D03*
X1070976Y552000D03*
Y533100D03*
X1084003Y532904D03*
X1083116Y552000D03*
X1074409Y566807D03*
X1061024Y555857D03*
X1077757D03*
X1084450D03*
X1091141Y555842D03*
X1067716D03*
X1081102Y574742D03*
Y585707D03*
X1074409D03*
X1091141Y574742D03*
Y585707D03*
X1067716Y574742D03*
Y585599D03*
Y566807D03*
X1091141D03*
X1074409Y574742D03*
X1070976Y570900D03*
X1083116D03*
X1057677Y529007D03*
X1047637D03*
X1044290Y588392D03*
X1081102Y566807D03*
X1071062Y612560D03*
X1064369Y612657D03*
X1084448D03*
X1091141Y612557D03*
X1050984Y612658D03*
X1057676Y612657D03*
X1046500Y623500D03*
X1050984Y593642D03*
X1047637Y609864D03*
X1044290Y607292D03*
X1057792Y589800D03*
X1054330Y609864D03*
X1087795D03*
X1071062Y607292D03*
X1061024Y593657D03*
X1061023Y604614D03*
X1077757Y593657D03*
X1084450D03*
X1067716Y593642D03*
Y609864D03*
Y604499D03*
X1081102Y609864D03*
X1091141Y593642D03*
Y607292D03*
X1084448D03*
X1077755D03*
X1061023Y609864D03*
X1070242Y589800D03*
X1083108D03*
X1077755Y612657D03*
X1044291Y612658D03*
X1057676Y607292D03*
X1047637Y604499D03*
X1094488Y604614D03*
X1081102Y604499D03*
X1054330D03*
X1050983Y607292D03*
X1074409Y609864D03*
Y593642D03*
X1087795Y604614D03*
X1074409D03*
X1094488Y609864D03*
X1064369Y607292D03*
X1119453Y-9864D03*
X1097352Y-7180D03*
X1104141Y-7851D03*
X1110520Y-7700D03*
X1114340Y-1801D03*
X1107874Y-1751D03*
X1101181Y-1801D03*
X1107724Y9114D03*
X1101181D03*
X1114340Y9098D03*
X1114400Y28100D03*
X1110520Y14814D03*
X1104177Y14714D03*
X1098500Y17000D03*
X1114300Y16900D03*
X1110520Y33700D03*
X1107874Y27899D03*
X1104141Y33700D03*
X1101181Y27899D03*
X1114366Y30750D03*
X1119440Y33149D03*
X1114340Y33399D03*
X1119440Y30540D03*
X1097834Y11100D03*
X1119400Y9300D03*
X1119453Y27936D03*
X1119440Y17114D03*
X1097900Y13700D03*
Y31900D03*
X1110520Y30100D03*
X1097834Y28100D03*
X1104141Y29949D03*
X1156300Y-2000D03*
X1151152Y-1801D03*
X1131299Y9114D03*
X1124606D03*
X1151152Y9098D03*
X1137992Y9114D03*
X1144535D03*
X1147331Y-4100D03*
X1144685Y-9901D03*
X1140952Y-4100D03*
X1137992Y-9901D03*
X1151178Y-7050D03*
X1156252Y-7260D03*
X1151152Y-4401D03*
X1156252Y-4651D03*
X1124606Y27899D03*
X1147331Y33700D03*
X1144685Y27899D03*
X1140952Y33700D03*
X1137992Y27899D03*
X1151177Y30750D03*
X1156251Y33149D03*
X1127952Y-7851D03*
X1124606Y-1751D03*
X1131299D03*
X1134645Y-7851D03*
X1156265Y-9864D03*
X1151200Y-9700D03*
X1147331Y-7700D03*
X1140952Y-7851D03*
X1137992Y-1801D03*
X1144685Y-1751D03*
X1151151Y33399D03*
X1156251Y30540D03*
X1144685Y17157D03*
X1147331Y12114D03*
X1137992Y17157D03*
X1141038Y12114D03*
X1151152Y14300D03*
X1156252Y14514D03*
X1151152Y11700D03*
X1156252Y11914D03*
X1156212Y9300D03*
X1127952Y14814D03*
X1151211Y28100D03*
X1156252Y17114D03*
X1151112Y16900D03*
X1147331Y30100D03*
Y14814D03*
X1134645Y29949D03*
X1140952D03*
X1140988Y14714D03*
X1134645Y14814D03*
X1156265Y27936D03*
X1127952Y29949D03*
X1131299Y27899D03*
X1119440Y-4651D03*
X1114340Y-4401D03*
X1119440Y-7260D03*
X1114366Y-7050D03*
X1124606Y-9901D03*
X1127952Y-3700D03*
X1131299Y-9901D03*
X1107874D03*
X1110520Y-4100D03*
X1134645Y-3700D03*
X1119440Y11914D03*
X1114340Y11700D03*
X1119440Y14514D03*
X1114340Y14300D03*
X1127952Y12114D03*
X1124606Y17157D03*
X1131299D03*
X1110520Y12114D03*
X1107874Y17157D03*
X1134645Y12114D03*
X1101181Y17157D03*
X1104227Y12114D03*
X1101181Y-9901D03*
X1104141Y-4100D03*
X1114340Y35999D03*
X1098235Y68090D03*
X1110520Y67900D03*
X1104141Y67749D03*
X1114366Y65950D03*
X1107874Y65699D03*
X1101181D03*
X1114366Y68550D03*
X1119440Y68340D03*
X1107874Y54957D03*
X1110520Y49914D03*
X1101181Y54957D03*
X1104227Y49564D03*
X1114340Y52100D03*
X1119440Y49714D03*
X1114340Y49500D03*
X1119440Y52314D03*
Y54914D03*
X1119400Y47100D03*
Y35800D03*
X1098100Y51000D03*
X1119453Y65736D03*
X1107874Y36049D03*
X1098022Y35761D03*
X1101181Y35999D03*
X1107724Y46914D03*
X1110520Y52614D03*
X1098581Y54883D03*
X1104177Y52514D03*
X1101181Y46900D03*
X1098125Y46975D03*
X1114300Y54700D03*
X1114340Y46898D03*
X1098259Y70896D03*
X1101181Y84714D03*
X1098218Y85296D03*
X1114340Y73799D03*
X1107874Y73849D03*
X1101181Y73799D03*
X1098207Y73589D03*
X1110520Y90314D03*
X1114340Y84698D03*
X1114316Y92500D03*
X1107724Y84714D03*
X1119440Y92714D03*
X1119416Y84700D03*
X1119466Y73550D03*
X1098300Y89900D03*
X1104177Y90314D03*
X1110520Y71500D03*
X1107874Y92757D03*
X1110520Y87714D03*
X1104227D03*
X1114340Y89900D03*
X1119440Y70949D03*
Y87514D03*
X1114340Y71199D03*
Y87300D03*
X1119440Y90114D03*
X1127952Y34100D03*
X1124606Y54957D03*
X1127952Y49914D03*
X1144685Y54957D03*
X1147331Y49914D03*
X1137992Y54957D03*
X1141038Y49914D03*
X1151151Y52100D03*
X1156251Y49714D03*
X1151151Y49500D03*
X1156251Y52314D03*
X1127952Y67749D03*
X1156211Y35800D03*
X1156200Y47000D03*
X1151152Y35999D03*
Y46898D03*
X1151100Y54700D03*
X1147331Y52614D03*
X1134645D03*
X1137992Y46914D03*
Y35999D03*
X1144535Y46914D03*
X1144685Y36049D03*
X1156252Y54914D03*
X1134645Y67749D03*
X1140952D03*
X1156265Y65736D03*
X1151178Y65950D03*
X1147331Y67900D03*
X1131299Y46914D03*
X1124606D03*
X1127952Y52614D03*
X1131299Y36049D03*
X1124606D03*
X1131299Y65699D03*
X1124606D03*
X1144685D03*
X1137992D03*
X1151178Y68550D03*
X1156252Y68340D03*
X1131299Y54957D03*
X1134645Y34100D03*
Y49914D03*
X1131299Y73849D03*
X1124606D03*
X1127952Y90414D03*
X1131299Y84714D03*
X1124606D03*
X1147331Y90414D03*
X1137992Y73799D03*
X1144535Y84714D03*
X1140988Y90314D03*
X1137992Y84714D03*
X1134645Y90414D03*
Y71900D03*
X1131299Y92757D03*
X1134645Y87714D03*
X1127952Y71900D03*
X1124606Y92757D03*
X1127952Y87714D03*
X1147331Y71500D03*
X1144685Y92757D03*
X1147331Y87714D03*
X1140952Y71500D03*
X1137992Y92757D03*
X1141038Y87714D03*
X1151152Y89900D03*
X1156252Y70949D03*
Y87514D03*
X1151152Y71199D03*
Y87300D03*
X1156252Y90114D03*
X1144685Y73849D03*
X1156252Y92714D03*
X1151128Y92500D03*
X1151152Y84698D03*
X1156228Y84700D03*
X1156278Y73550D03*
X1151152Y73799D03*
X1101181Y92757D03*
X1104141Y71500D03*
X1138242Y104314D03*
X1144685D03*
X1144535Y112357D03*
X1147331Y106964D03*
X1138242Y112357D03*
X1141038Y106964D03*
X1151152Y110514D03*
X1156252Y107655D03*
X1151178Y107865D03*
X1156278Y110264D03*
Y112865D03*
X1151152Y113114D03*
X1141038Y109564D03*
X1147331D03*
X1156265Y105051D03*
X1151178Y105265D03*
X1099241Y216196D03*
Y212296D03*
X1109381Y214247D03*
X1116141Y218147D03*
X1106001Y212296D03*
X1102621Y218147D03*
Y214247D03*
X1119521Y216196D03*
X1119520Y212296D03*
X1104871Y198050D03*
X1106001Y216196D03*
X1112761D03*
X1129660Y206447D03*
X1126280Y216196D03*
Y212296D03*
X1125300Y199900D03*
X1122900Y214247D03*
Y218147D03*
X1129660Y214247D03*
X1147950Y209900D03*
X1136420Y218147D03*
Y214247D03*
X1151060Y212296D03*
X1157820D03*
Y216196D03*
X1151060D03*
X1154440Y214247D03*
X1144300Y274696D03*
X1106001Y227896D03*
X1116141Y222047D03*
X1109381D03*
Y225947D03*
X1116141Y233746D03*
X1112761Y239596D03*
X1119521Y231797D03*
X1099241Y227896D03*
Y220096D03*
X1102621Y229847D03*
X1099241Y223996D03*
X1109381Y233746D03*
X1112761Y231797D03*
Y223996D03*
X1116141Y237647D03*
X1109381D03*
X1106001Y223996D03*
X1102621Y237647D03*
X1119521Y239596D03*
X1106001D03*
X1102621Y233746D03*
X1099241Y239596D03*
X1102621Y245447D03*
X1112761Y251296D03*
X1116141Y245447D03*
X1106001Y243496D03*
X1112761D03*
X1109381Y241547D03*
X1106001Y251296D03*
X1099241D03*
Y247396D03*
X1119521Y223996D03*
Y220096D03*
Y227896D03*
Y247396D03*
Y251296D03*
X1106001Y231797D03*
X1116141Y229847D03*
X1096756Y278941D03*
X1099186Y278938D03*
X1102336Y274819D03*
X1107561Y269038D03*
X1116141Y264947D03*
X1111631Y271300D03*
X1106001Y262996D03*
Y259096D03*
X1099241Y255196D03*
Y259096D03*
X1119521Y270796D03*
X1118391Y274997D03*
X1119521Y255196D03*
X1102621Y261047D03*
Y257147D03*
X1109381Y261047D03*
X1116141Y257147D03*
X1112761Y259096D03*
X1110648Y276899D03*
X1100200Y273300D03*
X1101491Y265400D03*
X1104871Y267300D03*
X1098111Y263400D03*
X1116141Y268847D03*
X1112761Y262996D03*
X1116141Y261047D03*
X1119521Y278596D03*
X1129660Y237647D03*
X1126280Y223996D03*
Y231797D03*
X1122900Y229847D03*
X1126280Y227896D03*
X1133040D03*
X1129660Y225947D03*
Y222047D03*
X1126280Y239596D03*
X1122900Y233746D03*
X1144300Y223996D03*
X1154440Y225947D03*
X1147680Y245447D03*
X1122900Y237647D03*
X1129660Y233746D03*
Y241547D03*
X1126280Y251296D03*
Y243496D03*
X1122900Y245447D03*
X1144300Y243496D03*
X1147680Y249347D03*
X1151060Y247396D03*
X1154440Y245447D03*
X1144300Y247396D03*
Y251296D03*
X1136420Y245447D03*
X1154440Y241547D03*
X1136420D03*
X1157820Y239596D03*
X1147680Y222047D03*
X1144300Y235696D03*
X1136420Y229847D03*
Y233746D03*
Y222047D03*
Y225947D03*
Y237647D03*
X1133040Y223996D03*
Y235696D03*
Y243496D03*
Y251296D03*
X1147680Y225947D03*
X1151060Y223996D03*
X1147680Y233746D03*
X1154440Y229847D03*
X1157820Y220096D03*
Y223996D03*
Y231797D03*
X1147680Y280547D03*
X1137540Y266896D03*
X1147680Y268847D03*
X1137540Y270796D03*
X1140920Y268847D03*
Y264947D03*
X1144300Y262996D03*
X1126280Y266896D03*
X1129660Y264947D03*
X1122900D03*
Y268847D03*
X1154440Y253247D03*
X1130780Y278596D03*
X1129660Y261047D03*
X1130780Y274696D03*
X1126280Y259096D03*
X1122900Y257147D03*
X1157820Y278596D03*
Y270796D03*
X1151060Y266896D03*
Y274696D03*
X1137540D03*
X1151060Y259096D03*
X1144300Y255196D03*
X1133040Y259096D03*
X1134160Y268847D03*
X1136420Y257147D03*
X1144300Y278596D03*
Y270796D03*
X1137540Y278596D03*
X1126280Y262996D03*
X1154440Y261047D03*
X1127400Y280547D03*
Y276646D03*
X1134160Y280547D03*
X1157820Y266896D03*
X1151060Y278596D03*
X1154440Y264947D03*
X1119521Y266896D03*
Y262996D03*
X1134160Y276646D03*
X1157820Y247396D03*
X1154440Y249347D03*
X1151060Y220096D03*
X1154440Y233746D03*
X1144300Y227896D03*
X1151060Y235696D03*
X1144300Y239596D03*
X1151060Y243496D03*
Y239596D03*
X1144300Y266896D03*
X1108125Y276799D03*
X1157820Y251296D03*
X1154440Y257147D03*
X1122900Y261047D03*
X1119521Y259096D03*
X1147680Y264947D03*
X1154440Y222047D03*
X1147680Y237647D03*
X1144300Y231797D03*
X1129660Y245447D03*
X1109381D03*
X1122900Y249347D03*
X1112761Y247396D03*
X1106001D03*
X1129660Y253247D03*
X1109381D03*
X1126280Y255196D03*
X1116141Y253247D03*
X1136420Y249347D03*
X1157820Y235696D03*
X1151060Y227896D03*
Y231797D03*
X1154440Y311747D03*
X1157820Y305896D03*
X1154440Y303947D03*
X1157820Y301996D03*
X1154440Y300047D03*
X1119521Y282496D03*
Y301996D03*
X1101256Y308841D03*
X1103756Y307841D03*
Y310341D03*
X1119521Y286396D03*
Y305896D03*
X1113900Y297800D03*
X1113132Y291702D03*
X1098756Y309841D03*
X1119521Y298096D03*
Y294196D03*
Y290296D03*
Y309797D03*
X1113500Y323400D03*
X1119521Y313696D03*
Y317596D03*
X1109200Y325100D03*
X1108251Y338746D03*
X1117261Y340996D03*
X1104871Y340697D03*
X1119521Y321496D03*
X1102300Y336700D03*
X1118391Y332897D03*
X1105900Y334000D03*
X1134160Y307847D03*
X1151060Y294196D03*
X1147680Y300047D03*
Y296147D03*
X1140920Y307847D03*
Y311747D03*
X1151060Y301996D03*
X1144300Y305896D03*
X1147680Y311747D03*
X1130780Y290296D03*
X1127400Y288347D03*
X1130780Y309797D03*
Y301996D03*
X1127400Y303947D03*
Y307847D03*
X1157820Y290296D03*
X1151060Y298096D03*
Y290296D03*
Y282496D03*
X1144300Y286396D03*
Y294196D03*
X1157820D03*
X1140920Y300047D03*
X1134160Y292247D03*
Y300047D03*
X1140920Y292247D03*
X1137540Y282496D03*
X1144300Y309797D03*
X1137540D03*
X1147680Y303947D03*
X1154440Y307847D03*
X1157820Y298096D03*
X1127400Y284447D03*
Y300047D03*
X1130780Y294196D03*
X1127400Y296147D03*
Y292247D03*
X1130780Y298096D03*
Y305896D03*
X1137540Y290296D03*
X1134160Y296147D03*
Y288347D03*
X1147680Y307847D03*
X1151060Y309797D03*
Y305896D03*
X1144300Y301996D03*
Y298096D03*
X1137540D03*
X1140920Y303947D03*
X1137540Y305896D03*
X1140920Y296147D03*
X1137540Y294196D03*
X1127400Y311747D03*
X1154440Y296147D03*
X1130780Y313696D03*
X1157820D03*
X1134160Y335147D03*
Y339047D03*
X1140920Y319547D03*
X1124021Y340996D03*
Y337096D03*
X1127400Y327347D03*
X1157820Y337096D03*
Y333196D03*
X1134160Y323446D03*
X1151060Y340996D03*
Y333196D03*
X1154440Y319547D03*
X1157820Y317596D03*
X1137540D03*
X1157820Y329296D03*
X1147680Y327347D03*
X1154440Y335147D03*
X1144300Y340996D03*
Y337096D03*
X1140920Y339047D03*
Y331247D03*
X1154440Y323446D03*
Y315647D03*
X1147680Y319547D03*
X1157820Y325396D03*
X1154440Y339047D03*
Y331247D03*
X1144300Y317596D03*
X1137540Y321496D03*
X1134160Y327347D03*
X1137540Y325396D03*
X1127400Y319547D03*
Y315647D03*
X1124021Y325396D03*
X1127400Y323446D03*
X1124021Y329296D03*
Y333196D03*
X1154440Y327347D03*
X1147680Y339047D03*
X1157820Y321496D03*
X1130780Y329296D03*
X1140920Y323446D03*
X1144300Y313696D03*
X1151060D03*
X1144300Y325396D03*
Y321496D03*
X1151060Y329296D03*
X1147680Y335147D03*
Y331247D03*
X1140920Y335147D03*
X1144300Y333196D03*
X1151060Y325396D03*
Y321496D03*
X1147680Y323446D03*
X1137540Y329296D03*
X1144300D03*
X1140920Y327347D03*
X1130780Y340996D03*
Y337096D03*
X1127400Y331247D03*
Y335147D03*
Y339047D03*
X1147680Y315647D03*
X1151060Y317596D03*
X1137540Y337096D03*
Y340996D03*
Y333196D03*
X1130780Y282496D03*
Y286396D03*
X1134160Y311747D03*
Y315647D03*
X1116999Y286826D03*
X1134160Y284447D03*
X1100361Y350747D03*
X1113881D03*
Y358547D03*
X1117261Y348796D03*
X1100361Y358547D03*
X1103741Y348796D03*
Y352696D03*
X1110501D03*
X1107121Y346847D03*
Y354647D03*
Y358547D03*
Y362447D03*
X1103741Y372197D03*
X1110501Y364396D03*
X1103741D03*
X1113881Y366347D03*
X1117261Y372197D03*
Y368296D03*
X1110501Y372197D03*
X1096981Y368296D03*
Y372197D03*
X1100361Y366347D03*
X1103741Y368296D03*
X1110501D03*
X1103741Y356596D03*
X1113881Y362447D03*
X1107121Y370247D03*
X1096981Y352696D03*
X1117261D03*
X1096981Y360496D03*
X1117261D03*
X1101491Y342646D03*
X1098111Y344597D03*
X1113881Y346847D03*
Y401447D03*
X1103741Y383896D03*
X1113881Y381947D03*
X1110501Y387796D03*
X1096981Y383896D03*
X1117261Y391696D03*
X1096981Y379996D03*
Y387796D03*
X1113881Y374146D03*
X1100361D03*
X1107121Y378047D03*
Y374146D03*
X1110501Y391696D03*
Y395595D03*
X1107121Y389747D03*
X1100361Y385847D03*
X1107121D03*
X1100361Y393647D03*
X1103741Y391696D03*
X1100361Y397547D03*
X1113881Y385847D03*
Y397546D03*
Y393647D03*
X1103741Y379996D03*
X1113881Y378047D03*
X1117261Y376096D03*
X1110501Y379996D03*
X1107121Y381947D03*
X1096981Y376096D03*
X1100361Y378047D03*
X1151060Y368296D03*
X1147680Y366347D03*
X1120641Y350747D03*
Y358547D03*
Y366347D03*
X1127400Y362447D03*
X1124021Y348796D03*
Y352696D03*
X1127400Y354647D03*
Y358547D03*
X1134160D03*
X1130780Y360496D03*
X1127400Y342947D03*
X1134160Y346847D03*
Y362447D03*
Y366347D03*
Y370247D03*
X1147680Y342947D03*
X1151060Y356596D03*
Y360496D03*
X1144300D03*
X1137540D03*
X1144300Y356596D03*
X1140920Y358547D03*
X1147680Y346847D03*
Y350747D03*
X1151060Y352696D03*
Y348796D03*
X1147680Y358547D03*
X1157820Y360496D03*
X1154440Y358547D03*
Y342947D03*
Y354647D03*
X1157820Y352696D03*
X1147680Y354647D03*
X1144300Y348796D03*
X1140920Y346847D03*
Y350747D03*
X1144300Y344896D03*
X1151060D03*
X1154440Y346847D03*
X1140920Y362447D03*
X1154440Y366347D03*
X1144300Y372197D03*
X1137540D03*
Y368296D03*
X1140920Y366347D03*
Y370247D03*
X1151060Y364396D03*
X1144300D03*
X1137540D03*
X1147680Y362447D03*
X1130780Y352696D03*
Y344896D03*
X1124021Y372197D03*
X1130780D03*
X1124021Y364396D03*
X1120641Y370247D03*
X1130780Y368296D03*
X1127400Y366347D03*
X1124021Y356596D03*
X1157820D03*
X1144300Y352696D03*
X1154440Y350747D03*
Y362447D03*
X1144300Y368296D03*
X1120641Y342947D03*
X1137540Y352696D03*
X1130780Y356596D03*
X1134160Y342947D03*
Y354647D03*
Y350747D03*
X1137540Y348796D03*
Y344896D03*
Y403396D03*
Y399496D03*
X1124021Y391696D03*
X1130780Y395596D03*
X1127400Y385847D03*
Y389747D03*
X1130780Y391696D03*
X1124021Y379996D03*
X1127400Y381947D03*
X1130780Y379996D03*
X1137540Y395597D03*
X1140920Y397546D03*
X1137540Y376096D03*
X1157820Y387796D03*
X1140920Y378047D03*
Y381947D03*
X1147680Y393647D03*
X1124021Y387796D03*
X1120641Y381947D03*
X1134160Y389747D03*
X1144300Y395597D03*
X1137540Y391696D03*
X1124021Y376096D03*
X1130780D03*
X1127400Y378047D03*
X1157820Y379996D03*
X1147680Y389747D03*
X1144300Y376096D03*
X1151060Y383896D03*
X1120641Y385847D03*
Y393647D03*
Y378047D03*
Y401447D03*
X1140920Y374146D03*
X1151060Y395597D03*
Y391696D03*
X1147680Y385847D03*
Y397546D03*
X1151060Y379996D03*
X1154440Y378047D03*
Y381947D03*
X1140920Y389747D03*
X1134160Y393647D03*
Y385847D03*
Y378047D03*
X1140920Y385847D03*
X1144300Y391696D03*
X1130780Y348796D03*
X1127400Y346847D03*
X1154440Y397546D03*
Y385847D03*
X1157820Y391696D03*
X1154440Y389747D03*
X1157820Y395597D03*
X1151060Y387796D03*
X1154440Y393647D03*
X1134160Y381947D03*
X1100361Y389747D03*
X1117261Y407296D03*
X1113881Y405347D03*
X1096699Y407782D03*
X1134160Y405347D03*
X1119440Y518114D03*
X1114316Y517900D03*
X1114340Y510098D03*
X1110520Y515714D03*
X1097343Y512794D03*
X1104177Y515714D03*
X1101181Y510114D03*
X1098300Y515300D03*
X1107724Y510114D03*
X1110520Y513114D03*
X1104227D03*
X1119440Y515514D03*
X1151152Y515300D03*
X1156252Y512914D03*
X1151152Y512700D03*
X1156252Y515514D03*
Y496167D03*
X1137992Y495887D03*
X1144385D03*
X1140988Y493744D03*
X1156252Y490867D03*
X1147331Y493494D03*
X1151168Y490867D03*
X1147331Y490894D03*
X1141038Y491144D03*
X1156252Y493567D03*
X1127952Y515814D03*
X1124606Y510114D03*
X1131299D03*
X1156252Y518114D03*
X1147331Y515814D03*
X1151128Y517900D03*
X1156252Y498867D03*
X1151168D03*
X1151152Y510098D03*
X1134645Y515814D03*
X1137992Y510114D03*
X1140988Y515714D03*
X1144535Y510114D03*
X1156228Y510100D03*
X1127952Y513114D03*
X1144685Y518157D03*
X1147331Y513114D03*
X1137992Y518157D03*
X1141038Y513114D03*
X1114340Y512700D03*
X1119440Y512914D03*
X1114340Y515300D03*
X1124606Y518157D03*
X1101181D03*
X1131299D03*
X1107874D03*
X1151168Y493467D03*
X1134645Y513114D03*
X1151168Y496167D03*
X1137992Y498487D03*
X1144385D03*
X1119440Y550714D03*
Y553314D03*
X1104141Y530949D03*
X1098040Y536723D03*
X1098160Y533809D03*
X1119416Y547900D03*
X1119466Y536750D03*
X1119453Y528936D03*
X1098300Y553100D03*
X1114340Y547898D03*
X1107724Y547914D03*
X1101181D03*
X1110520Y553514D03*
X1104177D03*
X1098118Y549843D03*
X1098018Y531156D03*
X1114366Y529150D03*
X1114340Y536999D03*
X1110520Y531100D03*
X1107874Y537049D03*
X1101181Y536999D03*
X1107874Y528899D03*
X1101181D03*
X1110520Y550914D03*
X1104227D03*
X1119440Y571949D03*
X1104227Y588714D03*
X1114340Y588300D03*
X1097343Y588394D03*
X1119440Y555914D03*
X1114316Y555700D03*
X1119416Y585700D03*
X1119466Y574550D03*
X1119453Y566736D03*
X1104141Y568749D03*
X1097899Y574773D03*
X1101181Y585714D03*
X1097834Y569200D03*
X1107724Y585714D03*
X1107874Y574849D03*
X1110520Y568900D03*
X1101181Y574799D03*
X1114340D03*
Y585698D03*
X1114366Y566950D03*
X1107874Y555957D03*
X1110520Y572500D03*
X1107874Y566699D03*
X1101181Y555957D03*
X1104141Y572500D03*
X1101181Y566699D03*
X1156252Y534149D03*
X1151152Y534399D03*
X1156252Y531540D03*
X1134645Y550914D03*
X1127952D03*
X1147331D03*
X1141038D03*
X1156252Y550714D03*
Y553314D03*
X1140988Y553514D03*
X1151152Y547898D03*
X1156228Y547900D03*
X1137992Y547914D03*
X1144535D03*
X1127952Y553614D03*
X1131299Y547914D03*
X1124606D03*
X1131299Y537049D03*
X1124606D03*
X1127952Y530949D03*
X1151178Y529150D03*
X1151152Y536999D03*
X1147331Y531100D03*
X1156278Y536750D03*
X1156265Y528936D03*
X1134645Y530949D03*
X1140952D03*
X1137992Y536999D03*
X1144685Y537049D03*
X1147331Y553614D03*
X1134645D03*
X1147331Y534700D03*
X1144685Y528899D03*
X1140952Y534700D03*
X1137992Y528899D03*
X1156252Y569340D03*
X1134645Y588714D03*
X1127952D03*
X1147331D03*
X1141038D03*
X1156252Y588514D03*
X1151152Y588300D03*
X1156252Y555914D03*
X1151128Y555700D03*
X1156265Y566736D03*
X1151178Y566950D03*
X1134645Y568749D03*
X1137992Y585714D03*
X1144535D03*
X1140952Y568749D03*
X1137992Y574799D03*
X1144685Y574849D03*
X1151152Y585698D03*
Y574799D03*
X1147331Y568900D03*
X1156228Y585700D03*
X1156278Y574550D03*
X1131299Y585714D03*
X1124606D03*
X1131299Y574849D03*
X1127952Y568749D03*
X1124606Y574849D03*
X1131299Y555957D03*
X1134645Y572900D03*
X1131299Y566699D03*
X1124606Y555957D03*
X1127952Y572900D03*
X1124606Y566699D03*
X1144685D03*
X1110520Y588714D03*
X1119440Y588514D03*
Y534149D03*
X1114366Y531750D03*
X1127952Y535100D03*
X1104141Y534700D03*
X1131299Y528899D03*
X1110520Y534700D03*
X1151152Y550500D03*
Y553100D03*
X1151178Y569550D03*
X1137992Y555957D03*
X1147331Y572500D03*
X1144685Y555957D03*
X1114340Y553100D03*
Y550500D03*
X1114366Y569550D03*
X1119440Y531540D03*
Y569340D03*
X1151178Y531750D03*
X1124606Y528899D03*
X1137992Y566699D03*
X1156252Y571949D03*
X1114340Y534399D03*
X1134645Y535100D03*
X1151152Y572199D03*
X1140952Y572500D03*
X1114340Y572199D03*
X1137992Y612599D03*
X1144685Y612649D03*
X1151152Y612599D03*
X1124606Y612649D03*
X1131299D03*
X1097374Y612659D03*
X1114340Y612599D03*
X1107874Y612649D03*
X1101181Y612599D03*
Y593757D03*
X1104141Y610300D03*
X1101181Y604499D03*
X1114340Y590900D03*
Y609999D03*
X1097352Y607220D03*
X1110520Y606700D03*
X1119453Y604536D03*
X1119466Y612350D03*
X1119440Y593714D03*
X1104177Y591314D03*
X1110520D03*
X1114316Y593500D03*
X1098300Y590900D03*
X1114366Y604750D03*
X1104141Y606549D03*
X1134645Y610700D03*
X1131299Y593757D03*
Y604499D03*
X1124606Y593757D03*
X1127952Y610700D03*
X1124606Y604499D03*
X1147700Y611200D03*
X1144685Y593757D03*
Y604499D03*
X1137992Y593757D03*
X1141332Y611668D03*
X1137992Y604499D03*
X1151178Y607350D03*
X1151152Y590900D03*
Y609999D03*
X1156252Y607140D03*
Y591114D03*
X1156265Y604536D03*
X1147331Y606700D03*
X1134645Y606549D03*
X1140952D03*
X1156278Y612350D03*
X1134645Y591414D03*
X1140988Y591314D03*
X1151128Y593500D03*
X1147331Y591414D03*
X1156252Y593714D03*
X1151178Y604750D03*
X1127952Y606549D03*
Y591414D03*
X1107874Y604499D03*
X1119440Y609749D03*
Y591114D03*
Y607140D03*
X1107874Y593757D03*
X1110520Y610300D03*
X1114366Y607350D03*
X1156252Y609749D03*
X1161417Y9114D03*
X1168110D03*
X1174803D03*
X1171456Y-3700D03*
X1168110Y-9901D03*
X1164763Y-3700D03*
X1161417Y-9901D03*
X1168110Y27899D03*
X1161417D03*
X1177763Y33700D03*
X1174803Y27899D03*
X1171456Y-7851D03*
X1164763D03*
X1177763D03*
X1168110Y-1751D03*
X1161417D03*
X1174803Y-1801D03*
X1168110Y17157D03*
X1171456Y12114D03*
X1161417Y17157D03*
X1164763Y12114D03*
X1171456Y14814D03*
X1164763Y29949D03*
X1171456D03*
X1164763Y14814D03*
X1177799Y14714D03*
X1177763Y29949D03*
X1181496Y-1751D03*
X1181346Y9114D03*
X1187963Y9098D03*
X1204921Y9114D03*
X1198228D03*
X1188011Y-9700D03*
X1193076Y-9864D03*
X1184142Y-7700D03*
X1193111Y-2000D03*
X1187963Y-1801D03*
X1201574Y-7851D03*
X1204921Y-1751D03*
X1198228D03*
X1218307D03*
X1211614Y-1801D03*
X1214574Y-7851D03*
X1208267D03*
X1218157Y9114D03*
X1211614D03*
X1204921Y27899D03*
X1198228D03*
X1218307D03*
X1214574Y33700D03*
X1211614Y27899D03*
X1187989Y30750D03*
X1193063Y33149D03*
X1187963Y33399D03*
X1193063Y30540D03*
X1193023Y9300D03*
X1184142Y30100D03*
Y14814D03*
X1188023Y28100D03*
X1187923Y16900D03*
X1193063Y17114D03*
X1193076Y27936D03*
X1201574Y14814D03*
Y29949D03*
X1208267Y14814D03*
Y29949D03*
X1214600Y14714D03*
X1214574Y29949D03*
X1184142Y33700D03*
X1181496Y27899D03*
X1184142Y12114D03*
X1204921Y17157D03*
X1198228D03*
X1201574Y12114D03*
X1187963Y14300D03*
X1193063Y14514D03*
X1187963Y11700D03*
X1193063Y11914D03*
X1184142Y-4100D03*
X1204921Y-9901D03*
X1201574Y-3700D03*
X1198228Y-9901D03*
X1187989Y-7050D03*
X1193063Y-7260D03*
X1187963Y-4401D03*
X1193063Y-4651D03*
X1208267Y-3700D03*
X1218307Y-9901D03*
X1214574Y-4100D03*
X1211614Y-9901D03*
X1208267Y12114D03*
X1218307Y17157D03*
X1211614D03*
X1214660Y12114D03*
X1174803Y-9901D03*
X1177763Y-4100D03*
X1181496Y-9901D03*
X1177849Y12114D03*
X1174803Y17157D03*
X1181496D03*
X1171456Y34100D03*
X1168110Y54957D03*
X1171456Y49914D03*
X1161417Y54957D03*
X1164763Y34100D03*
Y49914D03*
X1174803Y54957D03*
X1177849Y49914D03*
X1161417Y36049D03*
X1164763Y52614D03*
X1168110Y36049D03*
Y46914D03*
X1161417D03*
X1174803D03*
X1171456Y52614D03*
X1174803Y35999D03*
X1177763Y67749D03*
X1171456D03*
X1164763D03*
X1168110Y65699D03*
X1161417D03*
X1174803D03*
X1177799Y90314D03*
X1174803Y84714D03*
X1168110D03*
Y73849D03*
X1161417D03*
X1174803Y73799D03*
X1171456Y71900D03*
X1168110Y92757D03*
X1171456Y87714D03*
X1164763Y71900D03*
X1161417Y92757D03*
X1164763Y87714D03*
X1177763Y71500D03*
X1174803Y92757D03*
X1177849Y87714D03*
X1161417Y84714D03*
X1164763Y90414D03*
X1171456D03*
X1204921Y54957D03*
X1208267Y34100D03*
Y49914D03*
X1198228Y54957D03*
X1201574Y34100D03*
Y49914D03*
X1218307Y54957D03*
X1211614D03*
X1214660Y49914D03*
X1187963Y52100D03*
X1193063Y49714D03*
X1187963Y49500D03*
X1193063Y52314D03*
X1181346Y46914D03*
X1181496Y36049D03*
X1184142Y52614D03*
X1193012Y47000D03*
X1187963Y46898D03*
Y35999D03*
X1187912Y54700D03*
X1187989Y65950D03*
X1193076Y65736D03*
X1193063Y54914D03*
X1193023Y35800D03*
X1204921Y36049D03*
X1198228D03*
Y46914D03*
X1204921D03*
X1201574Y52614D03*
X1184142Y67900D03*
X1201574Y67749D03*
X1218307Y36049D03*
X1211614Y35999D03*
X1214960Y52864D03*
X1211614Y46914D03*
X1218157D03*
X1208267Y52614D03*
X1211614Y73799D03*
X1218307Y73849D03*
X1208267Y90414D03*
X1218157Y84714D03*
X1211614D03*
X1181496Y92757D03*
X1184142Y71500D03*
Y87714D03*
X1208267Y71900D03*
X1204921Y92757D03*
X1208267Y87714D03*
X1201574Y71900D03*
X1198228Y92757D03*
X1201574Y87714D03*
X1218307Y92757D03*
X1214574Y71500D03*
X1211614Y92757D03*
X1214874Y87374D03*
X1187963Y89900D03*
X1193063Y70949D03*
Y87514D03*
X1187963Y71199D03*
Y87300D03*
X1214574Y67749D03*
X1208267D03*
X1181496Y65699D03*
X1204921D03*
X1198228D03*
X1218307D03*
X1211614D03*
X1187989Y68550D03*
X1193063Y68340D03*
X1181496Y54957D03*
X1184142Y49914D03*
X1193063Y90114D03*
X1181346Y84714D03*
X1181496Y73849D03*
X1184142Y90414D03*
X1193039Y84700D03*
X1193063Y92714D03*
X1187939Y92500D03*
X1187963Y84698D03*
Y73799D03*
X1193089Y73550D03*
X1198228Y73849D03*
X1204921D03*
X1198228Y84714D03*
X1204921D03*
X1201574Y90414D03*
X1177799Y109914D03*
X1161632Y104314D03*
X1167925Y112357D03*
X1170721Y106964D03*
X1161632Y112357D03*
X1164428Y106964D03*
X1174742Y112357D03*
X1177849Y107314D03*
X1170721Y109564D03*
X1164428D03*
X1168075Y104314D03*
X1174742D03*
X1208267Y110014D03*
X1181496Y112357D03*
X1184142Y106964D03*
X1204921Y112357D03*
X1208267Y107314D03*
X1198228Y112357D03*
X1201574Y107314D03*
X1187963Y110514D03*
X1193063Y107655D03*
X1187989Y107865D03*
X1193089Y110264D03*
X1181346Y104314D03*
X1187963Y113114D03*
X1193089Y112865D03*
X1184142Y109564D03*
X1193076Y105051D03*
X1187989Y105265D03*
X1201574Y110014D03*
X1198228Y104314D03*
X1204921D03*
X1161200Y206446D03*
X1167960Y206447D03*
Y218147D03*
X1171339Y216196D03*
X1178099Y204496D03*
X1174719Y202547D03*
X1171339Y208397D03*
X1174719Y218147D03*
Y206447D03*
X1178099Y208397D03*
Y216196D03*
X1161200Y210346D03*
Y218147D03*
X1209033Y183907D03*
X1210000Y192500D03*
X1181479Y206447D03*
X1188239Y210346D03*
Y206447D03*
X1201759Y218147D03*
X1205759Y206682D03*
X1197492Y201356D03*
X1198379Y212296D03*
X1194999Y210346D03*
X1184859Y204496D03*
X1188239Y214247D03*
X1181479Y218147D03*
X1191619Y208397D03*
X1188239Y202247D03*
X1181479Y202547D03*
X1218868Y214869D03*
X1218000Y218100D03*
X1198379Y216196D03*
X1188239Y218147D03*
X1184859Y212296D03*
X1181479Y210346D03*
X1184859Y216196D03*
X1174719Y210346D03*
X1164580Y212296D03*
X1184859Y208397D03*
X1178099Y212296D03*
X1194999Y214247D03*
X1191619Y216196D03*
X1171339Y212296D03*
X1167960Y210346D03*
X1164580Y216196D03*
X1208519Y229847D03*
X1164580Y235696D03*
X1167960Y229847D03*
X1164580Y223996D03*
Y227896D03*
Y239596D03*
X1171339Y251296D03*
X1167960Y222047D03*
X1164580Y220096D03*
X1167960Y233746D03*
X1161200Y222047D03*
X1167960Y249347D03*
Y241547D03*
Y245447D03*
Y237647D03*
X1171339Y239596D03*
Y243496D03*
X1174719Y249347D03*
X1178099Y247396D03*
X1161200Y241547D03*
X1164580Y247396D03*
X1161200Y249347D03*
X1171339Y247396D03*
X1178099Y243496D03*
X1171339Y235696D03*
Y220096D03*
Y231797D03*
X1178099Y227896D03*
Y235696D03*
Y220096D03*
X1174719Y237647D03*
X1167960Y257147D03*
Y253247D03*
X1174719D03*
X1164580Y270796D03*
X1171339Y274696D03*
X1174719Y280547D03*
X1171339Y266896D03*
X1164580Y278596D03*
X1159578Y265117D03*
X1171339Y259096D03*
X1178099Y274696D03*
X1161200Y268847D03*
X1164580Y255196D03*
X1161200Y272747D03*
X1159410Y259720D03*
X1178099Y270796D03*
Y278596D03*
X1162300Y264947D03*
X1178099Y255196D03*
X1161200Y253247D03*
X1174719Y268847D03*
Y276646D03*
X1167960D03*
Y264947D03*
X1181479Y222047D03*
X1188239D03*
X1191619Y239596D03*
X1188239Y225947D03*
X1184859Y235696D03*
X1188239Y237647D03*
X1184859Y247396D03*
X1188239Y249347D03*
X1201759Y229847D03*
Y225947D03*
Y233746D03*
X1198379Y235696D03*
Y243496D03*
X1201759Y241547D03*
Y249347D03*
X1198379Y239596D03*
X1194999Y225947D03*
Y222047D03*
Y233746D03*
X1184859Y239596D03*
Y251296D03*
X1212199D03*
Y243496D03*
X1208519Y233746D03*
X1215700Y223600D03*
X1181479Y249347D03*
Y237647D03*
Y241547D03*
X1184859Y223996D03*
X1201759Y237647D03*
X1198379Y227896D03*
X1205139Y231797D03*
X1201759Y245447D03*
X1194999Y237647D03*
X1198379Y251296D03*
X1194999Y264947D03*
Y268847D03*
Y272747D03*
Y280547D03*
X1188239Y257147D03*
X1208519Y272747D03*
X1208819Y280547D03*
X1181479Y264947D03*
X1184859Y255196D03*
X1191619Y270796D03*
X1198379Y262996D03*
X1194999Y276646D03*
X1198379Y270796D03*
X1181479Y257147D03*
Y261047D03*
Y268847D03*
Y276646D03*
X1212199Y274696D03*
X1217200Y270500D03*
X1213808Y264800D03*
X1208519Y264947D03*
X1184859Y259096D03*
X1191619Y274696D03*
X1205139D03*
X1198379Y278596D03*
X1201759Y261047D03*
X1198379Y255196D03*
X1201759Y257147D03*
X1174719Y272747D03*
X1164580Y251296D03*
X1167960Y261047D03*
X1159390Y262460D03*
X1161200Y225947D03*
X1181479D03*
Y233746D03*
Y229847D03*
X1184859Y270796D03*
X1191619Y278596D03*
X1205139Y259096D03*
X1216234Y268055D03*
X1212199Y223996D03*
Y231797D03*
X1205139Y239596D03*
X1208519Y237647D03*
X1205139Y220096D03*
X1191619D03*
X1184859Y243496D03*
X1194999Y241547D03*
Y245447D03*
Y253247D03*
X1191619Y251296D03*
Y231797D03*
X1188239Y233746D03*
Y229847D03*
X1174719Y225947D03*
X1171339Y223996D03*
X1161200Y229847D03*
X1201759Y222047D03*
X1198379Y220096D03*
X1174719Y233746D03*
X1167960Y225947D03*
X1174719Y229847D03*
X1188239Y264947D03*
Y272747D03*
X1208519Y241547D03*
X1205139Y251296D03*
X1208519Y257147D03*
X1201759Y264947D03*
X1191619Y255196D03*
X1198379Y259096D03*
X1191619Y262996D03*
X1188239Y261047D03*
X1191619Y266896D03*
X1184859Y274696D03*
X1205139Y266896D03*
X1208519Y268847D03*
X1201759D03*
Y276646D03*
X1184859Y231797D03*
X1208519Y225947D03*
X1191619Y227896D03*
X1174719Y257147D03*
X1178099Y259096D03*
X1161200Y245447D03*
X1174719Y261047D03*
X1167960Y272747D03*
X1171339Y255196D03*
X1181479Y272747D03*
X1201759D03*
Y280547D03*
X1208519Y249347D03*
X1194999Y257147D03*
X1198379Y247396D03*
X1184859Y278596D03*
X1188239Y276646D03*
Y280547D03*
X1198379Y231797D03*
X1205139Y227896D03*
X1191619Y259096D03*
X1194999Y249347D03*
X1184859Y262996D03*
X1161200Y233746D03*
X1191619Y243496D03*
X1188239Y241547D03*
X1214732Y243496D03*
X1212199Y239596D03*
X1217476Y243482D03*
X1216234Y265555D03*
X1174719Y300047D03*
Y284447D03*
X1164580Y294196D03*
Y290296D03*
Y286396D03*
X1161200Y284447D03*
X1178099Y294196D03*
Y298096D03*
Y286396D03*
X1164580Y301996D03*
X1171339D03*
X1161200Y307847D03*
X1174719Y292247D03*
Y288347D03*
X1171339Y286396D03*
Y290296D03*
X1167960Y300047D03*
X1164580Y298096D03*
X1167960Y296147D03*
Y292247D03*
Y288347D03*
X1161200Y296147D03*
X1178099Y290296D03*
X1161200Y311747D03*
Y300047D03*
Y303947D03*
X1174719D03*
X1167960D03*
X1178099Y309797D03*
X1171339Y305896D03*
X1164580Y309797D03*
Y305896D03*
X1167960Y307847D03*
Y311747D03*
X1171339Y309797D03*
X1178099Y301996D03*
X1174719Y311747D03*
Y307847D03*
X1178099Y305896D03*
X1171339Y298096D03*
Y294196D03*
X1174719Y296147D03*
X1161200Y335147D03*
Y339047D03*
X1164580Y329296D03*
Y333196D03*
Y337096D03*
X1167960Y339047D03*
Y327347D03*
X1161200Y331247D03*
Y327347D03*
X1178099Y337096D03*
Y317596D03*
X1164580Y321496D03*
Y317596D03*
X1161200Y323446D03*
Y319547D03*
Y315647D03*
X1167960Y323446D03*
Y315647D03*
Y319547D03*
X1174719Y315647D03*
X1171339Y317596D03*
X1164580Y325396D03*
X1171339D03*
X1174719Y335147D03*
Y339047D03*
X1164580Y340996D03*
X1167960Y331247D03*
X1171339Y321496D03*
X1178099Y313696D03*
X1171339D03*
X1164580D03*
X1205500Y309797D03*
X1198379D03*
X1194999Y288347D03*
Y292247D03*
Y296147D03*
Y300047D03*
Y307847D03*
Y303947D03*
X1191619Y298096D03*
X1198379Y282496D03*
X1181479Y300047D03*
Y288347D03*
Y292247D03*
Y311747D03*
Y307847D03*
Y303947D03*
X1188239Y288347D03*
Y284447D03*
Y292247D03*
X1184859Y294196D03*
Y290296D03*
X1191619Y294196D03*
X1184859Y309797D03*
X1188239Y311747D03*
X1184859Y301996D03*
X1201759Y284447D03*
Y288347D03*
X1205439Y298096D03*
X1198379Y286396D03*
X1205439Y305896D03*
X1194999Y335147D03*
Y331247D03*
X1212200Y333196D03*
X1208519Y339047D03*
X1208826Y319544D03*
X1184859Y325396D03*
Y333196D03*
X1198379Y337096D03*
Y329296D03*
X1181479Y327347D03*
Y319547D03*
Y335147D03*
X1198379Y313696D03*
X1188239Y319547D03*
X1184859Y321496D03*
X1188239Y339047D03*
Y335147D03*
X1184859Y329296D03*
X1191619Y321496D03*
X1198379Y325396D03*
Y340996D03*
X1201759Y323446D03*
X1205139Y333196D03*
X1194999Y319547D03*
Y315647D03*
X1181479Y339047D03*
X1178099Y340996D03*
X1205139D03*
X1201759Y339047D03*
X1198379Y333196D03*
X1201759Y335147D03*
Y331247D03*
X1184859Y337096D03*
X1191619Y309797D03*
X1188239Y303947D03*
X1194999Y327347D03*
X1184859Y317596D03*
X1191619D03*
Y305896D03*
Y301996D03*
X1184859Y340996D03*
X1194999Y339047D03*
X1191619Y333196D03*
Y329296D03*
X1188239Y323446D03*
X1184859Y313696D03*
X1188239Y315647D03*
X1198379Y290296D03*
Y294196D03*
X1205439Y286596D03*
X1181479Y284447D03*
X1205439Y294196D03*
X1191619Y282496D03*
Y290296D03*
X1205439D03*
X1191619Y286396D03*
X1178099Y282496D03*
X1205139D03*
X1184859D03*
X1194999Y284447D03*
X1184859Y286396D03*
X1167960Y370247D03*
X1164580Y372197D03*
X1171339Y356596D03*
Y360496D03*
X1164580Y356596D03*
X1167960Y342947D03*
X1171339Y348796D03*
X1174719Y354647D03*
Y342947D03*
X1161200Y370247D03*
X1171339Y372197D03*
X1167960Y362447D03*
X1178099Y364396D03*
X1174719Y346847D03*
X1178099Y348796D03*
Y344896D03*
X1167960Y358547D03*
X1171339Y344896D03*
X1174719Y350747D03*
X1167960Y366347D03*
X1171339Y368296D03*
Y399496D03*
X1164580Y403396D03*
X1178099D03*
X1167960Y389747D03*
X1161200Y397546D03*
X1167960Y397547D03*
X1161200Y374146D03*
X1178099Y391696D03*
X1174719Y397546D03*
X1164580Y399496D03*
X1174719Y393647D03*
X1161200Y378047D03*
X1164580Y379996D03*
X1174719Y381947D03*
X1194999Y346847D03*
Y354647D03*
X1209219Y370247D03*
X1212199Y356597D03*
Y344896D03*
Y352696D03*
X1188239Y370247D03*
X1191619Y372197D03*
Y364396D03*
Y352696D03*
X1194999Y342947D03*
X1181479Y346847D03*
X1188239Y366347D03*
X1194999D03*
X1191619Y348796D03*
X1184859Y356596D03*
X1191619Y360496D03*
X1201759Y350747D03*
X1205139Y360496D03*
X1181479Y374146D03*
Y389747D03*
X1209769Y374146D03*
X1184859Y383896D03*
X1188239Y393647D03*
X1201759Y389747D03*
X1197258Y397546D03*
X1194999Y385847D03*
X1188239Y378047D03*
X1201759D03*
X1208819Y393647D03*
Y381897D03*
X1181479Y385847D03*
X1188239Y381947D03*
X1208819Y385847D03*
X1181479Y393647D03*
X1184859Y399496D03*
X1178099Y395596D03*
X1174719Y401447D03*
X1198379Y356596D03*
Y360496D03*
X1181479Y370247D03*
X1174719D03*
X1178099Y360496D03*
X1191619Y383896D03*
X1167960Y381947D03*
X1181479Y342947D03*
X1201759Y346847D03*
X1198379Y344896D03*
X1201759Y342947D03*
X1184859Y387796D03*
X1188239Y385847D03*
Y389747D03*
X1194999Y370247D03*
X1184859Y391696D03*
Y395596D03*
X1181479Y397546D03*
X1178099Y399496D03*
X1171339Y403396D03*
X1198379Y352696D03*
X1201759Y358547D03*
X1194999Y362447D03*
X1198379Y372197D03*
Y364396D03*
X1167960Y401447D03*
X1194999Y374146D03*
X1171339Y364396D03*
X1201759Y374146D03*
X1194999Y378047D03*
X1178099Y372197D03*
X1171339Y376096D03*
X1167960Y374146D03*
X1171339Y379996D03*
X1164580Y383896D03*
X1161200Y381947D03*
X1181479Y350747D03*
Y354647D03*
X1174719Y358547D03*
Y362447D03*
Y366347D03*
X1178099Y356596D03*
X1184859Y348796D03*
X1174719Y374146D03*
Y378047D03*
X1167960D03*
X1188239Y346847D03*
Y342947D03*
X1181479Y381947D03*
X1167960Y385847D03*
X1161200D03*
X1164580Y387796D03*
X1174719Y385847D03*
X1178099Y383896D03*
Y379996D03*
X1161200Y393647D03*
X1184859Y352696D03*
X1198379Y379996D03*
X1194999Y381947D03*
X1167960Y393647D03*
X1184859Y344896D03*
X1171339Y387796D03*
X1198029Y405411D03*
X1195555Y405773D03*
X1192200Y409550D03*
X1185989Y407800D03*
X1181479Y405347D03*
X1174719D03*
X1167960D03*
X1161417Y518157D03*
X1174803D03*
X1177849Y513114D03*
X1180400Y495787D03*
X1167500Y495800D03*
X1174203Y495787D03*
X1161320Y495800D03*
X1170656Y491144D03*
X1164363Y491044D03*
X1177849Y490944D03*
X1170656Y493844D03*
X1164363Y493744D03*
X1177799Y493544D03*
X1168110Y510114D03*
X1164763Y515814D03*
X1161417Y510114D03*
X1177799Y515714D03*
X1171456Y515814D03*
X1174803Y510114D03*
X1168110Y518157D03*
X1171456Y513114D03*
X1208267Y493444D03*
X1200974Y490744D03*
X1193063Y490909D03*
X1187978Y490609D03*
X1184142Y490794D03*
Y493394D03*
X1200974Y493344D03*
X1193063Y493509D03*
X1208267Y496144D03*
X1187978Y495909D03*
X1193063Y496209D03*
X1181346Y510114D03*
X1204400Y495887D03*
X1198100Y495800D03*
X1208267Y515814D03*
X1211614Y510114D03*
X1218157D03*
X1187963Y510098D03*
X1204921Y510114D03*
X1198228D03*
X1201574Y515814D03*
X1184142D03*
X1187939Y517900D03*
X1193039Y510100D03*
X1193063Y518114D03*
X1187978Y498609D03*
X1193063Y498909D03*
X1181496Y518157D03*
X1184142Y513114D03*
X1204921Y518157D03*
X1208267Y513114D03*
X1198228Y518157D03*
X1201574Y513114D03*
X1211614Y518157D03*
X1214874Y512774D03*
X1187963Y515300D03*
X1193063Y512914D03*
X1187963Y512700D03*
X1193063Y515514D03*
X1204400Y498487D03*
X1198100Y498400D03*
X1187978Y493209D03*
X1180400Y498387D03*
X1174203D03*
X1161417Y498487D03*
X1167510D03*
X1218307Y518157D03*
X1164763Y513114D03*
Y535100D03*
X1177763Y534700D03*
X1174803Y528899D03*
X1171456Y550914D03*
X1164763D03*
X1177849D03*
X1161417Y547914D03*
X1168110D03*
X1174803D03*
X1177799Y553514D03*
X1177763Y530949D03*
X1168110Y537049D03*
X1164763Y530949D03*
X1161417Y537049D03*
X1171456Y530949D03*
X1174803Y536999D03*
X1164763Y553614D03*
X1171456D03*
Y535100D03*
X1168110Y528899D03*
X1161417Y566699D03*
X1174803D03*
X1171456Y588714D03*
X1164763D03*
X1177849D03*
X1174803Y574799D03*
X1161417Y574849D03*
X1171456Y568749D03*
X1168110Y585714D03*
X1161417D03*
X1168110Y574849D03*
X1164763Y568749D03*
X1174803Y585714D03*
X1177763Y568749D03*
X1184142Y550914D03*
X1208267D03*
X1201574D03*
X1214874Y550574D03*
X1187963Y553100D03*
X1193063Y550714D03*
Y553314D03*
X1181496Y537049D03*
X1181346Y547914D03*
X1211614Y536999D03*
X1214574Y530949D03*
X1184142Y531100D03*
X1193076Y528936D03*
X1198228Y547914D03*
X1204921D03*
X1201574Y553614D03*
Y530949D03*
X1204921Y537049D03*
X1198228D03*
X1193039Y547900D03*
X1187963Y547898D03*
X1184142Y553614D03*
X1193089Y536750D03*
X1187989Y529150D03*
X1187963Y536999D03*
X1218307Y537049D03*
X1211614Y547914D03*
X1208267Y553614D03*
Y530949D03*
X1218157Y547914D03*
X1184142Y534700D03*
X1181496Y528899D03*
X1208267Y535100D03*
X1204921Y528899D03*
X1201574Y535100D03*
X1198228Y528899D03*
X1218307D03*
X1214574Y534700D03*
X1211614Y528899D03*
X1187989Y531750D03*
X1193063Y534149D03*
X1187963Y534399D03*
X1193063Y531540D03*
X1201574Y588714D03*
X1214660D03*
X1193063Y588514D03*
X1187963Y588300D03*
X1181346Y585714D03*
X1181496Y574849D03*
X1193063Y555914D03*
X1187939Y555700D03*
X1218157Y585714D03*
X1218307Y574849D03*
X1208267Y568749D03*
X1214574D03*
X1211614Y574799D03*
Y585714D03*
X1184142Y568900D03*
X1187989Y566950D03*
X1193076Y566736D03*
X1193039Y585700D03*
X1187963Y585698D03*
X1193089Y574550D03*
X1187963Y574799D03*
X1198228Y585714D03*
Y574849D03*
X1204921Y585714D03*
Y574849D03*
X1201574Y568749D03*
X1181496Y566699D03*
X1204921D03*
X1198228D03*
X1218307Y555957D03*
Y566699D03*
X1211614Y555957D03*
X1214574Y572500D03*
X1211614Y566699D03*
X1187989Y569550D03*
X1193063Y571949D03*
Y569340D03*
X1184142Y588714D03*
X1208267D03*
X1204921Y555957D03*
X1198228D03*
X1187963Y550500D03*
X1184142Y572500D03*
X1201574Y572900D03*
X1187963Y572199D03*
X1208267Y572900D03*
X1181496Y555957D03*
X1174803D03*
X1161417D03*
X1171456Y572900D03*
X1168110Y555957D03*
Y566699D03*
X1177763Y572500D03*
X1164763Y572900D03*
X1161417Y528899D03*
X1181496Y612649D03*
X1218307D03*
X1211614Y612599D03*
X1187963D03*
X1204921Y612649D03*
X1198228D03*
X1168110D03*
X1161417D03*
X1174803Y612599D03*
X1168110Y593757D03*
X1171456Y610700D03*
X1168110Y604499D03*
X1161417Y593757D03*
Y604499D03*
X1174803Y593757D03*
X1177763Y610300D03*
X1174803Y604499D03*
X1171456Y606549D03*
X1164763D03*
Y591414D03*
X1171456D03*
X1177799Y591314D03*
X1177763Y606549D03*
X1204921Y604499D03*
X1198228Y593757D03*
X1201574Y610700D03*
X1198228Y604499D03*
X1218307Y593757D03*
Y604499D03*
X1211614Y593757D03*
X1214574Y610300D03*
X1211614Y604499D03*
X1187963Y590900D03*
X1187989Y607350D03*
X1193063Y609749D03*
X1187963Y609999D03*
X1193063Y591114D03*
Y607140D03*
X1208267Y591414D03*
X1214574Y606549D03*
X1208267D03*
X1187939Y593500D03*
X1184142Y591414D03*
X1193063Y593714D03*
X1187989Y604750D03*
X1193076Y604536D03*
X1193089Y612350D03*
X1184142Y606700D03*
X1201574Y591414D03*
Y606549D03*
X1181496Y593757D03*
X1184142Y610300D03*
X1181496Y604499D03*
X1208267Y610700D03*
X1204921Y593757D03*
X1164763Y610700D03*
X1238385Y29949D03*
Y14814D03*
X1245078Y29949D03*
Y14814D03*
X1251771Y16999D03*
X1248425Y27899D03*
X1269700Y13078D03*
X1267960Y28494D03*
X1241732Y27899D03*
X1251771D03*
X1248425Y17057D03*
X1258464Y27899D03*
X1261811D03*
Y16999D03*
X1258464D03*
X1265157Y27899D03*
Y16999D03*
X1241732Y-1751D03*
X1238385Y-7851D03*
X1241732Y9114D03*
X1248425Y-1751D03*
Y-9901D03*
X1251771D03*
X1245078Y-7851D03*
X1248425Y9157D03*
X1269800Y-5822D03*
X1265157Y9157D03*
X1261000Y9100D03*
X1258464Y9157D03*
X1251771D03*
Y-1743D03*
X1261811Y-9901D03*
X1258464D03*
X1261811Y-1743D03*
X1265157D03*
X1258464D03*
X1265157Y-9901D03*
X1276346Y-10250D03*
X1278900Y-14800D03*
X1235039Y9114D03*
X1224774Y9098D03*
X1224822Y-9700D03*
X1229887Y-9864D03*
X1224774Y-1801D03*
X1235039Y-1751D03*
X1229922Y-2000D03*
X1220953Y-7700D03*
Y33700D03*
X1235039Y27899D03*
X1224800Y30750D03*
X1229874Y30540D03*
X1224774Y33399D03*
X1229874Y33149D03*
X1229800Y9300D03*
X1224790Y16900D03*
X1229874Y17114D03*
X1229887Y27936D03*
X1220953Y30100D03*
X1224800Y28100D03*
X1220953Y14814D03*
Y-4100D03*
X1245078Y-3700D03*
X1241732Y-9901D03*
X1238385Y-3700D03*
X1235039Y-9901D03*
X1224800Y-7050D03*
X1229874Y-7260D03*
X1224774Y-4401D03*
X1229874Y-4651D03*
X1255118Y-9901D03*
Y-1743D03*
X1220953Y12114D03*
X1241732Y17157D03*
X1245078Y12114D03*
X1235039Y17157D03*
X1238385Y12114D03*
X1224774Y14300D03*
X1229874Y14514D03*
X1224774Y11700D03*
X1229874Y11914D03*
X1255118Y27899D03*
Y16999D03*
Y9157D03*
X1241732Y36049D03*
Y46914D03*
X1238385Y52614D03*
Y67749D03*
X1245078Y52614D03*
X1251771Y65699D03*
X1248425D03*
Y36049D03*
Y46957D03*
X1245078Y67749D03*
X1267976Y73676D03*
X1268022Y54443D03*
X1241732Y65699D03*
Y54957D03*
X1245078Y34100D03*
Y49914D03*
X1238385Y34100D03*
Y49914D03*
X1251771Y36057D03*
Y54799D03*
X1248425Y54857D03*
X1251771Y46957D03*
X1258464D03*
Y36057D03*
Y54799D03*
X1261811Y46957D03*
Y54799D03*
X1265157Y36057D03*
X1261811D03*
X1265157Y46957D03*
X1261811Y65699D03*
X1258464D03*
X1265157D03*
X1267959Y47245D03*
X1268111Y58040D03*
X1241732Y92757D03*
X1245078Y71900D03*
Y87714D03*
X1238385Y71900D03*
Y87714D03*
X1251771Y84757D03*
X1248425Y92657D03*
X1265157Y73857D03*
X1261811D03*
X1258464D03*
X1261811Y84757D03*
X1258464D03*
X1265157D03*
X1251771Y73857D03*
X1261811Y92599D03*
X1258464D03*
X1241732Y84714D03*
Y73849D03*
X1238385Y90414D03*
X1251771Y92599D03*
X1245078Y90414D03*
X1248425Y84757D03*
Y73849D03*
X1268581Y92706D03*
X1220953Y49914D03*
X1235039Y54957D03*
X1224774Y52100D03*
X1229874Y52314D03*
X1224774Y49500D03*
X1229874Y49714D03*
X1224774Y84698D03*
X1224750Y92500D03*
X1224774Y73799D03*
X1235039Y84714D03*
Y73849D03*
X1220953Y71500D03*
Y87714D03*
X1235039Y92757D03*
X1224774Y89900D03*
X1229874Y70949D03*
Y87514D03*
X1224774Y71199D03*
Y87300D03*
X1229800Y35750D03*
X1229874Y54914D03*
X1235039Y46914D03*
Y36049D03*
X1224774Y46898D03*
X1220953Y52614D03*
X1224774Y35999D03*
X1229887Y65736D03*
X1224800Y65950D03*
X1220953Y67900D03*
X1235039Y65699D03*
X1224800Y68550D03*
X1229874Y68340D03*
Y90114D03*
X1229900Y73550D03*
X1229850Y84700D03*
X1229874Y92714D03*
X1220953Y90414D03*
X1255118Y65699D03*
Y54799D03*
Y36057D03*
Y46957D03*
X1265157Y54799D03*
X1255118Y92599D03*
Y84757D03*
Y73857D03*
X1265157Y92599D03*
X1240927Y154932D03*
X1243948Y154916D03*
X1251344Y127925D03*
X1277100Y122670D03*
X1264550Y114670D03*
X1277100Y114800D03*
X1261030Y105350D03*
X1268900Y122500D03*
X1270350Y98300D03*
X1277600Y106200D03*
X1268576Y117788D03*
X1275470Y99390D03*
X1266200Y122500D03*
X1254024Y128013D03*
X1246251Y130066D03*
X1257800Y110900D03*
X1260500Y117500D03*
X1247326Y122802D03*
X1254300Y105200D03*
X1277660Y109450D03*
X1277230Y117570D03*
X1278030Y148510D03*
X1237704Y148423D03*
X1269810Y154398D03*
X1249025Y130460D03*
X1263798Y133493D03*
X1278000Y145780D03*
X1268236Y141938D03*
X1272100Y141603D03*
X1265828Y140568D03*
X1237400Y103100D03*
X1268600Y104700D03*
X1266646Y150540D03*
X1257850Y116950D03*
Y113850D03*
X1255400Y108000D03*
X1259950Y144650D03*
X1264700Y154800D03*
X1240022Y141773D03*
X1261546Y150584D03*
X1264146D03*
X1268500Y102100D03*
X1271500D03*
X1240000Y129500D03*
X1271500Y122500D03*
X1271490Y104700D03*
X1248616Y133817D03*
X1261800Y154973D03*
X1262569Y147201D03*
X1252000Y145300D03*
X1252437Y140192D03*
X1260737Y133877D03*
X1251980Y106960D03*
X1250200Y122900D03*
X1240010Y144754D03*
X1257800Y120800D03*
X1221767Y175858D03*
X1233902Y173337D03*
X1240309Y161900D03*
X1267050Y169800D03*
X1241381Y172040D03*
X1246655Y176395D03*
X1244410Y173150D03*
X1246910D03*
X1242800Y175200D03*
X1263080Y191320D03*
X1260140Y191670D03*
X1263300Y169450D03*
X1241712Y187710D03*
X1259200Y168350D03*
X1252800Y176000D03*
X1255200D03*
X1267800Y161800D03*
X1271400Y161900D03*
X1260510Y206840D03*
X1267220Y203600D03*
X1267218Y207495D03*
X1258810Y204840D03*
X1263728Y211444D03*
X1262250Y201227D03*
X1265718Y201459D03*
X1258482Y201495D03*
X1257770Y199150D03*
X1260260Y199862D03*
X1264180Y199510D03*
X1240500Y218200D03*
X1240452Y208240D03*
Y215740D03*
Y213240D03*
Y210740D03*
X1243196Y207002D03*
X1242800Y204150D03*
X1244380Y202160D03*
X1255310Y193850D03*
X1252930Y193270D03*
X1263040Y193930D03*
X1259360Y193950D03*
X1257210Y192340D03*
X1268986Y205727D03*
X1269254Y197923D03*
X1270930Y200220D03*
X1268930Y201820D03*
X1272522Y202191D03*
X1270754Y203959D03*
X1267486Y199691D03*
X1262018Y197959D03*
X1265786Y197691D03*
X1259518Y197459D03*
X1263950Y203227D03*
X1260620Y203130D03*
X1255982Y200995D03*
X1255833Y197423D03*
X1256810Y203340D03*
X1262182Y204995D03*
X1265420Y205400D03*
X1250235Y199342D03*
X1251940Y197530D03*
X1247803Y198486D03*
X1254065Y199191D03*
X1252330Y201030D03*
X1254310Y202840D03*
X1250625Y202804D03*
X1248290Y201720D03*
X1246620Y203570D03*
X1246090Y200330D03*
X1245014Y205405D03*
X1251089Y194810D03*
X1249571Y196718D03*
X1253521Y195666D03*
X1267554Y195923D03*
X1261220Y195650D03*
X1263804Y196318D03*
X1265570Y194510D03*
X1257601Y195655D03*
X1262080Y209140D03*
X1265450Y209263D03*
X1263680Y207160D03*
X1229780Y181980D03*
Y178980D03*
X1232780Y181980D03*
X1226914Y184708D03*
X1232780Y178980D03*
X1226780D03*
Y181980D03*
X1226785Y210403D03*
X1221300Y205400D03*
X1226500Y199800D03*
X1226867Y207904D03*
X1220167Y194407D03*
X1227200Y215543D03*
X1220702Y216708D03*
X1226785Y213003D03*
X1221300Y208000D03*
X1226500Y202400D03*
X1220580Y179810D03*
X1243300Y223100D03*
X1268404Y246304D03*
X1277504Y250346D03*
X1275154Y236296D03*
X1279950Y229338D03*
X1276628Y234270D03*
X1272761Y240220D03*
X1278183Y231886D03*
X1274100Y255300D03*
X1275577Y253123D03*
X1251395Y226373D03*
X1253791Y226228D03*
X1248672Y226494D03*
X1252221Y228668D03*
X1245300Y224800D03*
X1220017Y220323D03*
X1220194Y243384D03*
X1223100Y258600D03*
X1223508Y262600D03*
X1270478Y243490D03*
X1279393Y247602D03*
X1225908Y259300D03*
Y261800D03*
X1243399Y398339D03*
X1249230Y402022D03*
X1246010Y400110D03*
X1262700Y461804D03*
X1259800Y463300D03*
X1255530Y474770D03*
X1277978Y491571D03*
X1258140Y474540D03*
X1271571Y479000D03*
X1271662Y487326D03*
X1271640Y474420D03*
X1271647Y482500D03*
X1269050Y486650D03*
X1269600Y480800D03*
X1272830Y471660D03*
X1257720Y493060D03*
X1255388Y483557D03*
X1256130Y467820D03*
X1265157Y510157D03*
X1261811Y517999D03*
X1258464Y510157D03*
Y517999D03*
X1261811Y510157D03*
X1248425Y518057D03*
X1251771Y510157D03*
X1262843Y497553D03*
X1277800Y497108D03*
X1280595Y496439D03*
X1266162Y496404D03*
X1269006Y496016D03*
X1241732Y510114D03*
X1238385Y515814D03*
X1269000Y514700D03*
X1245078Y515814D03*
X1251771Y517999D03*
X1248425Y510157D03*
X1241732Y518157D03*
X1245078Y513114D03*
X1238385D03*
X1278573Y519596D03*
X1235039Y510114D03*
X1220953Y515814D03*
X1229874Y518114D03*
X1229850Y510100D03*
X1224750Y517900D03*
X1224774Y510098D03*
X1220953Y513114D03*
X1235039Y518157D03*
X1224774Y515300D03*
X1229874Y512914D03*
X1224774Y512700D03*
X1229874Y515514D03*
X1274576Y510235D03*
X1267584Y499694D03*
X1271105Y498516D03*
X1271300Y510600D03*
X1269209Y501777D03*
X1255120Y510158D03*
Y518000D03*
X1248474Y488913D03*
X1249193Y491308D03*
X1265157Y517999D03*
X1262900Y466504D03*
X1256320Y490660D03*
X1258126Y469540D03*
X1256350Y486080D03*
X1255120Y574834D03*
X1265157Y547957D03*
X1261811D03*
X1258464D03*
X1251771D03*
X1265157Y537057D03*
X1261811D03*
X1258464Y528899D03*
X1251771Y537057D03*
X1258464D03*
X1261811Y528899D03*
X1265157Y528876D03*
X1277200Y539100D03*
X1277137Y547393D03*
X1279318Y545212D03*
X1241732Y547914D03*
Y537049D03*
X1238385Y530949D03*
Y553614D03*
X1269800Y532978D03*
X1251771Y528899D03*
X1248425Y537049D03*
Y528899D03*
X1245078Y553614D03*
Y530949D03*
X1248425Y547957D03*
X1245078Y535100D03*
X1241732Y528899D03*
X1238385Y535100D03*
X1245078Y550914D03*
X1238385D03*
X1241732Y574849D03*
Y585714D03*
X1238385Y568749D03*
X1268500Y555800D03*
X1267900Y574300D03*
X1248425Y585757D03*
Y574849D03*
Y566699D03*
X1245078Y568749D03*
X1241732Y555957D03*
X1245078Y572900D03*
X1241732Y566699D03*
X1238385Y572900D03*
X1245078Y588714D03*
X1238385D03*
X1265157Y585757D03*
X1261811D03*
X1258464D03*
X1251771D03*
X1261811Y555799D03*
X1258464D03*
X1251771D03*
X1248425Y555857D03*
X1251771Y566699D03*
Y574857D03*
X1265157D03*
X1261811D03*
X1258464D03*
X1261811Y566699D03*
X1258464D03*
X1273200Y582200D03*
X1265157Y566676D03*
Y555799D03*
X1220953Y550914D03*
X1229874Y550714D03*
X1224774Y550500D03*
X1229874Y553314D03*
X1220953Y531100D03*
X1229887Y528936D03*
X1229900Y536750D03*
X1224800Y529150D03*
X1224774Y536999D03*
X1235039Y537049D03*
Y547914D03*
X1229850Y547900D03*
X1224774Y547898D03*
X1220953Y553614D03*
X1235039Y528899D03*
X1224800Y531750D03*
X1229874Y534149D03*
X1224774Y534399D03*
X1229874Y531540D03*
X1220953Y588714D03*
X1229874Y588514D03*
X1224774Y588300D03*
X1229874Y555914D03*
X1224750Y555700D03*
X1220953Y568900D03*
X1229900Y574550D03*
X1224774Y574799D03*
X1229850Y585700D03*
X1224774Y585698D03*
X1229887Y566736D03*
X1224800Y566950D03*
X1235039Y585714D03*
Y574849D03*
X1220953Y572500D03*
X1235039Y555957D03*
Y566699D03*
X1229874Y571949D03*
X1224774Y572199D03*
X1229874Y569340D03*
X1255120Y537034D03*
Y555144D03*
X1224774Y553100D03*
X1224800Y569550D03*
X1220953Y534700D03*
X1265157Y604476D03*
Y593599D03*
X1241732Y612649D03*
X1238385Y606549D03*
Y591414D03*
X1263800Y606800D03*
X1267800Y593600D03*
X1248425Y612649D03*
X1251771Y604499D03*
X1248425D03*
X1245078Y606549D03*
X1251771Y593599D03*
X1245078Y591414D03*
X1270400Y593600D03*
X1241732Y593757D03*
X1245078Y610700D03*
X1241732Y604499D03*
X1238385Y610700D03*
X1258464Y593599D03*
X1261811D03*
X1248425Y593657D03*
X1251771Y612657D03*
X1258464Y604499D03*
X1261811D03*
X1265157Y612657D03*
X1261811D03*
X1258464D03*
X1224774Y612599D03*
X1235039Y612649D03*
X1220953Y610300D03*
X1235039Y593757D03*
Y604499D03*
X1224774Y590900D03*
X1224800Y607350D03*
X1229874Y609749D03*
X1224774Y609999D03*
X1229874Y591114D03*
Y607140D03*
X1220953Y591414D03*
X1229874Y593714D03*
X1224750Y593500D03*
X1224800Y604750D03*
X1229887Y604536D03*
X1220953Y606700D03*
X1229900Y612350D03*
X1255120Y612634D03*
Y593600D03*
X1301279Y10058D03*
X1304079D03*
X1306879D03*
X1301200Y12610D03*
X1306800D03*
X1303774Y-18842D03*
X1299549Y-18619D03*
X1287700Y-16700D03*
X1292692Y1008D03*
X1299369Y-15680D03*
X1293600Y-17000D03*
X1293816Y-13533D03*
X1282252Y-14747D03*
X1284859Y-14524D03*
X1301200Y15200D03*
X1301100Y2700D03*
X1316300Y-14800D03*
X1320800Y-16900D03*
X1307900Y-14700D03*
X1309500Y-16800D03*
X1323600Y-16900D03*
X1322000Y-14800D03*
X1324800D03*
X1326000Y-12700D03*
X1323600Y-12600D03*
X1327600Y-14800D03*
Y4700D03*
X1326400Y2600D03*
X1324800Y4700D03*
X1322000D03*
X1323600Y2600D03*
X1306700Y2700D03*
X1309500D03*
X1307900Y4800D03*
X1320800Y2600D03*
X1316300Y4700D03*
X1317900Y2600D03*
X1319200Y4700D03*
X1313500Y4800D03*
X1315004Y2567D03*
X1326400Y-16900D03*
X1302300Y4800D03*
X1303900Y2700D03*
X1310700Y4800D03*
X1312300Y2700D03*
X1305100Y4800D03*
X1322532Y9822D03*
X1325332D03*
X1306700Y-16800D03*
X1328800Y-12700D03*
X1312300Y-16800D03*
X1310700Y-14700D03*
X1315004Y-16933D03*
X1313500Y-14700D03*
X1319200Y-14800D03*
X1317900Y-16900D03*
X1321452Y31803D03*
X1304000Y15200D03*
X1328085Y9865D03*
X1322483Y12834D03*
X1328045Y15831D03*
X1325308Y15734D03*
X1322508D03*
X1328123Y12730D03*
X1306800Y15200D03*
X1328987Y2525D03*
X1313942Y30714D03*
X1309760Y30691D03*
X1316300Y31911D03*
X1318700Y31943D03*
X1311809Y32096D03*
X1325383Y12634D03*
X1304940Y32350D03*
X1304000Y12610D03*
X1336500Y81100D03*
X1320000Y85500D03*
X1327168Y61483D03*
X1296935Y51335D03*
X1296908Y36900D03*
X1296928Y48700D03*
X1295581Y94320D03*
X1298422Y74000D03*
X1298754Y83233D03*
X1301219Y89141D03*
X1301000Y62000D03*
X1323500Y68000D03*
X1318341Y60000D03*
X1321841Y63000D03*
X1304000Y62000D03*
X1308983Y93814D03*
X1304500Y40066D03*
X1324127Y50827D03*
X1327452Y55544D03*
X1327500Y51547D03*
X1310600Y41500D03*
X1308100D03*
X1323400Y41439D03*
X1326000D03*
X1326058Y43956D03*
X1323400Y43839D03*
X1318341Y63000D03*
X1341400Y46100D03*
X1309700Y83300D03*
X1317195Y87098D03*
X1311559Y91431D03*
X1311551Y93952D03*
X1304685Y78827D03*
X1336850Y76450D03*
X1317300Y89600D03*
X1330300Y83500D03*
X1336900Y89896D03*
X1323500Y75000D03*
Y71500D03*
X1308400Y79600D03*
X1317300Y84600D03*
X1327500Y68000D03*
X1327467Y70786D03*
X1327500Y65300D03*
X1323000Y83000D03*
X1335120Y94450D03*
X1337400Y72000D03*
X1328500Y92500D03*
X1336900Y61600D03*
X1327900Y142918D03*
X1310175Y154696D03*
X1286116Y118932D03*
Y115932D03*
X1295581Y97320D03*
X1293700Y121800D03*
X1288381Y97320D03*
X1291381D03*
X1295240Y149830D03*
X1295172Y153670D03*
X1291735Y150061D03*
X1291772Y153694D03*
X1293335Y148177D03*
X1293543Y151756D03*
X1287790Y156575D03*
X1295700Y144450D03*
X1286000Y134500D03*
Y139500D03*
Y137000D03*
X1298400Y144500D03*
X1288500Y137000D03*
Y139500D03*
Y134500D03*
X1286000Y132000D03*
X1288500D03*
X1308972Y96742D03*
X1338500Y96000D03*
X1302526Y119102D03*
X1302504Y116700D03*
Y111700D03*
Y114300D03*
X1325125Y100001D03*
X1322628Y100134D03*
X1323800Y104250D03*
X1326800D03*
Y107250D03*
X1323800D03*
X1326600Y123450D03*
X1323600D03*
X1326600Y126450D03*
X1323600D03*
X1340100Y145000D03*
X1301770Y101300D03*
X1310098Y150040D03*
X1335100Y155000D03*
Y145000D03*
X1330100Y150000D03*
X1340100D03*
Y155000D03*
X1315100Y145000D03*
X1335100Y150000D03*
X1330100Y145000D03*
Y155000D03*
X1323026Y133323D03*
X1326026D03*
X1306900Y131744D03*
X1301900Y124400D03*
X1320500Y145000D03*
X1295500Y159970D03*
X1299907Y159808D03*
X1330100Y165000D03*
Y170000D03*
X1340100Y165000D03*
Y170000D03*
X1335100D03*
Y165000D03*
X1320100D03*
X1325100D03*
X1320100Y170000D03*
X1325100D03*
X1310061Y165235D03*
X1305171Y164767D03*
X1330100Y160000D03*
X1340100D03*
X1306363Y169928D03*
X1335100Y160000D03*
X1323030Y216531D03*
X1329324Y208951D03*
X1338224Y209051D03*
X1334724D03*
X1326474Y216500D03*
X1331824Y209051D03*
X1324938Y209251D03*
X1322500D03*
X1320390Y216824D03*
X1333074Y216500D03*
X1336074D03*
X1300300Y169900D03*
X1303838Y169922D03*
X1330074Y216500D03*
X1281799Y193190D03*
X1283720Y223870D03*
X1288800Y233900D03*
X1300444Y267919D03*
X1336900Y232118D03*
X1325900D03*
X1314900D03*
X1342400D03*
X1331400D03*
X1320400D03*
X1309462Y240229D03*
X1320400Y234959D03*
X1325900D03*
X1314900D03*
X1336900D03*
X1331400D03*
X1342400D03*
X1334113Y273115D03*
X1340866Y268795D03*
X1327625Y275971D03*
X1330039Y279618D03*
X1308200Y255800D03*
X1310950Y255650D03*
X1315100Y237645D03*
X1325900Y237900D03*
X1342400D03*
X1331400D03*
X1320289Y237671D03*
X1323734Y279663D03*
X1330171Y276035D03*
X1336448Y271755D03*
X1340248D03*
X1333680Y276035D03*
X1327243Y279663D03*
X1336900Y237900D03*
X1306585Y258250D03*
X1319310Y300795D03*
X1299700Y298557D03*
X1299735Y301298D03*
X1336480Y309755D03*
X1336793Y303784D03*
X1342500Y312100D03*
X1316300Y282000D03*
X1325300Y282600D03*
X1314792Y286427D03*
X1314490Y283862D03*
X1335400Y284900D03*
X1334400Y292050D03*
X1337200Y292012D03*
X1336240Y301243D03*
X1341740D03*
X1323688Y290205D03*
X1303866Y292345D03*
X1305558Y294313D03*
X1306290Y298255D03*
X1303380Y309441D03*
X1302768Y296942D03*
X1319297Y296878D03*
X1321600Y294700D03*
X1338700Y284700D03*
X1305873Y309245D03*
X1305950Y306611D03*
X1341920Y309755D03*
X1342480Y303852D03*
X1302203Y314439D03*
X1331720Y334810D03*
X1326300Y341309D03*
X1320900Y321300D03*
X1323750Y319750D03*
X1331650Y317250D03*
X1319906Y338025D03*
X1338500Y319600D03*
X1318751Y282730D03*
X1322260D03*
X1336240Y306760D03*
X1341740D03*
X1319888Y290205D03*
X1341375Y314675D03*
Y319675D03*
X1308887Y285015D03*
X1316600Y305500D03*
X1336336Y333825D03*
X1326014Y347732D03*
X1342570Y368220D03*
X1330100Y350100D03*
X1332600Y349900D03*
X1315496Y361190D03*
X1332613Y346417D03*
X1329757Y346511D03*
X1341954Y360368D03*
X1335250Y344250D03*
X1331770Y399490D03*
X1332650Y374450D03*
X1317788Y402562D03*
Y400062D03*
X1331856Y401995D03*
X1329064Y399556D03*
X1329288Y402062D03*
X1330200Y377300D03*
X1330758Y389785D03*
Y386785D03*
Y383785D03*
X1324872Y380682D03*
X1322054Y380560D03*
X1324872Y383682D03*
X1327800Y383500D03*
X1325000Y377500D03*
X1327600Y377400D03*
X1319300Y378500D03*
X1327700Y380400D03*
X1322100Y377800D03*
X1323288Y402062D03*
X1323064Y399556D03*
X1320423Y399579D03*
X1320288Y402062D03*
X1326288D03*
X1326064Y399556D03*
X1332600Y377200D03*
X1332748Y380503D03*
X1330190Y380406D03*
X1336886Y351113D03*
X1339597Y349756D03*
X1335100Y427500D03*
X1329419Y464337D03*
X1323815Y463543D03*
X1318054Y460507D03*
X1285769Y440062D03*
X1341528Y463528D03*
X1321172Y464474D03*
X1288671Y445338D03*
X1326626Y464400D03*
X1296468Y437500D03*
X1300100Y442500D03*
X1301000Y460900D03*
X1300438Y433001D03*
X1300315Y427902D03*
X1305100Y432500D03*
X1320100Y427500D03*
Y432500D03*
X1325100Y427500D03*
Y432500D03*
X1305181Y427834D03*
X1310100Y427500D03*
Y432500D03*
X1315100Y427500D03*
Y432500D03*
X1340100Y427500D03*
X1330100Y432500D03*
Y427500D03*
X1340100Y432500D03*
X1335100D03*
X1319320Y418900D03*
X1334889Y421400D03*
X1332236Y419004D03*
X1329400Y404524D03*
X1329736Y419004D03*
X1329889Y421400D03*
X1332389D03*
X1331973Y404580D03*
X1322370Y421400D03*
X1324889Y421470D03*
X1320400Y404524D03*
X1326400D03*
X1323400D03*
X1324736Y419074D03*
X1322217Y419004D03*
X1327236Y419030D03*
X1327389Y421426D03*
X1334967Y419001D03*
X1325100Y457500D03*
Y452500D03*
X1320100Y457500D03*
Y452500D03*
X1315100D03*
X1310100D03*
X1315100Y457500D03*
X1305100D03*
Y452500D03*
X1310100Y457500D03*
X1330100D03*
Y452500D03*
X1335100Y457500D03*
Y452500D03*
Y447500D03*
Y442500D03*
X1330100D03*
X1305100D03*
X1310100D03*
X1320100D03*
X1315100D03*
X1325100D03*
X1340100Y457500D03*
Y452500D03*
Y447500D03*
Y442500D03*
X1304200Y462030D03*
X1316820Y421400D03*
Y418900D03*
X1286831Y443058D03*
X1337100Y499300D03*
X1319738Y477497D03*
X1322360Y472592D03*
X1322260Y477492D03*
X1326877Y469279D03*
X1319699Y472327D03*
X1297878Y493150D03*
X1295240Y493359D03*
X1290500Y480200D03*
Y482700D03*
X1299450Y484950D03*
X1295960Y519450D03*
Y516450D03*
Y513450D03*
X1295880Y510810D03*
X1298460Y513450D03*
Y516450D03*
Y519450D03*
X1298380Y510810D03*
X1301000Y466500D03*
X1301240Y476228D03*
X1304200Y466600D03*
X1320300Y498300D03*
X1335100Y507700D03*
X1332500Y509100D03*
X1339600Y515800D03*
X1341050Y498275D03*
X1334300Y499300D03*
X1340986Y511187D03*
X1313700Y515200D03*
Y517800D03*
X1309870Y499254D03*
X1319300Y525450D03*
X1321800D03*
X1311772Y501000D03*
X1319075D03*
X1316675Y500983D03*
X1314272Y501000D03*
X1329419Y469337D03*
X1287770Y501897D03*
X1339900Y518900D03*
X1332600Y506300D03*
X1308500Y540784D03*
X1305500Y542500D03*
X1295660Y527700D03*
X1298460Y536700D03*
Y530700D03*
Y533700D03*
Y527700D03*
X1295660Y536700D03*
Y530700D03*
Y533700D03*
X1285400Y561000D03*
X1282600Y581000D03*
Y583600D03*
X1295090Y579360D03*
X1293290Y581160D03*
X1290900Y563300D03*
X1288100Y562000D03*
X1300000Y552400D03*
Y558400D03*
Y555400D03*
X1343100Y566300D03*
X1340700D03*
X1338000D03*
X1340526Y563337D03*
X1343026D03*
X1338026D03*
X1333026D03*
X1335526D03*
Y566237D03*
X1318500Y539900D03*
X1327956Y545655D03*
X1317500Y552400D03*
X1320500D03*
X1323500D03*
X1324707Y545493D03*
X1316100Y543400D03*
X1321800Y532750D03*
X1319300Y532650D03*
X1321800Y527850D03*
X1319300D03*
Y530250D03*
X1321800D03*
X1317500Y555400D03*
X1320500D03*
X1323500D03*
X1303000Y576000D03*
Y579000D03*
Y571400D03*
Y568900D03*
Y565900D03*
Y563400D03*
X1306000Y579000D03*
X1323774Y563145D03*
Y566145D03*
X1309000Y565900D03*
Y563400D03*
Y571400D03*
X1306000Y568900D03*
X1309000D03*
X1306000Y576000D03*
X1324000Y568900D03*
X1306000Y571400D03*
X1321000D03*
X1324000D03*
X1321000Y568900D03*
X1318000D03*
X1312000D03*
X1318000Y571400D03*
X1315000D03*
Y568900D03*
X1312000Y571400D03*
X1320500Y558400D03*
X1317500D03*
X1312000Y563400D03*
Y565900D03*
X1315000Y563400D03*
Y565900D03*
X1323500Y558400D03*
X1318000Y563400D03*
Y565900D03*
X1321000Y563400D03*
Y565900D03*
X1306000D03*
Y563400D03*
X1333026Y566237D03*
X1292190Y576952D03*
X1290292Y578962D03*
X1298100Y598300D03*
Y595800D03*
Y590000D03*
Y592500D03*
X1296295Y615596D03*
X1311876Y619501D03*
X1314476D03*
X1307600Y620100D03*
X1301384Y618119D03*
X1306600Y610000D03*
X1306556Y607558D03*
X1324200Y610100D03*
Y600100D03*
Y597600D03*
X1321100Y598500D03*
Y601000D03*
X1315100Y598500D03*
Y601000D03*
X1312100Y598500D03*
X1309100D03*
Y601000D03*
X1312100D03*
X1318100Y598500D03*
Y601000D03*
X1324200Y602700D03*
Y605100D03*
Y607500D03*
X1402600Y10000D03*
X1400100D03*
X1357400Y-19800D03*
X1360400Y10600D03*
X1350654Y-18411D03*
X1348154Y-15911D03*
Y-18411D03*
X1357600Y5140D03*
X1345518Y-18476D03*
X1353154Y-18411D03*
X1376094Y4406D03*
X1380008Y-3805D03*
X1366789Y5776D03*
X1375676Y7630D03*
X1385608Y-17485D03*
X1388294Y-5675D03*
X1389523Y4966D03*
X1380678Y-422D03*
X1380300Y2944D03*
X1374100Y-16900D03*
X1376719Y-16802D03*
X1382151Y-5545D03*
X1369389Y5776D03*
X1380950Y30232D03*
X1376842Y15185D03*
X1374431Y15170D03*
X1381642Y25898D03*
X1400616Y13795D03*
X1379200Y27000D03*
X1355950Y-16507D03*
X1359450Y-7D03*
X1355950D03*
X1357489Y-1924D03*
X1359450Y2493D03*
X1355950D03*
X1357489Y-14424D03*
Y-10524D03*
Y-6124D03*
X1355889Y-8524D03*
X1355847Y-12275D03*
X1355989Y-3924D03*
X1356261Y32017D03*
X1356300Y20100D03*
X1356376Y24167D03*
X1356200Y28200D03*
X1357900Y30200D03*
X1357800Y26100D03*
X1357803Y22200D03*
X1356261Y15517D03*
X1357700Y17800D03*
X1359761Y32317D03*
X1371650Y-907D03*
X1371589Y-3424D03*
Y-5924D03*
X1371900Y28600D03*
X1371598Y-11633D03*
X1371632Y-9191D03*
X1371653Y-16654D03*
X1371605Y-14069D03*
X1371941Y22617D03*
X1371950Y20200D03*
X1371900Y17800D03*
Y15400D03*
Y26100D03*
Y31100D03*
X1380219Y5581D03*
X1379025Y-9799D03*
X1369408Y50479D03*
X1351908Y40402D03*
X1362448Y43413D03*
X1375412Y92182D03*
X1378464Y91979D03*
X1371500Y63200D03*
X1375500Y76000D03*
X1397500Y51000D03*
X1365855Y46972D03*
X1359800Y37300D03*
X1357300D03*
X1361634Y95519D03*
X1347000Y87500D03*
X1343500D03*
X1360700Y86550D03*
X1351500Y83000D03*
X1344000D03*
X1402700Y51100D03*
X1381817Y46484D03*
X1388627Y35032D03*
X1380500Y54500D03*
X1380900Y59820D03*
X1372400Y37785D03*
X1376989Y46971D03*
X1397550Y68059D03*
X1395050D03*
X1397050Y58559D03*
X1392050D03*
X1394550D03*
X1397050Y55559D03*
X1394550D03*
X1392050D03*
X1397539Y65098D03*
X1394939D03*
X1392339D03*
X1369700Y37800D03*
X1377009Y39753D03*
X1367100Y37800D03*
X1389138Y58499D03*
X1395000Y78800D03*
X1397400D03*
X1392584Y78798D03*
X1395000Y76200D03*
X1392584D03*
X1397400D03*
X1367700Y86450D03*
X1403746Y91680D03*
X1370100Y82500D03*
X1366100D03*
X1364700Y86550D03*
X1389068Y78556D03*
X1389100Y74600D03*
X1359500Y83000D03*
X1355500D03*
X1350830Y60730D03*
X1356261Y34517D03*
X1356950Y54370D03*
X1356760Y66660D03*
X1357000Y60500D03*
X1359761Y34817D03*
X1350800Y66600D03*
X1351190Y54710D03*
X1363170Y54280D03*
X1362900Y60500D03*
X1363040Y66660D03*
X1362674Y46058D03*
X1348945Y40264D03*
X1370975Y67225D03*
X1343260Y53770D03*
X1351488Y74000D03*
X1358500Y74500D03*
X1347500Y83000D03*
X1357000Y86640D03*
X1383171Y57549D03*
X1379110Y45033D03*
X1392149Y68006D03*
X1371910Y48800D03*
X1370849Y59349D03*
X1380500Y50500D03*
X1372300Y86400D03*
X1363500Y77400D03*
X1403264Y82000D03*
X1356230Y126500D03*
X1359230D03*
X1360730Y129000D03*
X1362230Y126500D03*
X1355100Y155000D03*
Y145000D03*
Y150000D03*
X1360100Y155000D03*
Y145000D03*
Y150000D03*
X1345000Y104500D03*
X1361634Y97919D03*
X1345100Y150000D03*
X1350100Y155000D03*
Y150000D03*
Y145000D03*
X1345100D03*
Y155000D03*
X1404200Y119200D03*
X1398600Y116500D03*
X1371500Y101000D03*
X1374808Y99366D03*
X1388100Y108500D03*
X1377308Y106866D03*
Y104366D03*
Y101866D03*
X1374808Y106866D03*
Y104366D03*
Y101866D03*
X1381359Y108496D03*
X1384600Y108500D03*
X1394298Y108548D03*
X1394310Y111506D03*
X1391359Y108496D03*
X1400300Y121500D03*
X1396780Y119080D03*
X1401200Y124300D03*
X1399400Y126400D03*
X1394700Y122950D03*
X1391700D03*
Y125950D03*
X1394700D03*
Y128950D03*
X1391700D03*
X1397994Y103350D03*
X1397952Y105998D03*
X1395326Y100913D03*
Y103413D03*
X1395347Y106040D03*
X1386700Y125450D03*
Y128450D03*
X1383700Y125450D03*
Y128450D03*
X1380700Y125450D03*
Y128450D03*
X1376100Y116100D03*
X1376669Y121763D03*
Y118763D03*
X1376100Y124950D03*
X1373850Y114450D03*
X1369730Y129000D03*
X1363730D03*
X1366730D03*
X1373850Y117450D03*
X1368230Y126500D03*
X1373850Y123450D03*
X1365230Y126500D03*
X1397193Y112602D03*
X1394253Y116989D03*
X1401300Y149600D03*
X1385100Y155000D03*
X1375100D03*
X1365100D03*
X1380100D03*
Y145000D03*
X1385100D03*
X1380100Y150000D03*
X1385100D03*
X1365100Y145000D03*
Y150000D03*
X1375100D03*
X1370100Y155000D03*
Y145000D03*
X1375100D03*
X1370100Y150000D03*
X1402500Y116300D03*
X1352200Y104950D03*
Y108400D03*
X1357700D03*
Y104950D03*
X1345257Y100000D03*
X1348615Y96239D03*
X1353500Y96959D03*
X1345500Y107529D03*
X1364700Y96440D03*
X1373850Y120450D03*
X1360100Y160000D03*
X1355100D03*
Y170000D03*
X1360100D03*
X1355100Y165000D03*
X1360100D03*
X1345100D03*
X1350100D03*
X1345100Y170000D03*
Y160000D03*
X1350100D03*
X1344462Y209272D03*
X1365100Y170000D03*
Y165000D03*
X1370100D03*
X1375100Y170000D03*
X1370100D03*
X1375100Y165000D03*
X1380100Y170000D03*
X1402020Y165561D03*
X1399100Y166900D03*
X1390100Y160000D03*
X1370100D03*
X1390100Y170000D03*
X1385100Y160000D03*
Y165000D03*
Y170000D03*
X1365100Y160000D03*
X1375100D03*
X1390100Y165000D03*
X1403400Y204766D03*
X1384671Y214832D03*
X1367789Y209216D03*
X1396933Y215763D03*
X1359500Y209200D03*
X1356926Y209100D03*
X1362000Y209300D03*
X1402870Y207918D03*
X1353569Y208960D03*
X1348569D03*
X1397211Y226041D03*
X1402400Y223600D03*
X1399852Y252353D03*
X1383753Y265548D03*
X1397400Y234959D03*
X1391900D03*
X1386400D03*
X1399978Y233775D03*
X1400066Y236274D03*
X1398600Y228700D03*
X1401565Y229435D03*
X1399600Y223600D03*
X1358900Y232118D03*
X1347900D03*
X1353400D03*
X1358900Y234959D03*
X1353400D03*
X1347900D03*
X1349500Y265500D03*
X1359100Y265600D03*
X1345050Y272350D03*
X1380900Y232118D03*
X1369900D03*
X1397400D03*
X1386400D03*
X1375400D03*
X1364400D03*
X1388518Y230789D03*
X1380900Y234959D03*
X1369900D03*
X1364400D03*
X1375400Y235100D03*
X1369100Y265500D03*
X1374864Y265629D03*
X1397400Y237900D03*
X1375400D03*
X1364400D03*
X1353400D03*
X1394881Y226997D03*
X1377522Y265600D03*
X1366312Y265525D03*
X1352468Y265695D03*
X1343668Y268095D03*
X1381031Y265600D03*
X1347468Y268095D03*
X1356268Y265695D03*
X1362803Y265525D03*
X1391900Y237900D03*
X1380900D03*
X1369900D03*
X1358900D03*
X1347900D03*
X1391900Y232118D03*
X1386400Y237900D03*
X1347892Y299741D03*
X1369320Y301219D03*
X1358514Y300815D03*
X1392135Y302051D03*
X1380601Y301465D03*
X1364260Y331619D03*
X1388450Y331250D03*
X1392400Y330800D03*
X1398062Y315743D03*
X1403100Y321350D03*
X1383639Y315274D03*
X1389600Y315200D03*
X1384024Y320225D03*
X1386048Y310310D03*
X1386265Y304310D03*
X1389600Y320100D03*
X1397640Y310631D03*
X1397880Y304640D03*
X1392380D03*
X1392340Y310625D03*
X1403260Y310623D03*
X1403300Y304640D03*
X1388208Y341489D03*
X1400400Y335400D03*
X1348080Y309825D03*
X1353142Y309761D03*
X1358792Y309760D03*
X1358800Y303700D03*
X1353359Y303767D03*
X1353672Y299605D03*
X1345700Y285300D03*
X1348190Y303810D03*
X1355300Y321675D03*
X1359200Y322200D03*
X1346550Y322350D03*
X1350650Y315050D03*
X1357452Y319395D03*
X1369540Y310125D03*
X1374900Y310130D03*
X1397635Y302051D03*
X1386101Y301465D03*
X1374820Y301219D03*
X1364014Y300815D03*
X1368200Y284000D03*
X1365246Y285931D03*
X1381100Y304360D03*
X1380910Y310300D03*
X1364044Y309691D03*
X1364213Y303694D03*
X1375040Y304135D03*
X1369540D03*
X1371000Y322400D03*
X1363059Y314514D03*
X1368947Y313993D03*
X1355800Y285000D03*
X1352400D03*
X1359000Y284900D03*
X1367200Y321600D03*
X1363700D03*
X1400558Y316357D03*
X1404286Y281729D03*
X1403037Y307630D03*
X1360294Y315025D03*
X1371090Y315395D03*
X1380904Y315947D03*
X1392226Y315658D03*
X1349134Y321145D03*
X1402092Y284022D03*
X1398347Y284023D03*
X1398926Y281582D03*
X1392135Y307630D03*
X1380548Y307310D03*
X1369340Y307130D03*
X1358544Y306690D03*
X1347642Y306760D03*
X1397635Y307630D03*
X1386048Y307310D03*
X1374840Y307130D03*
X1364044Y306690D03*
X1353142Y306760D03*
X1392226Y319458D03*
X1349134Y317436D03*
X1400558Y320157D03*
X1380904Y319747D03*
X1371090Y319195D03*
X1360294Y318825D03*
X1396470Y330014D03*
X1381431Y284259D03*
X1358500Y338400D03*
X1370200D03*
X1364300Y338300D03*
X1403037Y302046D03*
X1392144Y364617D03*
X1389450Y372250D03*
X1384700Y359700D03*
X1392500Y344600D03*
X1392805Y360466D03*
X1388500Y350864D03*
X1391200Y386300D03*
X1384531Y382957D03*
X1394760Y394720D03*
X1394370Y384230D03*
X1394260Y351170D03*
X1389500Y360500D03*
X1388300Y346200D03*
X1384300Y398900D03*
X1386800D03*
X1384252Y401343D03*
X1386752D03*
X1380900Y383164D03*
X1371600Y368700D03*
X1362510Y360717D03*
X1354024Y398985D03*
X1352338Y404153D03*
X1351379Y399227D03*
X1352239Y401593D03*
X1359600Y360800D03*
X1356466Y360680D03*
X1344731Y359567D03*
X1358512Y371792D03*
X1360450Y402100D03*
X1359360Y398810D03*
X1357880Y403760D03*
X1356560Y398910D03*
X1362250Y399160D03*
X1354681Y401444D03*
X1354982Y404154D03*
X1357542Y401381D03*
X1378200Y346900D03*
X1374344Y371431D03*
X1380200Y370400D03*
X1376979Y370536D03*
X1364856Y366666D03*
X1382017Y367584D03*
X1380800Y392300D03*
X1372007Y396668D03*
X1380200Y373100D03*
X1377103Y373428D03*
X1374300Y402053D03*
X1376800D03*
X1381752Y401343D03*
X1379252D03*
X1381800Y398900D03*
X1378207Y394568D03*
X1369407Y396668D03*
X1363250Y401700D03*
X1371200Y402100D03*
X1381500Y396200D03*
X1375201Y396303D03*
X1365731Y360698D03*
X1358500Y374500D03*
X1360200Y377400D03*
X1358655Y379352D03*
X1362068Y393385D03*
X1360300Y381100D03*
X1360200Y384700D03*
Y389000D03*
X1358700Y386700D03*
X1358568Y390885D03*
Y393385D03*
X1358600Y382800D03*
X1362068Y390885D03*
X1374300Y377885D03*
Y381485D03*
X1374268Y374285D03*
Y389985D03*
X1374207Y384968D03*
Y387468D03*
X1391845Y348325D03*
X1383700Y392300D03*
X1388900Y387800D03*
X1380872Y378098D03*
X1370300Y350200D03*
X1358300Y344200D03*
X1358400Y350100D03*
X1370200Y343900D03*
X1364100Y350200D03*
X1385100Y427500D03*
Y442500D03*
Y437500D03*
X1385416Y410502D03*
X1404558Y416575D03*
X1402725Y408136D03*
X1402520Y413246D03*
X1388085Y410479D03*
X1403998Y429775D03*
X1404558Y421575D03*
X1398275Y453561D03*
X1397975Y457561D03*
X1403998Y434775D03*
X1395725Y417193D03*
X1393900Y415000D03*
X1396900D03*
Y412500D03*
X1393900D03*
X1385100Y452500D03*
Y447500D03*
X1389900Y427400D03*
X1385100Y432500D03*
X1395100Y427500D03*
Y432500D03*
X1389900Y447400D03*
X1344090Y463630D03*
X1346739Y463615D03*
X1382849Y410471D03*
X1380449Y410479D03*
X1358990Y411040D03*
X1358910Y408480D03*
X1358980Y406060D03*
X1355100Y427500D03*
Y432500D03*
X1361558Y410527D03*
X1349800Y458200D03*
X1350100Y447500D03*
Y452500D03*
X1360100Y447500D03*
Y452500D03*
Y457500D03*
X1345100Y442500D03*
X1350100D03*
X1345100Y437500D03*
X1350100D03*
X1355100D03*
Y442500D03*
X1362560Y463478D03*
X1369034Y458075D03*
X1365100Y432500D03*
Y427500D03*
X1369907Y410513D03*
X1372535Y410512D03*
X1375239Y410590D03*
X1377928Y410451D03*
X1366984Y410481D03*
X1364403Y410496D03*
X1370100Y447500D03*
X1365100Y437500D03*
X1380100Y442500D03*
Y437500D03*
X1370100D03*
X1375100D03*
Y452500D03*
X1370100D03*
X1380100Y447500D03*
X1370100Y442500D03*
X1365100Y452500D03*
X1379857Y458108D03*
X1365100Y442500D03*
X1375100D03*
X1380100Y452500D03*
X1365100Y447500D03*
X1402775Y453561D03*
X1395375Y457561D03*
X1390100Y457500D03*
X1395100Y447500D03*
X1401398Y429775D03*
Y434775D03*
X1402775Y457561D03*
X1388900Y525230D03*
X1395581Y525357D03*
X1383600Y482504D03*
X1386041Y493723D03*
X1383519Y487445D03*
X1390330Y516690D03*
X1385033Y516848D03*
X1387568Y516892D03*
X1388865Y519788D03*
X1388850Y522266D03*
X1386033Y498811D03*
X1403027Y520231D03*
X1402950Y510650D03*
X1400445Y510159D03*
X1395242Y520301D03*
X1383859Y519931D03*
X1386359D03*
X1396035Y514863D03*
X1386241Y487323D03*
Y482623D03*
X1388719Y498745D03*
X1383263Y493673D03*
X1347546Y476897D03*
X1350500Y475100D03*
X1354462Y474141D03*
X1347196Y472941D03*
X1355800Y508500D03*
X1344761Y498282D03*
X1344073Y508263D03*
X1363800Y481600D03*
X1363662Y486636D03*
X1365741Y492723D03*
X1382578Y516805D03*
X1377492Y516892D03*
X1369757Y517465D03*
X1365719Y497545D03*
X1373345Y519940D03*
X1381095D03*
X1376109Y519931D03*
X1378609D03*
X1368441Y497523D03*
X1366309Y486618D03*
X1366341Y481823D03*
X1360741Y486523D03*
X1381041Y482575D03*
X1362841Y492823D03*
X1380741Y487489D03*
X1352490Y515470D03*
X1346870Y515450D03*
X1352590Y519170D03*
X1346970Y519150D03*
X1388741Y493623D03*
X1383241Y498595D03*
X1368441Y492723D03*
X1362880Y497556D03*
X1360863Y481673D03*
X1347081Y507919D03*
X1396158Y537595D03*
X1401777Y557632D03*
X1385033Y544267D03*
X1390623Y574986D03*
X1400830Y564090D03*
X1400288Y570099D03*
X1404420Y576330D03*
X1400980Y587086D03*
X1397980D03*
X1399721Y537509D03*
X1386800Y535600D03*
Y541500D03*
Y538500D03*
X1384310Y538540D03*
Y535540D03*
Y541540D03*
X1385316Y574705D03*
X1387986Y574960D03*
X1390595Y549328D03*
X1387907Y544286D03*
X1404519Y560280D03*
Y557380D03*
X1361600Y559400D03*
X1358529Y537492D03*
X1361163Y540052D03*
X1358518Y540073D03*
X1356018D03*
X1356029Y537492D03*
X1363674Y537471D03*
X1355548Y559959D03*
X1361926Y584037D03*
Y586537D03*
X1359100Y586200D03*
X1357400Y588400D03*
X1360100D03*
X1344613Y556376D03*
Y561376D03*
Y558876D03*
X1347700Y554100D03*
X1353520Y537480D03*
X1344613Y553876D03*
X1361174Y537471D03*
X1358439Y559959D03*
X1375479Y540117D03*
X1375500Y537717D03*
X1366265Y537437D03*
X1363663Y540052D03*
X1363568Y550589D03*
X1380521Y535276D03*
X1378021D03*
X1375621Y535254D03*
X1371265Y537437D03*
X1368765D03*
X1366459Y550589D03*
X1377979Y537717D03*
Y540117D03*
X1380479Y537717D03*
X1368596Y539889D03*
X1371096D03*
X1366096D03*
X1380479Y540117D03*
X1382331Y543818D03*
X1382032Y560143D03*
X1376070Y559760D03*
X1382200Y562700D03*
X1379000Y561500D03*
X1373700Y584656D03*
X1379053Y581864D03*
X1371100Y584656D03*
X1376800Y584328D03*
X1364426Y586637D03*
Y584137D03*
X1382500Y575400D03*
Y579100D03*
X1365028Y547954D03*
X1362528D03*
X1360500Y570900D03*
Y574700D03*
X1360261Y578873D03*
X1360247Y567390D03*
X1360261Y562373D03*
Y581373D03*
X1362000Y576700D03*
Y572800D03*
X1362100Y569100D03*
X1362000Y565600D03*
X1375961Y569473D03*
X1376000Y565700D03*
X1375961Y562273D03*
X1363761Y581373D03*
X1375961Y577973D03*
X1376000Y575456D03*
Y572956D03*
X1390500Y539000D03*
X1383074Y581963D03*
X1390462Y541800D03*
X1400216Y560128D03*
X1387050Y615350D03*
X1392500Y592000D03*
X1384744Y605689D03*
X1385000Y602700D03*
X1386921Y620689D03*
X1390851D03*
X1400980Y589586D03*
X1395060Y590630D03*
X1373838Y616161D03*
X1380890Y615820D03*
X1371100Y615756D03*
X1376556D03*
X1357726Y591037D03*
X1360226D03*
X1382586Y609602D03*
X1382605Y612102D03*
X1375600Y589700D03*
X1382100Y592800D03*
X1382000Y589500D03*
X1382200Y606300D03*
X1363761Y612573D03*
X1360261D03*
X1360200Y597800D03*
X1361600Y599900D03*
X1361500Y595700D03*
X1360100Y610100D03*
X1360200Y606300D03*
Y602000D03*
X1361900Y608200D03*
X1361500Y604200D03*
X1360261Y593573D03*
X1375961Y600673D03*
X1375861Y597073D03*
X1375961Y593473D03*
X1363761Y610073D03*
X1375961Y609173D03*
X1375900Y604156D03*
Y606656D03*
X1398010Y590040D03*
X1405100Y10000D03*
X1413721Y13139D03*
X1416871D03*
X1454991Y5589D03*
X1454715Y2784D03*
X1450508Y2756D03*
X1410600Y9100D03*
X1410571Y13170D03*
X1420019Y13466D03*
X1448367Y13533D03*
X1438918D03*
X1429469Y13466D03*
X1457814D03*
X1436131Y5248D03*
X1432661Y5220D03*
X1449991Y5589D03*
X1436025Y7756D03*
X1427442Y11563D03*
X1431025Y7756D03*
X1422442Y11563D03*
X1465237D03*
X1460237D03*
X1446340D03*
X1441340D03*
X1407422Y13139D03*
X1420337Y45477D03*
X1416837D03*
X1411546Y43116D03*
X1406546D03*
X1406674Y46120D03*
X1411254Y46018D03*
X1412250Y65359D03*
X1407150Y58859D03*
X1410150D03*
X1407150Y52859D03*
X1410150D03*
X1409250Y65359D03*
X1407150Y55859D03*
X1410150D03*
X1413721Y36749D03*
X1412250Y68359D03*
X1409250D03*
X1407964Y79700D03*
X1407960Y93800D03*
X1407300Y77300D03*
X1410200Y77400D03*
X1405149Y93679D03*
X1406746Y91680D03*
X1406264Y82000D03*
X1409264D03*
X1404964Y79700D03*
X1409150Y71259D03*
X1412150D03*
X1425081Y48412D03*
X1442067Y34830D03*
X1423170Y36635D03*
X1432619Y34830D03*
X1451516D03*
X1460965D03*
X1453809Y94639D03*
X1453700Y83750D03*
X1455889Y73700D03*
X1453221Y73750D03*
X1455347Y92065D03*
X1457000Y82000D03*
X1450973Y112225D03*
X1452648Y103788D03*
X1451198Y143761D03*
X1451590Y138750D03*
X1451021Y151626D03*
X1438348Y155908D03*
X1451228Y141261D03*
X1451233Y146405D03*
X1451273Y148905D03*
X1452232Y109500D03*
X1422196Y218052D03*
X1446331Y197285D03*
X1458569Y192143D03*
X1449847Y202322D03*
X1439000Y208500D03*
X1442251Y180818D03*
X1408247Y206270D03*
X1418300Y199900D03*
X1451386Y173499D03*
X1451366Y165296D03*
X1451365Y170318D03*
Y176014D03*
X1450532Y178372D03*
X1454070Y163360D03*
X1454660Y166200D03*
X1440150Y175550D03*
X1440124Y166180D03*
X1451427Y167818D03*
X1447999Y205645D03*
X1458908Y187699D03*
X1444850Y242730D03*
X1433362Y280744D03*
X1412579Y268273D03*
X1433362Y278244D03*
X1426658Y274252D03*
X1455600Y254826D03*
X1439700Y253100D03*
X1434800Y248900D03*
X1435655Y246550D03*
X1441750Y236800D03*
X1434300Y251600D03*
X1437400Y244150D03*
X1464150Y235550D03*
X1462700Y221700D03*
X1464200Y231400D03*
X1407274Y245652D03*
X1410979Y270473D03*
X1451850Y262200D03*
X1461348Y244350D03*
X1454350Y262200D03*
X1466006Y265300D03*
X1465063Y253544D03*
X1464700Y256100D03*
X1447154Y251710D03*
X1462704Y254470D03*
X1422281Y221479D03*
X1454056Y266169D03*
X1466404Y245350D03*
X1454000Y259700D03*
X1437800Y258300D03*
X1452200Y254500D03*
X1452728Y243306D03*
X1458800Y254882D03*
X1433700Y254200D03*
X1458318Y243000D03*
X1426905Y267045D03*
X1448500Y257700D03*
X1430365Y262624D03*
X1433057Y257388D03*
X1438500Y255400D03*
X1459548Y221731D03*
X1410800Y316100D03*
X1408580Y310632D03*
X1408760Y304637D03*
X1408376Y339882D03*
X1408250Y333000D03*
X1408348Y336436D03*
X1410550Y320800D03*
X1410489Y337988D03*
X1443500Y327900D03*
X1416000Y332900D03*
Y338100D03*
X1444311Y324366D03*
X1419343Y310652D03*
X1416000Y335500D03*
X1419283Y304570D03*
X1413983Y304645D03*
X1413943Y310628D03*
X1419220Y301983D03*
X1408537Y302046D03*
X1419333Y307598D03*
X1413387Y316233D03*
X1405392Y284022D03*
X1413720Y307634D03*
X1408537Y307630D03*
X1413387Y320033D03*
X1413720Y301983D03*
X1464400Y382720D03*
X1448050Y374950D03*
X1464273Y397648D03*
X1463200Y362200D03*
X1463870Y367869D03*
X1453900Y353350D03*
X1463617Y357259D03*
X1413400Y361300D03*
X1456000Y360700D03*
X1463942Y359742D03*
X1464400Y390800D03*
X1450400Y354300D03*
X1460400Y353000D03*
X1459111Y356353D03*
X1447685Y352025D03*
X1453251Y356676D03*
X1461016Y359965D03*
X1417656Y367547D03*
X1420101Y396236D03*
X1418138Y386361D03*
X1415000Y399000D03*
X1412220Y388360D03*
X1417217Y379129D03*
X1417349Y382137D03*
X1417773Y374107D03*
X1464124Y353776D03*
X1465500Y395400D03*
X1456750Y381850D03*
X1459033Y395334D03*
X1446700Y387900D03*
X1437897Y402315D03*
X1443100Y368950D03*
X1464361Y385275D03*
X1415500Y353200D03*
X1445510Y350327D03*
X1415450Y350550D03*
X1456981Y384569D03*
X1445100Y374900D03*
X1452699Y404060D03*
X1439934Y403730D03*
X1444400Y371600D03*
X1465048Y402370D03*
X1420515Y373585D03*
Y368585D03*
X1456900Y387600D03*
X1457300Y373600D03*
X1420075Y378375D03*
Y393402D03*
Y383375D03*
Y388402D03*
X1413735Y396302D03*
Y391302D03*
X1408225Y438233D03*
X1411900Y429775D03*
X1405375Y453561D03*
X1405608Y456761D03*
X1411900Y434775D03*
X1408225Y441000D03*
X1435479Y423107D03*
X1439350Y406900D03*
X1459200Y459800D03*
Y454100D03*
X1459000Y449997D03*
X1451400Y454100D03*
Y459800D03*
X1445000Y437000D03*
X1429000Y437059D03*
X1444800Y442500D03*
X1444500Y448000D03*
X1429100Y453400D03*
X1429000Y448000D03*
Y442600D03*
X1448800Y427800D03*
X1459478Y432851D03*
X1462131D03*
X1458300Y442675D03*
X1412484Y440748D03*
X1412375Y443545D03*
X1412447Y416368D03*
X1412545Y421974D03*
X1413300Y454400D03*
X1413075Y457561D03*
X1448800Y416500D03*
X1464300Y404900D03*
X1439000Y423000D03*
X1464600Y428000D03*
X1459300Y430000D03*
X1464525Y420014D03*
X1464731Y432942D03*
X1445100Y431500D03*
X1459200Y465500D03*
X1451400D03*
X1461800Y454100D03*
X1464200Y449997D03*
X1439813Y409422D03*
X1439651Y412466D03*
X1466382Y406773D03*
X1442830Y406472D03*
X1443252Y409029D03*
X1405423Y413281D03*
X1407158Y421575D03*
X1454000Y459800D03*
X1405423Y408281D03*
X1407158Y416575D03*
X1414982Y417040D03*
X1409300Y429775D03*
X1410475Y457561D03*
X1415146Y421946D03*
X1409300Y434775D03*
X1464400Y465500D03*
X1456600D03*
X1461800Y459800D03*
X1454000Y454100D03*
X1414107Y447267D03*
X1461600Y449997D03*
X1464400Y454100D03*
X1461800Y465500D03*
X1454000D03*
X1410475Y453561D03*
X1456600Y454100D03*
X1464400Y459800D03*
X1456600D03*
X1448000Y431500D03*
X1431900Y453500D03*
X1447500Y448000D03*
X1431900Y442600D03*
X1448000Y437000D03*
X1431900Y448000D03*
X1447700Y442500D03*
X1431900Y437100D03*
X1408753Y527518D03*
X1405950Y510650D03*
X1407884Y512751D03*
X1461713Y515196D03*
X1460661Y484891D03*
X1459213Y515196D03*
X1461267Y489790D03*
X1456602Y485864D03*
X1452188Y487223D03*
X1456590Y488976D03*
X1418241Y489523D03*
X1418441Y482523D03*
X1441842Y482924D03*
X1442041Y494423D03*
X1415541Y489523D03*
X1416100Y483500D03*
X1415800Y477500D03*
Y495200D03*
X1420200Y520500D03*
X1447749Y485395D03*
X1439314Y477723D03*
X1439400Y483600D03*
X1439341Y489323D03*
X1453700Y501600D03*
X1458357Y523271D03*
X1461100Y523600D03*
X1439400Y494700D03*
X1431690Y521530D03*
X1449568Y487276D03*
X1417800Y521500D03*
X1414800Y521400D03*
X1458060Y495020D03*
X1458935Y512470D03*
X1428500Y521000D03*
X1438390Y527175D03*
X1436396Y477691D03*
X1413041Y477423D03*
X1412941Y489523D03*
X1464553Y508872D03*
X1436441Y489323D03*
X1412741Y494223D03*
X1436541Y494423D03*
X1436600Y482900D03*
X1413193Y482532D03*
X1436358Y525142D03*
X1418341Y494423D03*
Y477323D03*
X1442141Y477623D03*
X1442041Y489223D03*
X1409693Y560343D03*
X1412093D03*
X1410850Y564210D03*
X1410340Y570370D03*
X1410486Y529792D03*
X1407019Y557380D03*
X1412019D03*
X1409519D03*
X1406993Y560343D03*
X1447852Y575687D03*
X1445800Y574300D03*
X1445750Y539000D03*
X1461500Y540000D03*
X1439861Y540497D03*
X1461653Y580762D03*
X1461707Y583162D03*
X1461878Y585556D03*
X1441252Y548631D03*
X1422509Y576823D03*
X1419809Y570723D03*
X1422509Y573823D03*
X1419809Y573723D03*
Y576723D03*
X1422509Y570823D03*
X1417252Y573470D03*
X1414743Y573363D03*
X1414851Y576624D03*
X1414744Y570801D03*
X1417182Y570711D03*
X1417288Y576624D03*
X1451150Y569900D03*
Y573200D03*
X1436160Y561200D03*
X1458629Y531604D03*
X1461500Y531500D03*
X1433100Y581770D03*
X1430570Y580890D03*
X1432590Y584550D03*
X1427500Y581100D03*
X1441409Y561117D03*
X1447022Y546578D03*
X1449922Y546664D03*
X1425243Y562260D03*
X1418402Y562624D03*
X1465700Y570500D03*
X1441805Y570887D03*
X1443797Y572482D03*
X1422500Y579800D03*
X1414800D03*
X1461930Y587956D03*
X1415173Y586332D03*
X1412673D03*
X1422920Y586250D03*
X1417920D03*
X1420420D03*
X1438799Y542785D03*
X1439123Y545294D03*
X1409500Y538000D03*
X1420500Y549800D03*
X1420400Y538000D03*
X1451533Y527867D03*
X1413600Y531300D03*
X1432560Y561160D03*
X1428791Y535512D03*
X1419600Y531500D03*
X1453533Y532667D03*
X1426870Y530800D03*
X1423800Y534800D03*
X1421560Y563455D03*
X1415582Y562904D03*
X1439822Y537382D03*
X1428281Y546119D03*
X1429026Y541026D03*
X1462039Y590354D03*
X1445145Y605727D03*
X1442525Y597279D03*
X1443654Y594749D03*
X1456277Y603454D03*
X1453628Y603368D03*
X1450720Y606067D03*
X1448071Y605981D03*
X1443473Y599944D03*
X1453451Y606114D03*
X1456100Y606200D03*
X1460200D03*
X1462155Y592761D03*
X1465334Y618564D03*
X1451314Y623298D03*
X1458000Y623400D03*
X1455000D03*
X1461000D03*
X1442200D03*
X1445200D03*
X1448200D03*
X1463419Y606912D03*
X1410950Y589670D03*
X1506300Y-6600D03*
X1498800Y-12676D03*
X1477100Y2400D03*
X1524800Y3500D03*
X1527700Y6963D03*
X1504400Y20300D03*
X1513700Y7082D03*
X1520700Y7100D03*
X1511900Y3500D03*
X1481600Y5300D03*
X1506900Y3500D03*
X1509400D03*
X1522600Y-6500D03*
X1514400Y3500D03*
X1520100D03*
X1469388Y5589D03*
X1469807Y2967D03*
X1474388Y5589D03*
X1473674Y2953D03*
X1476712Y13466D03*
X1467264Y13533D03*
X1485242Y4589D03*
X1496660Y-10252D03*
X1516900Y3500D03*
X1501900Y-9124D03*
X1492900Y4000D03*
X1489600D03*
X1521900Y27500D03*
X1509500Y31900D03*
X1495611Y13466D03*
X1486162Y13500D03*
X1524154Y28918D03*
X1521092Y21665D03*
X1527600Y3500D03*
X1493770Y6909D03*
X1484135Y11563D03*
X1488770Y6909D03*
X1479135Y11563D03*
X1470862Y38209D03*
X1470414Y34830D03*
X1479863D03*
X1497711Y34427D03*
X1489311Y34830D03*
X1490057Y85165D03*
X1490821Y73750D03*
X1524557Y88336D03*
X1520314Y78880D03*
X1517162Y78784D03*
X1519599Y86117D03*
X1491164Y82923D03*
X1519580Y81313D03*
X1499613Y84046D03*
X1515294Y91306D03*
X1523563Y93565D03*
X1511700Y84600D03*
X1499875Y86681D03*
X1526744Y93265D03*
X1513335Y92921D03*
X1499875Y90481D03*
X1524744Y133656D03*
X1513935Y120143D03*
Y108332D03*
X1513013Y96546D03*
X1514600Y126650D03*
X1482455Y124222D03*
X1474717Y110370D03*
X1473096Y120999D03*
X1468755Y128478D03*
X1482300Y118400D03*
X1468590Y131200D03*
X1475200Y142600D03*
X1476761Y152725D03*
X1469747Y148276D03*
X1483093Y130796D03*
X1489053Y103325D03*
X1489780Y105820D03*
X1524284Y112773D03*
X1511800Y127050D03*
X1513879Y113349D03*
X1518514Y130991D03*
X1526513Y120769D03*
Y103958D03*
X1526728Y124168D03*
X1518438Y100926D03*
X1490178Y112315D03*
X1518376Y111499D03*
X1523950Y104050D03*
X1523889Y99033D03*
X1523557Y116165D03*
X1523813Y120546D03*
X1523756Y108762D03*
X1501603Y108500D03*
X1499618Y124520D03*
X1497699Y112140D03*
X1511634Y121195D03*
X1511635Y114535D03*
X1511650Y109400D03*
Y103400D03*
X1511651Y98675D03*
X1500775Y98101D03*
X1501700Y103300D03*
X1513023Y140630D03*
X1511664Y133603D03*
X1488350Y149450D03*
X1523719Y149488D03*
X1488800Y145000D03*
X1502000Y147500D03*
X1492013Y155610D03*
X1495848Y150600D03*
X1496150Y148115D03*
X1511660Y138510D03*
X1513136Y157081D03*
X1515358Y151743D03*
X1513500Y153800D03*
X1500643Y154819D03*
X1496038Y154229D03*
X1503466Y142486D03*
X1510184Y142614D03*
X1505673Y146346D03*
X1490900Y146600D03*
X1500455Y110933D03*
X1496658Y115088D03*
X1472500Y123700D03*
X1473100Y131900D03*
X1473200Y118300D03*
X1514425Y134180D03*
X1524900Y139100D03*
X1484113Y128513D03*
X1500700Y127250D03*
X1498705Y99522D03*
X1483366Y120746D03*
X1493069Y152834D03*
X1473354Y153246D03*
X1485210Y134837D03*
X1513935Y104532D03*
Y116343D03*
X1524000Y123300D03*
X1490674Y98787D03*
X1498810Y108290D03*
X1526813Y108958D03*
X1526513Y115769D03*
X1500455Y114388D03*
X1496726Y120588D03*
X1473100Y128950D03*
X1514425Y137980D03*
X1526310Y142190D03*
X1485755Y131671D03*
X1500806Y133339D03*
X1526744Y98265D03*
X1483366Y115902D03*
X1498660Y102746D03*
X1520150Y127600D03*
X1500703Y158233D03*
X1507524Y218600D03*
X1510800Y193330D03*
X1512500Y199837D03*
X1492136Y199125D03*
X1479000Y207225D03*
X1512700Y205100D03*
X1497237Y217281D03*
X1519243Y191627D03*
X1513900Y218000D03*
X1478611Y209695D03*
X1478089Y182650D03*
X1511100Y186275D03*
X1499800Y199300D03*
X1491196Y218527D03*
X1523400Y217900D03*
X1483523Y181100D03*
X1517328Y186208D03*
X1475401Y210017D03*
X1515060Y192443D03*
X1487716Y218650D03*
X1470382Y188372D03*
X1472758Y216495D03*
X1510638Y166240D03*
X1468700Y163100D03*
X1476761Y157400D03*
X1471388Y173700D03*
X1496713Y174853D03*
X1527500Y167726D03*
X1502192Y164871D03*
X1494783Y177907D03*
X1493200Y162700D03*
X1488300Y161700D03*
X1497493Y162078D03*
X1492469Y179387D03*
X1494939Y159500D03*
X1492500Y176887D03*
X1489088Y176680D03*
X1488900Y172576D03*
X1489015Y179832D03*
X1516616Y205537D03*
X1512525Y208944D03*
X1516598Y203037D03*
X1516872Y208863D03*
X1504706Y164871D03*
X1488300Y158300D03*
X1477388Y172988D03*
X1473888Y173721D03*
X1474883Y182275D03*
X1492597Y172636D03*
X1474439Y207621D03*
X1527657Y278700D03*
X1470950Y252846D03*
X1469004Y246287D03*
X1467040Y260357D03*
X1470556Y256900D03*
X1468450Y252900D03*
X1472200Y243000D03*
X1469150Y242931D03*
X1479500Y238500D03*
X1499559Y231173D03*
X1498022Y221900D03*
X1498685Y224715D03*
X1491700Y241661D03*
X1478500Y252000D03*
X1479000Y254500D03*
X1477397Y256657D03*
X1484000Y257500D03*
X1496812Y273718D03*
X1491265Y226492D03*
X1519300Y245196D03*
X1491438Y221137D03*
X1523580Y237960D03*
X1509814Y247215D03*
X1509800Y244676D03*
X1503842Y245678D03*
X1499070Y255934D03*
X1499472Y250370D03*
X1504772Y259229D03*
X1507003Y272249D03*
X1504461Y274426D03*
X1521962Y278650D03*
X1526150Y234300D03*
X1479700Y224801D03*
X1482004Y222483D03*
X1497082Y277987D03*
X1474096Y256706D03*
X1483457Y244568D03*
X1495682Y255861D03*
X1493199Y255507D03*
X1484700Y251800D03*
X1487500Y244500D03*
X1495696Y258361D03*
X1492697Y267303D03*
X1475004Y246287D03*
X1492753Y273724D03*
X1499681Y279910D03*
X1512790Y240099D03*
X1516549Y234278D03*
X1486926Y247834D03*
X1491407Y258353D03*
X1523470Y242580D03*
X1470950Y229669D03*
X1471604Y246287D03*
X1516613Y240656D03*
X1498478Y233675D03*
X1520413Y239498D03*
X1482400Y248000D03*
X1474520Y251740D03*
X1525650Y248700D03*
X1502165Y251200D03*
X1505946Y254432D03*
X1500840Y319870D03*
X1517115Y330005D03*
X1470276Y330774D03*
X1468399Y324930D03*
X1470257Y321929D03*
X1466970Y320235D03*
X1472500Y341074D03*
X1526722Y295400D03*
X1501583Y339389D03*
X1521817Y330937D03*
X1526000Y341000D03*
X1517600Y320940D03*
X1487426Y330100D03*
X1514050Y327490D03*
X1526936Y307015D03*
X1473231Y320250D03*
X1516138Y310749D03*
X1487858Y340412D03*
X1484100Y330115D03*
X1499829Y341250D03*
X1482550Y333600D03*
X1482585Y340856D03*
X1493240Y325828D03*
X1520766Y341000D03*
X1505000Y340990D03*
X1484620Y339152D03*
X1510851Y340113D03*
X1513796Y330680D03*
X1497997Y338546D03*
X1504370Y330970D03*
X1518060Y317520D03*
X1525677Y311835D03*
X1510584Y330640D03*
X1492540Y328250D03*
X1516301Y313244D03*
X1527537Y330048D03*
X1525051Y329553D03*
X1487904Y337500D03*
X1482386Y336926D03*
X1483506Y326061D03*
X1514100Y321792D03*
X1514067Y315626D03*
X1493290Y287984D03*
X1526900Y292866D03*
X1496900Y293900D03*
X1493268Y293943D03*
X1496600Y281400D03*
X1493700Y281476D03*
X1508650Y287500D03*
X1496628Y288440D03*
X1499987Y288487D03*
X1518006Y286706D03*
X1501550Y293750D03*
X1514722Y293257D03*
X1515482Y280800D03*
X1512300Y280847D03*
X1511900Y287500D03*
X1472450Y337500D03*
X1472500Y334800D03*
X1471562Y325531D03*
X1487000Y333300D03*
X1523935Y318901D03*
X1497179Y306372D03*
X1499723Y300106D03*
X1505923Y309510D03*
X1505935Y306674D03*
X1508455Y313041D03*
X1503538Y318068D03*
X1495810Y341200D03*
X1495445Y338724D03*
X1496400Y336376D03*
X1512182Y293317D03*
X1498600Y334800D03*
X1473255Y372654D03*
X1507200Y356000D03*
X1502970Y350610D03*
X1520675Y394414D03*
X1470100Y392350D03*
X1472940Y384030D03*
X1467597Y363000D03*
X1470800Y395200D03*
X1469000Y345850D03*
X1472550Y397500D03*
X1470800Y402250D03*
X1472680Y380630D03*
X1473083Y393770D03*
X1489475Y387654D03*
X1514265Y355542D03*
X1495325Y391034D03*
X1493375Y387654D03*
X1495325Y377514D03*
X1524575Y394414D03*
X1520313Y357069D03*
X1520429Y354379D03*
X1525561Y350253D03*
X1498309Y360005D03*
X1511000Y350627D03*
X1481000Y350000D03*
X1478607Y359082D03*
X1498246Y352305D03*
X1478612Y361670D03*
X1498246Y354905D03*
X1507154Y353100D03*
X1524746Y356717D03*
Y354217D03*
X1516775Y380894D03*
X1526659Y397500D03*
X1524575Y380894D03*
X1522476Y361907D03*
X1522625Y377514D03*
X1483172Y351806D03*
X1474500Y365500D03*
X1478500D03*
X1483500D03*
X1482000Y395098D03*
Y399035D03*
Y383287D03*
Y387224D03*
X1473255Y376254D03*
X1528146Y349842D03*
X1519626Y365817D03*
X1488394Y365466D03*
X1497275Y401174D03*
X1508975D03*
X1483950Y401650D03*
X1491425Y391034D03*
X1503125Y377514D03*
X1491425D03*
X1507200Y358700D03*
X1498246Y357505D03*
X1518725Y397794D03*
Y391034D03*
X1512875Y401174D03*
Y394414D03*
X1514925Y358844D03*
X1489838Y350011D03*
X1484600Y394100D03*
X1483740Y359550D03*
X1524746Y359217D03*
X1495325Y384274D03*
X1483664Y362914D03*
X1520675Y401174D03*
X1516775D03*
X1515328Y363389D03*
X1516775Y387654D03*
X1478163Y354940D03*
X1483867Y356753D03*
X1526525Y377514D03*
X1514825D03*
X1526525Y384274D03*
Y391034D03*
X1514825Y384274D03*
X1520675Y387654D03*
Y380894D03*
X1514825Y391034D03*
X1508975Y387654D03*
Y380894D03*
X1503125Y384274D03*
Y391034D03*
X1497275Y380894D03*
X1491425Y384274D03*
X1497275Y387654D03*
Y394414D03*
X1491425Y397794D03*
X1503125D03*
X1508975Y394414D03*
X1514825Y397794D03*
X1524575Y401174D03*
X1507025Y391034D03*
X1489915Y352637D03*
X1498246Y362705D03*
X1501175Y394414D03*
X1499225Y391034D03*
Y384274D03*
X1493375Y394414D03*
X1489475D03*
X1488479Y362967D03*
Y360367D03*
X1496000Y350000D03*
X1488479Y357767D03*
X1466873Y397648D03*
X1469873D03*
X1468048Y402370D03*
X1505075Y380894D03*
X1517367Y349964D03*
X1472449Y439421D03*
X1467000Y454100D03*
Y459800D03*
X1466800Y449997D03*
X1470262Y420711D03*
X1467355Y432919D03*
X1469931Y432842D03*
X1467401Y411557D03*
X1471900Y406900D03*
X1472530Y432731D03*
X1472400Y428063D03*
X1472800Y420689D03*
X1467000Y465500D03*
X1524575Y463826D03*
X1491425Y411314D03*
X1487525D03*
X1518675Y451425D03*
X1516775Y457066D03*
X1512954Y407653D03*
X1524575Y407624D03*
X1518650Y416750D03*
X1499225Y411314D03*
X1501175Y407934D03*
X1515500Y413600D03*
X1528100Y413700D03*
X1512350Y410450D03*
X1521800Y419900D03*
X1501200Y450600D03*
X1505714Y448145D03*
X1501175Y443546D03*
X1503125Y446926D03*
X1505075Y457066D03*
X1524575D03*
X1524950Y445100D03*
Y448250D03*
X1521800Y445100D03*
X1528147Y454546D03*
X1509200Y410450D03*
X1485250Y408017D03*
X1497200Y421200D03*
X1505715Y441368D03*
X1506059Y429249D03*
X1505459Y421107D03*
X1503128Y419892D03*
X1512350Y423050D03*
X1518650Y426200D03*
Y423050D03*
X1515500Y426200D03*
X1482000Y418720D03*
Y406909D03*
Y410846D03*
Y414783D03*
Y422658D03*
Y426595D03*
X1483400Y438100D03*
X1482603Y442418D03*
X1482000Y462028D03*
X1483115Y454379D03*
X1483200Y450455D03*
X1482500Y434600D03*
X1503125Y404554D03*
X1509200Y413600D03*
X1510925Y404554D03*
X1497275Y414694D03*
X1503125Y424834D03*
X1497275Y428214D03*
X1495325Y424834D03*
X1503125Y433406D03*
X1491425D03*
X1495325D03*
X1524950Y419900D03*
X1518650D03*
X1483818Y430597D03*
X1528100Y410550D03*
X1501219Y416596D03*
X1487525Y404554D03*
X1526525D03*
X1515500Y416750D03*
X1518700Y406500D03*
X1491425Y404554D03*
X1495325Y411314D03*
X1512350Y445100D03*
X1509200D03*
Y454550D03*
X1491425Y446926D03*
X1515500Y423050D03*
X1524950Y426200D03*
Y423050D03*
X1509200Y416750D03*
X1512350D03*
X1505605Y423604D03*
X1509200Y423050D03*
Y419900D03*
X1515500D03*
X1512350D03*
Y426200D03*
X1509200D03*
X1515500Y429350D03*
X1518650D03*
X1509200D03*
X1512350D03*
X1518650Y438800D03*
X1515500D03*
X1512350D03*
X1505392Y437133D03*
X1509200Y438800D03*
Y441950D03*
X1512350D03*
X1515500D03*
X1524950Y438800D03*
X1509200Y435650D03*
X1518650D03*
X1515500D03*
X1512350D03*
X1524950D03*
Y429350D03*
X1505462Y434630D03*
X1505075Y407934D03*
X1524950Y413600D03*
X1497273Y407610D03*
X1512400Y454500D03*
X1503125Y440166D03*
X1501175Y436786D03*
X1495325Y440166D03*
X1497275Y436786D03*
X1510925Y460446D03*
X1505442Y443900D03*
X1507025Y460446D03*
X1503125Y453786D03*
Y460446D03*
X1501175Y457066D03*
X1487525Y453686D03*
X1497275Y457066D03*
Y450306D03*
X1495325Y446926D03*
Y453686D03*
X1497275Y443546D03*
X1501175Y463826D03*
X1493375D03*
X1515500Y445100D03*
X1514825Y460446D03*
X1520675Y457066D03*
X1518725Y460446D03*
X1521800Y441950D03*
Y448250D03*
X1526525Y460446D03*
X1522625D03*
X1524950Y441950D03*
X1485300Y443484D03*
X1483375Y458375D03*
X1525000Y416750D03*
X1516700Y409900D03*
X1518650Y413600D03*
X1501175Y428214D03*
X1499225Y424834D03*
X1516775Y463826D03*
X1487525Y440166D03*
X1491425D03*
X1489475Y443546D03*
X1487500Y424600D03*
X1491400D03*
X1470106Y412152D03*
X1472688Y412055D03*
X1467290Y428013D03*
X1469900D03*
X1469400Y449997D03*
X1472000D03*
X1469382Y406773D03*
X1493375Y450306D03*
X1489475Y428214D03*
Y436786D03*
X1491425Y460446D03*
X1489475Y450306D03*
X1491425Y453686D03*
X1493375Y457066D03*
X1495325Y460446D03*
X1497275Y463826D03*
X1485030Y463690D03*
X1489475Y463826D03*
X1508975Y457066D03*
X1515389Y451400D03*
X1521800D03*
X1518650Y448250D03*
X1467262Y420711D03*
X1470643Y495299D03*
X1473140Y525407D03*
X1482200Y477800D03*
X1482958Y486118D03*
X1485100Y469900D03*
X1482000Y481713D03*
Y469902D03*
X1476800Y498900D03*
X1482300D03*
X1476800Y507300D03*
X1481700Y524200D03*
X1473800Y495800D03*
X1499225Y480726D03*
X1508975Y477346D03*
X1510925Y480726D03*
X1508975Y470586D03*
X1510925Y473966D03*
X1505075Y470586D03*
X1501175D03*
X1503125Y467206D03*
X1507025Y487486D03*
X1487525Y473966D03*
X1491425D03*
X1489475Y470586D03*
X1490100Y489700D03*
X1487525Y487486D03*
X1489475Y484106D03*
X1516775D03*
X1514825Y480726D03*
Y473966D03*
X1516775Y470586D03*
X1518725Y487486D03*
Y480726D03*
Y473966D03*
Y467206D03*
X1522625D03*
Y473966D03*
Y487486D03*
X1526525D03*
Y473966D03*
Y467206D03*
X1514825Y487486D03*
X1511752Y498780D03*
X1490929Y507104D03*
X1506060Y508180D03*
X1501490Y504988D03*
X1501934Y513047D03*
X1505743Y516117D03*
X1511215Y507781D03*
X1512400Y519020D03*
X1493930Y522800D03*
X1488410Y517810D03*
X1497267Y505323D03*
X1496174Y514221D03*
X1509000Y498750D03*
X1488500Y498900D03*
X1526500Y498671D03*
Y506400D03*
X1485300Y498962D03*
X1483804Y509928D03*
X1484200Y524200D03*
X1524575Y470586D03*
X1484200Y515700D03*
X1481700D03*
X1475316Y527194D03*
X1472250Y485100D03*
X1472500Y509810D03*
X1501175Y477346D03*
X1493375D03*
X1505075Y484106D03*
X1501175D03*
X1497275Y470586D03*
X1495325Y467206D03*
X1526500Y503800D03*
Y501300D03*
X1507025Y480726D03*
X1495325D03*
X1503125D03*
X1508975Y484106D03*
X1507025Y473966D03*
X1503125D03*
X1493375Y470586D03*
X1499225Y487486D03*
X1497275Y484106D03*
X1493375D03*
X1499225Y473966D03*
X1495325Y487486D03*
X1512875Y484106D03*
X1510925Y487486D03*
X1497275Y477346D03*
X1489475D03*
X1491425Y467206D03*
X1505075Y477346D03*
X1511126Y503038D03*
X1500655Y516122D03*
X1488293Y508000D03*
X1481975Y507975D03*
X1474400Y517200D03*
X1508626Y503038D03*
X1506985Y510645D03*
X1510005Y518155D03*
X1498277Y508239D03*
X1490100Y520000D03*
X1485693Y508000D03*
X1479375Y507975D03*
X1503400Y524663D03*
X1507405Y518155D03*
X1498055Y516122D03*
X1509585Y510645D03*
X1500877Y508239D03*
X1492700Y520000D03*
X1468101Y573963D03*
X1468649Y570012D03*
X1481200Y531200D03*
X1483700D03*
X1527698Y578870D03*
X1474776Y572315D03*
X1491776Y573571D03*
X1479893Y572315D03*
X1482293D03*
X1477493D03*
X1487093D03*
X1489493D03*
X1484693D03*
X1518000Y562330D03*
X1510740Y557860D03*
X1494422Y574000D03*
X1481400Y539700D03*
X1494200Y530600D03*
X1497106Y531368D03*
X1511388Y531045D03*
X1503200Y530500D03*
X1505600D03*
X1508772Y530416D03*
X1514118Y530411D03*
X1483900Y539700D03*
X1525500Y582674D03*
Y580184D03*
X1525837Y574700D03*
X1523416Y573949D03*
X1527822Y576130D03*
X1525500Y577684D03*
X1499900Y574000D03*
X1496900D03*
X1489380Y546030D03*
X1478700Y533700D03*
X1469701Y599554D03*
X1469301Y607790D03*
X1467839Y618964D03*
X1469200Y610739D03*
X1470356Y618000D03*
X1470353Y592128D03*
X1469767Y596353D03*
X1480975Y620100D03*
X1516400Y619800D03*
X1504700Y608500D03*
X1500445Y619956D03*
X1492750Y615903D03*
X1494100Y613280D03*
X1497800Y610000D03*
X1497097Y613043D03*
X1483279Y619100D03*
X1505679Y620111D03*
X1511204Y620056D03*
X1475883Y619217D03*
X1503008Y620018D03*
X1472412Y596032D03*
Y599532D03*
X1479029Y596132D03*
X1477129Y597656D03*
X1474912Y596032D03*
X1480760Y611602D03*
X1485429Y597571D03*
X1491412Y596032D03*
X1489229Y597571D03*
X1487329Y596032D03*
X1512500Y598639D03*
X1510450Y597300D03*
X1507950D03*
X1510450Y600800D03*
X1508031Y599922D03*
X1524800Y598778D03*
X1522900Y597300D03*
X1526950D03*
X1518800Y597200D03*
X1520813Y598508D03*
X1516800Y598639D03*
X1514500Y597300D03*
X1527050Y613000D03*
X1523450Y612900D03*
X1519850Y613000D03*
X1487912Y611632D03*
X1491512Y611732D03*
X1484312D03*
X1511350Y613000D03*
X1513867Y612939D03*
X1516367D03*
X1475812Y611732D03*
X1474912Y599532D03*
X1478329Y611671D03*
X1483104Y596072D03*
X1481229Y597571D03*
X1472932Y619131D03*
X1504700Y611100D03*
X1518900Y619800D03*
X1508550Y619810D03*
X1513700Y619900D03*
X1478500Y619300D03*
X1549334Y23856D03*
X1538520Y11911D03*
X1584447Y-6702D03*
X1584000Y-16100D03*
X1581947Y-6702D03*
X1530800Y3500D03*
X1534000D03*
X1546800Y3400D03*
X1580398Y5400D03*
X1586500Y-16100D03*
X1580398Y-600D03*
X1579447Y-6702D03*
X1549800Y3400D03*
X1554800D03*
X1560500D03*
X1569000D03*
X1566000D03*
X1567498Y12506D03*
X1577048D03*
X1586998Y11355D03*
X1589623Y24528D03*
X1570200Y12900D03*
X1579773Y13257D03*
X1589259Y10241D03*
X1545111Y24172D03*
X1540000Y3400D03*
X1541400Y12500D03*
X1528384Y28040D03*
X1552300Y3400D03*
X1558000D03*
X1544882Y-6900D03*
X1549600Y-10800D03*
X1551309Y12792D03*
X1560700Y13000D03*
X1551834Y23856D03*
X1554434D03*
X1548698Y12506D03*
X1558148Y12306D03*
X1589500Y-600D03*
X1571500Y-1406D03*
X1573048Y12506D03*
X1581998Y11355D03*
X1554148Y12306D03*
X1563498Y12506D03*
X1544698D03*
X1563200Y3400D03*
X1543500D03*
X1588962Y75926D03*
X1575959Y84198D03*
X1584748Y70840D03*
X1572586Y95639D03*
X1587359Y84348D03*
X1579807Y75841D03*
X1582407D03*
X1570511Y75396D03*
X1573076Y75328D03*
X1573060Y84120D03*
X1589900Y84422D03*
X1583621Y87213D03*
X1588700Y94288D03*
X1573473Y37216D03*
X1582923D03*
X1587734Y70974D03*
X1583374Y81319D03*
X1575018Y71213D03*
X1579100Y69000D03*
X1574780Y90992D03*
X1535300Y78490D03*
X1562850Y73642D03*
X1541520Y79387D03*
X1538870Y78980D03*
X1532800Y78590D03*
X1562575Y76231D03*
X1556810Y71760D03*
X1542179Y39695D03*
X1545572Y38188D03*
X1541988Y90207D03*
Y92707D03*
X1541670Y87760D03*
X1554573Y37216D03*
X1564023D03*
X1544180Y91660D03*
X1546370Y84180D03*
X1545250Y88360D03*
X1556200Y94800D03*
X1577269Y95344D03*
X1529449Y137408D03*
X1557981Y141470D03*
X1572395Y110754D03*
X1574000Y149500D03*
Y152100D03*
X1572634Y98546D03*
X1576506Y143416D03*
X1574197Y127915D03*
X1588000Y100500D03*
X1588500Y106788D03*
X1567968Y136682D03*
X1567981Y139607D03*
X1579310Y128604D03*
X1576606Y104392D03*
X1579290Y131104D03*
X1573153Y103721D03*
X1577770Y149519D03*
X1577950Y152600D03*
X1589622Y112876D03*
X1577700Y155353D03*
Y140149D03*
X1567520Y133354D03*
X1589200Y121800D03*
X1589880Y134851D03*
X1582500Y109900D03*
X1587620Y135921D03*
X1580275Y101041D03*
X1578000Y113000D03*
X1585500Y101000D03*
X1553353Y124209D03*
X1553500Y157000D03*
X1552171Y133000D03*
X1555000Y139000D03*
X1549000Y115571D03*
X1542000Y126246D03*
X1549187Y104713D03*
X1542100Y119200D03*
X1542900Y121700D03*
X1531700Y155600D03*
X1541421Y106742D03*
X1541800Y99700D03*
X1541900Y97300D03*
X1541413Y155259D03*
X1541434Y139871D03*
X1531678Y135284D03*
X1541390Y136498D03*
X1558136Y100877D03*
X1554627D03*
X1553500Y121000D03*
X1548955Y101358D03*
X1558189Y107067D03*
X1554800Y129100D03*
Y98200D03*
X1558100D03*
X1558383Y121500D03*
X1554945Y133400D03*
X1531726Y123800D03*
X1563108Y126423D03*
X1541351Y151900D03*
X1558100Y138025D03*
Y133526D03*
Y124427D03*
Y128926D03*
X1531985Y147000D03*
X1532923Y144518D03*
X1542685Y133321D03*
X1555676Y123283D03*
X1573121Y120649D03*
X1530101Y132671D03*
X1541765Y114000D03*
X1541831Y149030D03*
X1583600Y207495D03*
X1566486Y181270D03*
X1583874Y217746D03*
X1582249Y191716D03*
X1587549Y192000D03*
X1566858Y175192D03*
X1570294Y167384D03*
X1572817Y169910D03*
X1568488Y164058D03*
X1571501Y180031D03*
X1553500Y165400D03*
X1557787Y192236D03*
X1561925Y192675D03*
X1558000Y205100D03*
X1557979Y188844D03*
X1535000Y207200D03*
X1535425Y188016D03*
X1535399Y190920D03*
X1552063Y202031D03*
X1549693Y196707D03*
X1548178Y190880D03*
X1545910Y199977D03*
X1546000Y197400D03*
X1543100Y184128D03*
X1533132Y158068D03*
X1531565Y176645D03*
X1537298Y162703D03*
X1535065Y164300D03*
X1561538Y174649D03*
X1545023Y161675D03*
X1562150Y160700D03*
X1557634Y175948D03*
X1562079Y163580D03*
X1552051Y172053D03*
X1558042Y172448D03*
X1567000Y259560D03*
X1568120Y251710D03*
X1574560Y237660D03*
X1571876Y255800D03*
X1570272Y234889D03*
X1572730Y235931D03*
X1586950Y251267D03*
X1570318Y238116D03*
X1572700Y239400D03*
X1568365Y247761D03*
X1589592Y252472D03*
X1582699Y252646D03*
X1579867Y265445D03*
X1530200Y257200D03*
X1531935Y224160D03*
X1533596Y273504D03*
X1532237Y247801D03*
X1528460Y244371D03*
X1537972Y236000D03*
X1542690Y236050D03*
X1541325Y245090D03*
X1547869Y243356D03*
X1547375Y245850D03*
X1542751Y240477D03*
X1563157Y258164D03*
X1561104Y234255D03*
X1563440Y250955D03*
X1559577Y236300D03*
X1558700Y252000D03*
X1574900Y240900D03*
X1547000Y263500D03*
Y269400D03*
X1541000Y263500D03*
Y269500D03*
X1544000Y266500D03*
X1545802Y233529D03*
X1584568Y281339D03*
X1589476Y322953D03*
X1565235Y303734D03*
X1578630Y293430D03*
X1572336Y287063D03*
X1578790Y290920D03*
X1581077Y284825D03*
X1578577Y284799D03*
X1565000Y290500D03*
X1571293Y284755D03*
X1573790Y284895D03*
X1580365Y341293D03*
X1577486Y307621D03*
X1566000Y341000D03*
X1587800Y308200D03*
X1580150Y329483D03*
X1581090Y338795D03*
X1569211Y331542D03*
Y334142D03*
X1569926Y308064D03*
X1566910Y315117D03*
X1581940Y295820D03*
X1588551Y341410D03*
X1583794Y338767D03*
X1581834Y318591D03*
X1583500Y303120D03*
Y300560D03*
X1573950Y338050D03*
X1585479Y316610D03*
X1582859Y341112D03*
X1570574Y341776D03*
X1528250Y311900D03*
X1530033Y340799D03*
X1533228Y325000D03*
X1529734Y319714D03*
X1532850Y303950D03*
X1530500Y287700D03*
X1537500Y292800D03*
X1533914Y286073D03*
X1533838Y288706D03*
X1554932Y332171D03*
X1560024Y331800D03*
X1564427Y311083D03*
X1548334Y325497D03*
X1548273Y313227D03*
X1543864Y311399D03*
X1551250Y320303D03*
X1547398Y333823D03*
X1554775Y295328D03*
X1560024Y329200D03*
X1536027Y305048D03*
X1534833Y309798D03*
X1539400Y320200D03*
X1544904Y334008D03*
X1557250Y315410D03*
X1551404Y309376D03*
X1560400Y307683D03*
X1550619Y303087D03*
X1559997Y310317D03*
X1534400Y296029D03*
X1564411Y315210D03*
X1538450Y314300D03*
X1543700Y322600D03*
X1563000Y341000D03*
X1538206Y303741D03*
X1542200Y324600D03*
X1548024Y322145D03*
X1548000Y331361D03*
X1546612Y287812D03*
X1559500Y290300D03*
X1559800Y285300D03*
X1548199Y285830D03*
X1552900Y281700D03*
X1554800Y290600D03*
X1548100Y342200D03*
X1538406Y330157D03*
X1554800Y341100D03*
X1557550D03*
X1547882Y318942D03*
X1550800Y296200D03*
X1549000Y316600D03*
X1575645Y320664D03*
X1565244Y300934D03*
X1568524Y312885D03*
X1582800Y312100D03*
X1564400Y308383D03*
X1586400Y392900D03*
X1567475Y380894D03*
Y387654D03*
X1582420Y377830D03*
X1582350Y374567D03*
X1582124Y381164D03*
X1573000Y391161D03*
X1571366Y401154D03*
X1582000Y396250D03*
X1567475Y394414D03*
X1570672Y362134D03*
X1567121Y365817D03*
X1576380Y362890D03*
X1582500Y369600D03*
X1573521Y365500D03*
X1571375Y394414D03*
X1565525Y377514D03*
X1567121Y363217D03*
X1566922Y359681D03*
X1567475Y401174D03*
X1576074Y359600D03*
X1582600Y389300D03*
X1571450Y359650D03*
X1565525Y391034D03*
X1570289Y384368D03*
X1585150Y397400D03*
X1571585Y382230D03*
X1586500Y354900D03*
X1589100Y358400D03*
X1569425Y391034D03*
Y397794D03*
X1587683Y397414D03*
X1571375Y387654D03*
X1569584Y378002D03*
X1581822Y365770D03*
X1587968Y403368D03*
X1530425Y384274D03*
X1533719Y362783D03*
X1533790Y360283D03*
X1528475Y380894D03*
X1529829Y362655D03*
X1530425Y391034D03*
Y397794D03*
X1532375Y401174D03*
Y380894D03*
Y387654D03*
Y394414D03*
X1533589Y366361D03*
X1532367Y356530D03*
X1553825Y391034D03*
X1546025D03*
X1563575Y394414D03*
X1557725Y397794D03*
X1550639Y350200D03*
X1563575Y401174D03*
X1538200Y364700D03*
X1553825Y397794D03*
X1546025D03*
X1538500Y359363D03*
X1552500Y358500D03*
X1557725Y377514D03*
X1538397Y361861D03*
X1538478Y350694D03*
Y353294D03*
Y355894D03*
X1559675Y401174D03*
X1542125Y397794D03*
X1558950Y363050D03*
X1547975Y394414D03*
X1542932Y355740D03*
X1547975Y387654D03*
X1536275D03*
Y380894D03*
X1534325Y391034D03*
X1559675Y387654D03*
Y394414D03*
X1551875Y380894D03*
X1557725Y391034D03*
X1536275Y394414D03*
X1558980Y360130D03*
X1538225Y377514D03*
Y384274D03*
X1544075Y380894D03*
Y387654D03*
X1538225Y391034D03*
Y397794D03*
X1544075Y394414D03*
X1558996Y365817D03*
X1555775Y394414D03*
X1549925Y397794D03*
X1561625D03*
X1555775Y401174D03*
X1549925Y377514D03*
X1561625D03*
Y391034D03*
Y384274D03*
X1549925Y391034D03*
Y384274D03*
X1555775Y387654D03*
Y380894D03*
X1560500Y350000D03*
X1557534Y353400D03*
X1553825Y377514D03*
X1543300Y360900D03*
X1543528Y352446D03*
X1546182Y355446D03*
X1543528Y349946D03*
X1543300Y363400D03*
X1550417Y362607D03*
X1586500Y358400D03*
X1587684Y362653D03*
X1587032Y350996D03*
X1580370Y462090D03*
X1584200Y462610D03*
X1557725Y424834D03*
X1569425Y440166D03*
X1587559Y423835D03*
X1567475Y436786D03*
X1588870Y440546D03*
X1571375Y443546D03*
X1588632Y452151D03*
X1587550Y456550D03*
X1585920Y452368D03*
X1587573Y445300D03*
X1587000Y411976D03*
X1571375Y436786D03*
X1589500Y412035D03*
X1583208Y404941D03*
X1569425Y446926D03*
X1584233Y427947D03*
X1565525Y411314D03*
X1583773Y436137D03*
X1585560Y421324D03*
X1581939Y426594D03*
X1583208Y452185D03*
X1569425Y453686D03*
X1589396Y425674D03*
X1567475Y450306D03*
X1565525Y440166D03*
X1571375Y457066D03*
X1567475D03*
X1569425Y460446D03*
X1582200Y456200D03*
X1565525Y431594D03*
X1569425D03*
Y404554D03*
X1583208Y412815D03*
X1584975Y460210D03*
X1587475D03*
X1582200Y460310D03*
X1569425Y424834D03*
Y411314D03*
X1567475Y407934D03*
X1582300Y446100D03*
X1571390Y464480D03*
X1587238Y432593D03*
X1583208Y416752D03*
X1567475Y421454D03*
X1532375Y463826D03*
Y407934D03*
X1531250Y445100D03*
Y448250D03*
X1528475Y457066D03*
X1532349Y455200D03*
X1531250Y419900D03*
Y451400D03*
Y426200D03*
Y429350D03*
Y423050D03*
Y438800D03*
Y435650D03*
Y441950D03*
X1530425Y460446D03*
X1528475Y407934D03*
X1551875D03*
Y414694D03*
X1563575Y407934D03*
X1559675Y414694D03*
X1546025Y404554D03*
X1561625Y424834D03*
X1551990Y421158D03*
X1551875Y428214D03*
X1561625Y431594D03*
X1563575Y428214D03*
X1555775Y443546D03*
Y436786D03*
X1563575Y457066D03*
X1549938Y453714D03*
X1547975Y457066D03*
X1549925Y446926D03*
X1557725D03*
X1561625Y460446D03*
X1555775Y457066D03*
X1551875D03*
X1557725Y453686D03*
X1559675Y443546D03*
Y436786D03*
X1547975Y463826D03*
X1551875D03*
X1555775D03*
X1538225Y460446D03*
X1559675Y407934D03*
X1561625Y446926D03*
X1543850Y416750D03*
Y413600D03*
X1540700Y416750D03*
X1534400D03*
X1537550D03*
X1551875Y450306D03*
X1534400Y413500D03*
X1549950Y404490D03*
X1544075Y463826D03*
X1537550Y413600D03*
X1536275Y407934D03*
X1540175D03*
X1540700Y413600D03*
X1543850Y445100D03*
Y451400D03*
X1549926Y411312D03*
X1553825Y411314D03*
X1544150Y409900D03*
X1553825Y446926D03*
Y440166D03*
X1555775Y414694D03*
X1561625Y418074D03*
X1540700Y445100D03*
X1537550Y448250D03*
X1534400D03*
X1540700D03*
X1537550Y445100D03*
X1534400D03*
X1540700Y435650D03*
X1547754Y430351D03*
X1547755Y423570D03*
X1547754Y427884D03*
X1553825Y453686D03*
X1547000Y435650D03*
X1549925Y431594D03*
X1547755Y421138D03*
X1549925Y440166D03*
X1543950Y438800D03*
X1543850Y441950D03*
X1549964Y424753D03*
X1551875Y436786D03*
X1540653Y454588D03*
X1540700Y423050D03*
X1537550Y429350D03*
X1540700D03*
X1534400Y426200D03*
X1537550D03*
X1540700D03*
X1534400Y429350D03*
Y423050D03*
X1537550D03*
X1534400Y438800D03*
Y435650D03*
X1549925Y460446D03*
X1559595Y450631D03*
X1547000Y416750D03*
X1557725Y404554D03*
X1563575Y414694D03*
X1559675Y457066D03*
X1534400Y419900D03*
X1540700D03*
X1543850Y429350D03*
Y426200D03*
X1537550Y419900D03*
X1534325Y404554D03*
X1538225D03*
X1542125D03*
X1540700Y410450D03*
X1534400Y451400D03*
Y441950D03*
X1537550D03*
X1534325Y460446D03*
X1537550Y451400D03*
X1544075Y457066D03*
X1540175D03*
X1540700Y451400D03*
Y441950D03*
X1540175Y463826D03*
X1543850Y435650D03*
X1537550D03*
Y438800D03*
X1540700D03*
X1536300Y455200D03*
X1553825Y418074D03*
X1559675Y421454D03*
X1555775D03*
X1582644Y495077D03*
X1568600Y494500D03*
X1565210Y509160D03*
X1567817Y499735D03*
X1569425Y473966D03*
X1571375Y470586D03*
X1565525Y480726D03*
X1570062Y487039D03*
X1587970Y472370D03*
X1587433Y490425D03*
X1567475Y470586D03*
X1584970Y472370D03*
X1589025Y495975D03*
X1568400Y503300D03*
X1567475Y484106D03*
X1565525Y487486D03*
X1569425Y480726D03*
X1531685Y499540D03*
Y502040D03*
X1532375Y470586D03*
X1530425Y473966D03*
X1528475Y470586D03*
Y477346D03*
X1534180Y498580D03*
X1534039Y502906D03*
X1531580Y510790D03*
X1534020Y511930D03*
X1533595Y505530D03*
Y509030D03*
X1534325Y467206D03*
X1538225D03*
X1542125D03*
X1540175Y470586D03*
X1555510Y501975D03*
Y499475D03*
X1555438Y507217D03*
Y509717D03*
X1565000Y506329D03*
Y503329D03*
X1534325Y487486D03*
X1536275Y484106D03*
X1544075Y470586D03*
X1542125Y473966D03*
X1540175Y477346D03*
X1536275Y470586D03*
X1544075Y477346D03*
X1538225Y473966D03*
X1542475Y504400D03*
X1542425Y512200D03*
X1546025Y467206D03*
X1553825Y487486D03*
Y480726D03*
X1557725D03*
X1549925Y473966D03*
X1547975Y470586D03*
X1553825Y473966D03*
Y467206D03*
X1555775Y470586D03*
X1557725Y473966D03*
X1555775Y477346D03*
Y484106D03*
X1549925Y487486D03*
X1546025Y480726D03*
X1548300Y499000D03*
X1564600Y500414D03*
X1555424Y504609D03*
X1555832Y512288D03*
X1548300Y506600D03*
X1544075Y484106D03*
X1542125Y480726D03*
X1538225Y487486D03*
X1546025D03*
X1540175Y484106D03*
X1542125Y487486D03*
X1551875Y477346D03*
X1548300Y504000D03*
X1563575Y477346D03*
X1542475Y507000D03*
Y499400D03*
X1548300Y509200D03*
X1538225Y480726D03*
X1534325D03*
X1528475Y484106D03*
X1532375D03*
Y477346D03*
X1547975D03*
X1546025Y473966D03*
X1548300Y501500D03*
X1542475Y501900D03*
Y509600D03*
X1548300Y511800D03*
X1565389Y585721D03*
X1581730Y537170D03*
X1587610Y579550D03*
X1580360Y565524D03*
X1580400Y568000D03*
X1580300Y563000D03*
Y560500D03*
X1566000Y575820D03*
X1565940Y573120D03*
X1565800Y570600D03*
X1565600Y568100D03*
Y565700D03*
X1529944Y574725D03*
X1529894Y577342D03*
X1532354Y577283D03*
X1532642Y579853D03*
X1529600Y582300D03*
X1532400D03*
X1529942Y579853D03*
X1563800Y564100D03*
X1561300Y564000D03*
X1558800Y563900D03*
X1563448Y566766D03*
X1563432Y569340D03*
X1545200Y585724D03*
X1542600D03*
X1550990Y586588D03*
X1554358Y587258D03*
X1589604Y585896D03*
X1581704D03*
X1585155Y538574D03*
X1586700Y620100D03*
X1587679Y596867D03*
X1585179Y596902D03*
X1579900Y606050D03*
X1587504Y605496D03*
Y607996D03*
X1573260Y601600D03*
X1570660Y601563D03*
X1566520Y623382D03*
X1569495Y623365D03*
X1572950Y593950D03*
X1573500Y619500D03*
X1529067Y615784D03*
X1529697Y613384D03*
X1532270Y610764D03*
X1532160Y613408D03*
X1546075Y618145D03*
X1544050Y615296D03*
X1534968Y597268D03*
X1535565Y591658D03*
X1560747Y623576D03*
X1557575Y623559D03*
X1541162Y607903D03*
X1543697Y606719D03*
X1563827Y621376D03*
X1554800Y620910D03*
X1537711Y613397D03*
X1538679Y615641D03*
X1534928Y610532D03*
X1538337Y601097D03*
X1534948Y613302D03*
X1545000Y591100D03*
X1540477Y620308D03*
X1540700Y613700D03*
X1552198Y623479D03*
X1553000Y591100D03*
X1541384Y601262D03*
X1581704Y590196D03*
X1589604D03*
X1558800Y599300D03*
X1560400Y611600D03*
X1564300Y599400D03*
X1564400Y605500D03*
X1561700Y602200D03*
X1552400Y607600D03*
X1554900Y607100D03*
X1556200Y602400D03*
X1554400Y599300D03*
X1564300Y611500D03*
X1577000Y619500D03*
X1545407Y604713D03*
X1555600Y591100D03*
X1579680Y610279D03*
X1545407Y598393D03*
X1595004Y-17346D03*
X1598602Y3437D03*
X1605500Y-3600D03*
X1592453Y8502D03*
X1610004Y-17346D03*
X1623900Y4600D03*
X1605004Y-17346D03*
X1600004D03*
X1602504D03*
X1608500Y-3600D03*
X1592829Y24460D03*
X1597800Y24300D03*
X1646200Y5300D03*
X1646400Y13400D03*
X1637482Y21623D03*
X1638550Y7200D03*
X1597700Y9000D03*
X1595848Y11406D03*
X1617000Y9500D03*
X1617500Y-14500D03*
X1601650Y24160D03*
X1597504Y-17346D03*
X1615000Y12000D03*
X1634200Y9700D03*
X1627500Y11700D03*
X1608123Y13302D03*
X1619100Y6500D03*
X1626400Y4600D03*
X1606700D03*
X1636500D03*
X1607504Y-17346D03*
X1601102Y-600D03*
X1590431Y-6702D03*
X1598602Y-600D03*
X1591848Y11406D03*
X1648748Y6325D03*
X1638865Y11105D03*
X1629148Y6825D03*
X1619798Y10755D03*
X1643865Y11105D03*
X1634148Y6825D03*
X1624798Y10755D03*
X1600898Y11355D03*
X1609833Y5425D03*
X1605898Y11355D03*
X1614833Y5425D03*
X1592715Y70817D03*
X1591600Y75700D03*
X1593000Y78140D03*
X1591270Y93940D03*
X1592200Y37700D03*
X1590464Y77962D03*
X1637700Y67400D03*
X1640900Y66900D03*
X1650876Y65237D03*
X1648276Y65221D03*
X1651250Y36750D03*
X1639623Y38100D03*
X1649073Y38200D03*
X1649900Y78600D03*
X1620050Y35550D03*
X1608500Y72688D03*
X1615115Y70786D03*
X1612000Y70984D03*
X1635337Y73500D03*
X1619000Y38500D03*
X1599000Y61500D03*
X1620900Y81300D03*
X1632000Y73500D03*
X1627489Y74960D03*
X1630386Y41448D03*
X1651298Y39462D03*
X1641848D03*
X1632398Y39862D03*
X1602000Y84500D03*
X1596900D03*
X1620733Y74847D03*
X1623200Y75800D03*
X1606797Y64949D03*
X1608452Y62890D03*
X1599500Y75000D03*
X1606579Y86726D03*
X1599500Y84500D03*
X1614169Y95004D03*
X1617347Y94581D03*
X1597867Y93900D03*
X1614997Y84403D03*
X1596050Y75400D03*
X1606730Y84230D03*
X1632000Y83000D03*
X1625451Y84288D03*
X1605184Y61044D03*
X1610450Y37300D03*
X1627380Y36652D03*
X1630121Y37609D03*
X1595943Y71522D03*
X1603138Y65890D03*
X1602840Y37382D03*
X1635900Y83000D03*
X1625075Y80182D03*
X1610853Y63861D03*
X1622635Y39900D03*
X1646848Y39462D03*
X1637398Y39862D03*
X1627715Y39934D03*
X1632006Y94500D03*
X1643500Y80400D03*
X1621100Y69600D03*
X1597987Y79500D03*
X1630826Y88087D03*
X1593241Y134295D03*
X1628788Y97800D03*
X1593756Y129048D03*
X1590800Y137800D03*
X1593500D03*
X1590949Y97850D03*
X1595335Y98135D03*
X1641600Y96500D03*
X1638500D03*
X1595522Y127278D03*
X1648000Y100597D03*
X1598449Y120760D03*
X1598300Y116477D03*
X1632020Y97871D03*
X1600000Y104243D03*
X1594452Y111377D03*
X1630836Y197560D03*
X1637870Y197577D03*
X1590525Y217033D03*
X1590495Y214525D03*
X1593020Y215129D03*
X1593218Y191776D03*
X1592870Y217900D03*
X1595291Y166423D03*
X1591800Y164900D03*
X1626935Y217775D03*
X1598006Y192421D03*
X1611761Y216250D03*
X1651000Y178628D03*
X1645700Y214050D03*
X1650600Y186300D03*
X1648349Y182276D03*
X1650300Y195251D03*
X1648400Y214100D03*
X1643887Y181841D03*
X1642457Y186948D03*
X1637870Y195077D03*
X1644290Y196383D03*
X1634069Y197454D03*
X1604401Y213500D03*
X1618500Y181680D03*
X1625524Y184531D03*
X1635100Y182800D03*
X1620036Y196186D03*
X1635112Y195181D03*
X1605250Y197250D03*
X1629595Y217725D03*
X1627326Y182759D03*
X1613053Y184949D03*
X1610554Y184877D03*
X1615362Y213507D03*
X1615553Y184908D03*
X1611761Y213507D03*
X1602185Y180709D03*
X1628950Y195344D03*
X1632590D03*
X1635351Y185444D03*
X1619500Y184944D03*
X1622248Y185060D03*
X1644433Y185415D03*
X1641800Y184400D03*
X1614000Y177800D03*
X1598950Y180300D03*
X1595800D03*
X1608056Y184771D03*
X1603300Y185100D03*
X1639258Y185620D03*
X1647852Y197374D03*
X1635621Y208259D03*
X1604222Y268107D03*
X1627177Y260267D03*
X1637281Y254322D03*
X1636684Y279815D03*
X1591865Y237407D03*
X1591174Y225017D03*
X1627024Y253387D03*
X1627043Y256900D03*
X1638216Y246021D03*
X1636684Y274815D03*
X1637269Y264421D03*
X1637281Y260922D03*
X1636914Y270900D03*
X1643106Y233913D03*
X1640871Y235210D03*
X1596600Y246350D03*
X1596300Y250320D03*
X1608489Y252095D03*
X1601870Y270470D03*
X1626124Y225250D03*
X1599270Y246310D03*
X1600810Y266006D03*
X1609051Y243415D03*
X1624798Y241937D03*
X1631300Y280400D03*
X1626291Y273309D03*
X1597201Y238188D03*
X1621164Y223392D03*
X1620250Y254741D03*
X1621164Y225910D03*
X1620240Y257660D03*
X1617498Y273433D03*
X1628624Y225318D03*
X1598028Y256422D03*
X1610290Y265352D03*
X1600552Y261281D03*
X1636684Y277315D03*
X1623447Y273273D03*
X1606849Y241210D03*
X1643775Y246137D03*
X1632128Y225472D03*
X1622000Y279495D03*
X1639413Y310235D03*
X1592110Y322002D03*
X1590176Y331844D03*
X1590212Y315425D03*
X1636800Y287956D03*
X1636922Y302588D03*
X1636861Y305091D03*
X1639040Y316343D03*
X1638086Y319664D03*
X1619897Y338636D03*
Y336136D03*
X1631015Y328350D03*
X1619897Y341136D03*
X1635355Y324228D03*
X1609172Y339630D03*
X1602776Y331304D03*
X1625846Y286154D03*
X1638063Y326504D03*
X1636822Y294946D03*
X1639413Y312735D03*
X1636925Y297444D03*
X1636822Y292446D03*
X1642712Y342347D03*
X1636684Y283141D03*
X1635503Y340146D03*
X1629503D03*
X1620159Y332004D03*
X1625400Y327667D03*
X1608764Y322440D03*
X1630200Y367730D03*
X1630900Y375600D03*
X1622100Y400600D03*
X1603307Y393224D03*
X1591912Y391052D03*
X1590218Y350995D03*
X1642443Y344879D03*
X1638991Y352037D03*
X1640001Y370790D03*
X1650624Y357884D03*
X1650480Y368215D03*
X1642126Y357894D03*
X1642114Y368142D03*
X1601060Y401010D03*
X1599100Y399100D03*
X1610828Y381387D03*
X1596151D03*
X1596168Y375135D03*
X1609761Y372584D03*
X1608146Y380322D03*
Y376171D03*
X1630300Y395300D03*
X1630408Y357603D03*
X1630550Y401300D03*
X1630534Y354900D03*
X1630476Y360103D03*
X1630400Y398700D03*
X1629300Y385400D03*
X1630240Y365099D03*
X1630400Y391800D03*
X1597900Y370000D03*
X1597850Y367329D03*
X1643150Y348692D03*
X1643700Y351667D03*
X1630337Y362600D03*
X1621727Y395374D03*
X1613474Y391105D03*
X1609271Y348166D03*
X1608850Y343835D03*
X1613452Y387098D03*
X1610140Y358350D03*
X1610370Y361890D03*
X1607412Y360895D03*
X1602215Y363981D03*
X1630000Y381400D03*
X1620447Y373926D03*
X1610642Y375135D03*
X1608020Y356500D03*
X1619889Y352841D03*
X1607443Y398649D03*
X1598878Y380344D03*
X1629503Y346146D03*
X1635503Y346046D03*
X1632503Y343146D03*
X1598878Y376346D03*
X1621800Y386300D03*
Y381500D03*
X1630800Y378500D03*
X1640266Y365500D03*
Y360500D03*
X1590154Y354762D03*
X1630120Y418887D03*
X1595800Y405900D03*
X1621000Y452000D03*
X1612500Y411800D03*
X1618800Y453400D03*
X1595200Y412700D03*
X1617900Y409900D03*
X1630750Y404800D03*
X1591446Y440472D03*
X1591344Y452134D03*
X1591430Y409440D03*
X1591350Y445300D03*
X1593400Y432200D03*
X1639500Y435700D03*
X1640625Y429460D03*
X1640000Y456900D03*
X1640100Y459700D03*
X1630200Y457175D03*
X1630300Y452100D03*
X1630150Y427663D03*
X1611642Y461877D03*
X1600400Y446100D03*
X1630219Y446000D03*
X1621000Y440500D03*
X1621044Y433364D03*
X1612250Y432500D03*
X1611418Y422971D03*
X1621182Y427091D03*
X1621347Y415297D03*
X1603719Y412000D03*
X1611638Y454809D03*
X1612100Y446000D03*
X1603000Y435500D03*
X1630386Y413942D03*
X1634400Y412900D03*
X1630276Y449517D03*
X1612183Y442623D03*
X1602600Y444287D03*
X1603050Y432523D03*
X1621010Y435870D03*
X1620500Y463727D03*
X1634500Y418500D03*
X1603650Y415469D03*
X1646540Y441240D03*
X1639750Y445477D03*
X1639500Y433200D03*
X1646480Y443880D03*
X1639774Y439486D03*
X1646451Y452590D03*
X1646469Y450090D03*
X1646525Y447590D03*
X1639822Y453140D03*
X1647200Y430450D03*
X1622700Y461900D03*
X1612825Y405438D03*
Y408974D03*
X1596500Y455500D03*
X1615061Y463157D03*
X1603000Y422971D03*
X1630200Y454675D03*
X1621226Y445026D03*
X1612256Y440088D03*
X1611935Y429515D03*
X1623749Y464213D03*
X1604200Y464387D03*
X1612250Y435500D03*
X1590037Y432515D03*
X1590581Y404170D03*
X1650944Y505166D03*
X1648330Y504544D03*
X1594880Y494880D03*
X1592025Y495975D03*
X1641963Y495964D03*
X1639391Y513065D03*
X1642670Y514939D03*
X1649336Y511502D03*
X1641470Y506403D03*
X1644651Y505500D03*
X1649545Y515215D03*
X1645969Y514870D03*
X1646700Y480300D03*
X1639394Y507798D03*
X1642880Y490047D03*
X1640781Y487760D03*
X1617700Y475957D03*
X1614000Y475970D03*
X1623705Y467855D03*
X1619607Y469945D03*
X1616607D03*
X1601557Y479225D03*
X1617300Y519000D03*
X1614900Y498575D03*
X1615100Y481400D03*
X1617600D03*
X1600780Y495416D03*
X1597380D03*
X1630159Y520608D03*
X1612500Y510300D03*
X1615000D03*
X1627032Y510226D03*
X1627068Y512626D03*
X1606200Y487100D03*
X1623814Y471400D03*
X1614000Y469500D03*
X1617700Y489700D03*
X1615200D03*
X1611506Y474768D03*
X1620500Y475000D03*
X1603500Y495300D03*
X1597178Y472226D03*
X1599900Y487100D03*
X1603802Y487205D03*
X1633359Y472859D03*
X1633075Y470174D03*
X1629778Y507294D03*
X1627407Y520318D03*
X1621783Y498617D03*
X1625485Y494188D03*
X1627622Y524928D03*
X1620030Y525066D03*
X1623551Y525015D03*
X1590580Y472370D03*
X1639113Y496734D03*
X1598700Y479225D03*
X1617771Y498714D03*
X1629530Y496374D03*
X1629500Y491500D03*
X1639271Y491135D03*
X1594280Y472370D03*
X1637500Y529400D03*
X1644800Y532800D03*
X1636848Y533794D03*
X1649900Y583500D03*
X1638674Y556178D03*
X1599070Y562266D03*
X1596570D03*
X1599120Y564764D03*
X1596620D03*
X1596600Y567250D03*
X1626518Y528029D03*
X1622040Y554827D03*
X1609829Y556599D03*
X1624293Y561747D03*
X1615030Y584260D03*
X1610080Y561367D03*
X1603060Y582920D03*
X1603120Y578020D03*
X1599170Y572780D03*
X1602000Y565700D03*
X1631975Y527700D03*
X1601540Y588793D03*
X1625094Y559200D03*
X1601825Y572325D03*
X1607533Y561644D03*
X1601825Y568325D03*
X1607533Y557644D03*
X1605994Y578500D03*
X1612519Y586004D03*
X1605994Y582500D03*
X1625094Y555200D03*
X1594110Y611510D03*
X1592934Y592396D03*
X1590304Y596896D03*
X1590004Y605496D03*
Y607996D03*
X1590530Y610620D03*
X1590881Y618788D03*
X1593519Y618736D03*
X1644856Y604930D03*
X1640921Y605334D03*
X1601504Y591526D03*
X1617600Y619800D03*
X1619700Y617300D03*
X1622330Y592325D03*
X1603550Y618250D03*
X1600950D03*
X1613721Y592325D03*
X1614700Y597000D03*
X1615862Y605507D03*
X1601489Y602812D03*
X1601270Y597200D03*
X1602150Y610720D03*
X1612519Y590004D03*
X1613349Y603250D03*
X1603919Y596750D03*
X1603869Y608450D03*
X1613349Y599250D03*
X1603869Y604450D03*
X1603919Y592750D03*
X1650869Y614200D03*
Y609200D03*
X1654800Y13518D03*
X1653100Y11500D03*
X1685948Y10725D03*
X1711863Y13276D03*
X1672427Y9700D03*
X1680033Y-16711D03*
X1666500Y10500D03*
X1688000Y3000D03*
X1676819Y-16779D03*
X1691000Y3000D03*
X1695200Y11317D03*
X1704771Y11261D03*
X1673500Y-16850D03*
X1680034Y2863D03*
X1664200Y5400D03*
X1656600Y6300D03*
X1664823Y13287D03*
X1685500Y3000D03*
X1682985Y2901D03*
X1675800Y4100D03*
X1702421Y13231D03*
X1684902Y13472D03*
X1691541Y13226D03*
X1653748Y6325D03*
X1676428Y11381D03*
X1666979Y6236D03*
X1657369Y10258D03*
X1690948Y10725D03*
X1681428Y11381D03*
X1671979Y6236D03*
X1662373Y10154D03*
X1700200Y11317D03*
X1709771Y11261D03*
X1682396Y74344D03*
X1693900Y73300D03*
X1697300Y73296D03*
X1700710Y73292D03*
X1690500Y73950D03*
X1679900Y74500D03*
X1678000Y81600D03*
X1653000Y77600D03*
X1669000Y92000D03*
X1659000Y88000D03*
X1661900Y92400D03*
X1708610Y85121D03*
X1709184Y88811D03*
X1707268Y77668D03*
X1692300Y56900D03*
X1684248Y56746D03*
X1658600Y44700D03*
X1696655Y77991D03*
X1694155D03*
X1691655D03*
X1689155D03*
X1700300Y94703D03*
X1704824Y90049D03*
X1674749Y87050D03*
X1676428Y74646D03*
X1673800Y75200D03*
X1675500Y81600D03*
X1673000D03*
X1670500D03*
X1678627Y54616D03*
X1672000Y51500D03*
X1712600Y46100D03*
X1669350Y69962D03*
X1664350Y72462D03*
Y69962D03*
X1659196Y70291D03*
X1661563Y72028D03*
X1709600Y45800D03*
X1711000Y55525D03*
X1669500Y51500D03*
X1656600Y73614D03*
X1659100D03*
X1668000Y81600D03*
X1665500D03*
X1695300Y94712D03*
X1697800Y94612D03*
X1692285D03*
X1692573Y85833D03*
X1702513Y79885D03*
X1696870Y86093D03*
X1689250Y86000D03*
X1668009Y37000D03*
X1667000Y51500D03*
X1706500Y37000D03*
X1678000D03*
X1687500D03*
X1660944Y36761D03*
X1696795Y38260D03*
X1708508Y39350D03*
X1699273Y39679D03*
X1679648Y39462D03*
X1670198D03*
X1660748D03*
X1689098D03*
X1658559Y37890D03*
X1659038Y95111D03*
X1659000Y85500D03*
X1670250Y87873D03*
X1667000Y88000D03*
X1663000Y81600D03*
X1677573Y86930D03*
X1677649Y90301D03*
X1675062Y91219D03*
X1656298Y39462D03*
X1712308Y39350D03*
X1703073Y39679D03*
X1694098Y39462D03*
X1684648D03*
X1675198D03*
X1665748D03*
X1689368Y98750D03*
X1686876Y98962D03*
X1680139Y99073D03*
X1696907Y99077D03*
X1664500Y99000D03*
X1657835Y156436D03*
X1660400Y98500D03*
X1672200Y112200D03*
X1701455Y153083D03*
X1698927Y153139D03*
X1674800Y103100D03*
X1678400Y103000D03*
X1655209Y181761D03*
X1680370Y185900D03*
X1674019Y175990D03*
X1663566Y213009D03*
X1674455Y169991D03*
X1677605Y169986D03*
X1674455Y172658D03*
X1655031Y184505D03*
X1654015Y217239D03*
X1655978Y207827D03*
X1663400Y179475D03*
X1681352Y196092D03*
X1686183Y191250D03*
X1683484Y190908D03*
X1687950Y186150D03*
X1682950Y184140D03*
X1680450Y183401D03*
X1708350Y175050D03*
X1708250Y164950D03*
X1688046Y174447D03*
X1667356Y213096D03*
X1660440Y200789D03*
X1702400Y193450D03*
X1702450Y190000D03*
X1664321Y195244D03*
X1658082Y195298D03*
X1673800Y201070D03*
X1660800Y181900D03*
X1687550Y213751D03*
X1671556Y208379D03*
X1702500Y187000D03*
X1713000Y185000D03*
X1709900Y187300D03*
X1705666Y198055D03*
X1676750Y206050D03*
X1667140Y182300D03*
X1674912Y183000D03*
X1669849Y193067D03*
X1674066Y196666D03*
X1673530Y209974D03*
X1703610Y161214D03*
X1700836Y161268D03*
X1695734Y164676D03*
X1691439Y174354D03*
X1677600Y172700D03*
X1707100Y188300D03*
X1664390Y201163D03*
X1659643Y213505D03*
X1676924Y196731D03*
X1671688Y182925D03*
X1666345Y241987D03*
X1683729Y242346D03*
X1690565Y251052D03*
X1667667Y257920D03*
X1670140Y257547D03*
X1670822Y254691D03*
X1661186Y245352D03*
X1662000Y250008D03*
X1664324Y248002D03*
X1666329Y245139D03*
X1662956Y243582D03*
X1681760Y245500D03*
X1684509Y245631D03*
X1688451Y249716D03*
X1686113Y250604D03*
X1683615Y250493D03*
X1679100Y276400D03*
X1681116Y238614D03*
X1681632Y233665D03*
X1657498Y279900D03*
Y274700D03*
Y269700D03*
X1657567Y264600D03*
X1657500Y259700D03*
X1657498Y277300D03*
Y267100D03*
X1657949Y257240D03*
X1666968Y260611D03*
X1684300Y233579D03*
X1679100Y278924D03*
Y271300D03*
Y273900D03*
X1680769Y242605D03*
X1653091Y331618D03*
X1652991Y318741D03*
Y323941D03*
Y329059D03*
X1653091Y326500D03*
X1652991Y321341D03*
X1657498Y284900D03*
X1679100Y292000D03*
Y284093D03*
Y294500D03*
Y286593D03*
Y289500D03*
X1657494Y292816D03*
X1679100Y281593D03*
X1657500Y287800D03*
X1657600Y304500D03*
X1679100Y302100D03*
Y304700D03*
Y299500D03*
Y297000D03*
X1664453Y308557D03*
X1654770Y399145D03*
X1652186Y365600D03*
Y360600D03*
X1654809Y401645D03*
X1652186Y354700D03*
Y352100D03*
X1654861Y396637D03*
X1660972Y401447D03*
X1661243Y390364D03*
Y392943D03*
X1660890Y397300D03*
X1660934Y387883D03*
X1664829Y379194D03*
X1664905Y376695D03*
X1667809Y427809D03*
X1667729Y424621D03*
X1668100Y418700D03*
X1678303Y442765D03*
X1667946Y412987D03*
X1681215Y451786D03*
X1673550Y442696D03*
X1684435Y456832D03*
Y459421D03*
X1661470Y456251D03*
X1661522Y453751D03*
X1669076Y438281D03*
X1664762Y438035D03*
X1676304Y449794D03*
X1676287Y447244D03*
X1667588Y434149D03*
X1667649Y430849D03*
X1667462Y440735D03*
X1669962D03*
X1668843Y465060D03*
X1675744Y456200D03*
X1664762Y443735D03*
X1669816Y443953D03*
Y446453D03*
X1673064Y446022D03*
X1679145Y461950D03*
X1673068Y448522D03*
X1669816Y448953D03*
X1661549Y451251D03*
X1681192Y454286D03*
X1668000Y416200D03*
X1673074Y453185D03*
X1675120Y439731D03*
X1681154Y449286D03*
X1664762Y440735D03*
X1676041Y458884D03*
X1660834Y404934D03*
X1655790Y476593D03*
X1651867Y484741D03*
X1651926Y482197D03*
X1671050Y490850D03*
X1687500Y505200D03*
X1672313Y497300D03*
X1687741Y466988D03*
X1705767Y482434D03*
X1698354Y486873D03*
X1687443Y487203D03*
X1681500Y482000D03*
X1699861Y520192D03*
X1697261D03*
X1695658Y486945D03*
X1694410Y499830D03*
X1692120Y501410D03*
X1699900Y512300D03*
X1692443Y487259D03*
X1710594Y519900D03*
X1667674Y467271D03*
X1681650Y510673D03*
X1687606Y500938D03*
X1672265Y473600D03*
X1678001Y473205D03*
X1665047Y467257D03*
X1689943Y487203D03*
X1671050Y483600D03*
Y481000D03*
X1680500Y473325D03*
X1687500Y484000D03*
X1690091Y503995D03*
X1672606Y499820D03*
X1671050Y487000D03*
X1681115Y525218D03*
X1709400Y513000D03*
X1651754Y488025D03*
X1684650Y505200D03*
X1672159Y494042D03*
X1701617Y482706D03*
X1676800Y483800D03*
X1652500Y575600D03*
X1653960Y562930D03*
X1667277Y535221D03*
X1698600Y584800D03*
X1680133Y535489D03*
X1699600Y578100D03*
X1710389Y577787D03*
X1664113Y548380D03*
X1658466D03*
X1661880Y583900D03*
X1686036Y548251D03*
X1677300Y550200D03*
X1680007Y547917D03*
X1669121Y547923D03*
X1708140Y547538D03*
X1697839Y545759D03*
X1709183Y588700D03*
X1700348Y546633D03*
X1680000Y550544D03*
X1658754Y551000D03*
X1669600Y550544D03*
X1685000D03*
X1663754Y551000D03*
X1674600Y550544D03*
X1652669Y582350D03*
Y578350D03*
X1705348Y546633D03*
X1660680Y586750D03*
X1654100Y615790D03*
X1653970Y607340D03*
X1652700Y591300D03*
Y600850D03*
X1662580Y593200D03*
X1661200Y601300D03*
Y607300D03*
X1709950Y592900D03*
X1710000Y595500D03*
Y604500D03*
Y600000D03*
X1701291Y602268D03*
X1699106Y618018D03*
X1658369Y606250D03*
X1652499Y593950D03*
X1660680Y590750D03*
X1658369Y602250D03*
X1652499Y597950D03*
X1714297Y11180D03*
X1756895Y30452D03*
X1723678Y11381D03*
X1756992Y20007D03*
X1763360Y24010D03*
X1730550Y21160D03*
X1721559Y13500D03*
X1730768Y13313D03*
X1763100Y21500D03*
X1768807Y21512D03*
X1753903Y22116D03*
X1749941Y21163D03*
X1741000Y21200D03*
X1741544Y9151D03*
X1752908Y9481D03*
X1744900Y9100D03*
X1755500Y9076D03*
X1759093Y9310D03*
X1761872Y-7220D03*
X1734875Y9238D03*
X1760693Y20045D03*
X1767069Y24010D03*
X1743152Y23197D03*
X1733168Y22312D03*
X1748152Y23197D03*
X1738168Y22312D03*
X1728678Y11381D03*
X1719297Y11180D03*
X1749085Y9177D03*
X1731350Y92140D03*
X1715259Y35602D03*
X1715100Y46100D03*
X1713550Y56000D03*
X1716900Y87900D03*
X1713900D03*
X1750250Y35925D03*
X1753059Y35300D03*
X1750400Y47400D03*
X1745094Y47106D03*
X1732650Y60650D03*
X1735150D03*
Y58150D03*
X1732650D03*
X1757772Y90174D03*
X1757395Y84794D03*
X1760364Y85136D03*
X1720500Y52440D03*
X1748500Y79500D03*
X1757998Y73637D03*
X1775000Y53500D03*
X1720100Y46100D03*
X1742594Y47106D03*
X1748854Y58533D03*
X1746328Y59011D03*
X1717600Y46100D03*
X1755400Y37700D03*
X1736700Y39600D03*
X1727383Y39465D03*
X1717958Y39880D03*
X1752000Y38865D03*
X1724758Y38600D03*
X1720600Y70200D03*
X1733910Y38233D03*
X1757054Y66059D03*
X1758100Y37000D03*
X1749364Y38971D03*
X1743500Y39300D03*
X1768450Y77376D03*
X1765900Y83700D03*
X1754703Y84053D03*
X1771459Y52695D03*
X1733900Y92200D03*
X1725474Y69250D03*
X1766240Y70500D03*
X1760016Y65774D03*
X1771707Y86500D03*
X1746552Y38900D03*
X1767250Y94500D03*
Y89500D03*
X1766333Y59116D03*
X1769250Y70350D03*
X1756895Y34252D03*
X1746550Y35925D03*
X1740598Y39486D03*
X1731183Y39465D03*
X1721758Y39880D03*
X1715100Y70500D03*
X1746491Y95650D03*
X1754600Y109200D03*
X1748425Y119190D03*
X1765015Y119100D03*
X1758100D03*
X1761300D03*
X1767250Y99500D03*
Y104500D03*
X1770850Y109500D03*
X1768886Y156173D03*
X1719250Y179150D03*
X1713596Y175795D03*
X1714189Y159550D03*
X1714528Y190189D03*
X1758650Y158650D03*
X1750189Y159550D03*
X1745689D03*
X1741189D03*
X1727689D03*
X1723189D03*
X1718689D03*
X1732189D03*
X1736689D03*
X1745777Y179574D03*
X1751975Y179374D03*
X1739377D03*
X1733178Y179574D03*
X1758375D03*
X1764673Y179374D03*
X1770973Y179574D03*
X1726700Y179400D03*
X1719000Y190500D03*
X1730400Y195850D03*
X1740900Y198800D03*
X1744000D03*
X1769100Y209700D03*
X1765950Y209600D03*
X1769016Y198872D03*
X1765866Y198772D03*
X1731260Y209600D03*
X1740709D03*
X1756000Y210000D03*
X1753400Y209900D03*
X1743900Y209700D03*
X1728616Y198872D03*
X1753311Y198700D03*
X1756600Y198800D03*
X1731216Y198872D03*
X1719100Y176000D03*
X1749295Y176104D03*
X1723189Y176012D03*
X1733484Y211631D03*
X1746125D03*
X1758725D03*
X1771325D03*
X1738484D03*
X1751125D03*
X1763725D03*
X1727193Y176525D03*
X1744792D03*
X1757390D03*
X1769988D03*
X1732193D03*
X1739792D03*
X1752390D03*
X1764988D03*
X1733563Y196776D03*
X1746082Y196843D03*
X1758668D03*
X1771241Y196841D03*
X1738563Y196776D03*
X1751082Y196843D03*
X1763668D03*
X1763554Y237712D03*
X1762795Y232106D03*
X1772244D03*
X1752554Y237712D03*
X1771451D03*
X1733880Y232810D03*
X1715837Y246178D03*
X1727896Y246175D03*
X1720651Y246141D03*
X1718820Y249032D03*
X1715078Y250231D03*
X1724181Y246159D03*
X1724944Y250324D03*
X1727444D03*
X1771243Y250100D03*
X1729944Y250324D03*
X1768516Y249983D03*
X1768700Y233644D03*
X1739847Y233334D03*
X1736847D03*
X1719080Y232852D03*
X1744603Y232489D03*
X1753347Y232106D03*
X1763300Y250100D03*
X1733900Y237300D03*
X1736400D03*
X1719080Y236152D03*
X1774451Y237712D03*
X1755554D03*
X1760554D03*
X1742398Y234681D03*
X1722251Y250532D03*
X1766077Y232681D03*
X1751900Y249700D03*
X1746900Y249804D03*
X1749462Y232955D03*
X1716037Y444550D03*
X1724590Y444521D03*
X1737150Y450850D03*
X1766100Y447900D03*
X1762992Y447938D03*
X1740963Y448476D03*
X1753543Y448100D03*
X1750393Y448037D03*
X1737795Y448100D03*
X1727620Y444380D03*
X1721990Y444521D03*
X1730996Y442804D03*
X1719317Y441947D03*
X1724369Y441601D03*
X1718587Y444550D03*
X1760767Y450408D03*
X1748169D03*
X1773366D03*
X1755767D03*
X1743169D03*
X1768366D03*
X1714530Y519900D03*
X1716490Y506970D03*
X1722000Y513000D03*
X1742900Y485000D03*
X1734000Y488100D03*
X1755000Y485000D03*
X1748600D03*
X1749396Y493969D03*
X1751868Y494045D03*
X1770325Y490255D03*
X1773500Y472100D03*
X1767300Y472700D03*
X1765325Y490255D03*
X1758500Y493800D03*
X1760900Y472800D03*
X1772459Y467005D03*
X1769309D03*
X1759860D03*
X1756710D03*
X1747262D03*
X1744112D03*
X1734663D03*
X1729200Y519000D03*
X1733830Y502650D03*
X1768900Y521124D03*
X1749090Y513790D03*
X1740400Y496300D03*
X1726600Y519000D03*
X1728700Y502600D03*
X1737300Y500900D03*
X1738180Y503487D03*
X1719089Y472104D03*
X1728700Y470200D03*
X1774200Y512800D03*
X1766100Y521124D03*
X1722347Y471811D03*
X1750800Y516100D03*
X1762715Y521085D03*
X1748125Y496400D03*
X1733639Y500085D03*
X1758575Y496406D03*
X1743125Y496400D03*
X1728639Y500085D03*
X1753575Y496406D03*
X1713600Y513000D03*
X1770325Y487355D03*
X1765325D03*
X1754300Y487855D03*
X1741900Y487755D03*
X1766700Y475655D03*
X1749300Y487855D03*
X1736900Y487755D03*
X1774300Y475055D03*
X1761700Y475655D03*
X1719560Y501770D03*
X1725694Y568814D03*
Y571814D03*
X1767500Y559800D03*
X1738697Y557888D03*
X1738434Y588986D03*
X1736003Y588244D03*
X1772578Y575993D03*
X1756417Y563840D03*
X1754000Y553500D03*
X1746000Y574000D03*
X1724250Y588250D03*
X1756500Y554500D03*
X1743500Y564500D03*
X1759500Y554500D03*
X1718000Y587723D03*
X1756578Y586743D03*
X1767141Y555500D03*
X1730759Y548162D03*
X1733000Y557000D03*
X1722500Y562000D03*
X1742200Y552863D03*
X1749000D03*
X1762595Y576191D03*
X1769000Y576378D03*
X1754897Y578750D03*
X1742381Y585530D03*
X1730814Y568814D03*
X1733000Y560000D03*
X1764300Y570900D03*
X1767455Y571695D03*
X1738216Y548239D03*
X1753807Y548183D03*
X1757478Y548192D03*
X1738498Y554255D03*
X1737958Y560500D03*
X1743200Y567300D03*
X1743100Y561700D03*
X1767000Y563500D03*
X1767529Y566200D03*
X1743000Y574500D03*
X1730774Y579960D03*
X1733368Y579868D03*
X1724899Y584748D03*
X1738088Y551000D03*
X1739500Y586500D03*
X1770719Y573964D03*
X1728245Y585244D03*
X1743000Y570000D03*
X1765300Y574700D03*
X1742381Y588530D03*
X1739179Y592070D03*
X1746052Y614796D03*
X1735000Y621002D03*
X1764912Y618718D03*
X1725133Y614896D03*
X1724092Y618700D03*
X1770600Y600800D03*
X1766400Y599400D03*
X1728341Y614851D03*
X1739211Y596711D03*
X1772158Y610960D03*
X1750399Y603201D03*
X1764823Y613600D03*
X1750739Y618718D03*
X1718008Y592002D03*
X1718037Y597184D03*
X1716950Y603450D03*
X1718037Y594684D03*
X1757319Y606953D03*
X1758550Y604350D03*
X1742509Y595869D03*
X1742381Y591530D03*
X1740270Y594419D03*
X1739714Y604967D03*
X1762062Y592055D03*
X1763500Y599100D03*
X1762062Y589555D03*
X1727843Y597142D03*
X1732443Y592342D03*
Y597142D03*
X1727743Y592342D03*
X1832449Y-8950D03*
X1835500Y-1700D03*
X1835600Y3900D03*
X1804800Y-1500D03*
X1825324Y1000D03*
X1824564Y3441D03*
X1785612Y10729D03*
X1782371Y26832D03*
X1804508Y11858D03*
X1798676Y11726D03*
X1830344Y13397D03*
X1828824Y3699D03*
X1816693Y13331D03*
X1829636Y26680D03*
X1831000Y-16300D03*
X1788421Y8122D03*
X1825870Y21587D03*
X1832900Y10300D03*
X1785366Y8100D03*
X1823300Y21700D03*
X1832842Y13500D03*
X1836700Y-18900D03*
X1819800Y2100D03*
X1813913Y2287D03*
X1816723Y9781D03*
X1808603Y9300D03*
X1823600Y8800D03*
X1809822Y26585D03*
X1807127Y26918D03*
X1795078Y11900D03*
X1790078Y11860D03*
X1804462Y8830D03*
X1799462D03*
X1808100Y21800D03*
X1815150Y26650D03*
X1797700Y21018D03*
X1791500Y26918D03*
X1813795Y12165D03*
X1808795D03*
X1828874Y-13520D03*
X1819837Y21700D03*
X1786865Y22375D03*
X1829888Y10735D03*
X1819800Y35500D03*
X1790700Y34900D03*
X1799774Y34890D03*
X1826414Y35486D03*
X1827100Y81600D03*
X1798454Y82256D03*
X1788216Y59197D03*
X1815637Y54775D03*
X1818396Y54752D03*
X1779750Y36530D03*
X1784341Y64841D03*
X1820457Y39128D03*
X1789356Y38286D03*
X1796100Y68800D03*
X1829580Y38620D03*
X1824130Y39703D03*
X1826900Y40400D03*
X1808444Y37152D03*
X1800000Y80000D03*
X1827000Y87000D03*
X1834300Y41100D03*
X1824240Y83680D03*
X1802119Y56581D03*
X1786341Y63341D03*
X1799438Y44328D03*
X1817186Y39929D03*
X1827000Y94550D03*
X1788200Y93000D03*
Y89000D03*
Y85000D03*
X1808363Y40033D03*
X1803300Y39900D03*
X1817352Y36909D03*
X1812352Y36949D03*
X1797700Y36804D03*
X1792700Y36871D03*
X1794100Y70898D03*
X1776828Y155211D03*
X1818383Y133277D03*
X1815883D03*
X1777000Y115750D03*
X1787500Y155170D03*
X1813118Y127976D03*
X1807509Y128500D03*
X1778000Y120000D03*
X1780720Y153850D03*
X1807166Y147401D03*
X1783252Y109044D03*
X1788448Y98820D03*
X1788648Y101490D03*
X1807745Y104500D03*
X1803400Y114000D03*
X1796059Y104402D03*
X1801366Y151937D03*
X1811348Y143448D03*
X1800264Y143789D03*
X1828340Y149960D03*
X1803058Y143733D03*
X1815348Y143437D03*
X1796500Y120000D03*
X1827150Y97800D03*
X1830316Y102163D03*
X1828960Y153010D03*
X1824990Y103620D03*
X1787373Y120188D03*
X1824509Y143653D03*
X1821348Y143437D03*
X1815026Y121478D03*
X1808226Y136171D03*
X1803509Y128500D03*
X1800792Y122691D03*
X1821350Y98270D03*
X1810100Y114700D03*
X1812743Y104395D03*
X1810245Y104500D03*
X1814900Y116900D03*
X1816418Y127976D03*
X1800000Y132627D03*
X1788000Y129000D03*
X1784750Y124000D03*
X1808313Y111705D03*
X1800420Y148240D03*
X1820648Y155537D03*
X1816348D03*
X1807818Y124179D03*
X1827500Y144900D03*
X1809810Y155858D03*
X1790100Y154000D03*
X1833629Y170807D03*
X1777172Y179374D03*
X1778466Y198772D03*
X1783572Y179574D03*
X1802369Y179374D03*
X1808769Y179574D03*
X1815000Y179300D03*
X1789870Y179374D03*
X1796170Y179574D03*
X1795348Y172037D03*
X1797848D03*
X1792748Y171937D03*
X1821367Y179574D03*
X1827565Y179174D03*
X1833388Y179500D03*
X1821261Y170012D03*
X1824200Y176900D03*
X1787000Y175500D03*
X1834103Y176021D03*
X1778900Y165800D03*
X1785500Y164000D03*
Y168000D03*
X1834400Y216900D03*
X1830415Y196567D03*
X1791150Y209600D03*
X1794300Y209700D03*
X1794216Y198872D03*
X1791066Y198772D03*
X1819457Y198872D03*
X1828700Y198800D03*
X1820349Y209586D03*
X1828950Y209600D03*
X1832274Y209734D03*
X1816266Y198772D03*
X1804166Y198472D03*
X1807751Y209586D03*
X1803072Y209728D03*
X1806821Y198600D03*
X1815670Y209728D03*
X1781700Y209700D03*
X1778550Y209600D03*
X1781616Y198872D03*
X1816125Y169492D03*
X1816348Y163437D03*
X1818500Y159500D03*
X1820648Y163437D03*
X1776325Y211631D03*
X1777587Y176525D03*
X1783925Y211631D03*
X1796526Y212231D03*
X1809125D03*
X1821685Y212161D03*
X1788925Y211631D03*
X1801526Y212231D03*
X1814125D03*
X1826685Y212161D03*
X1790185Y176525D03*
X1802784D03*
X1815382D03*
X1782587D03*
X1795185D03*
X1807784D03*
X1820382D03*
X1783841Y196841D03*
X1776241D03*
X1814041D03*
X1801441D03*
X1809041D03*
X1821682D03*
X1796441D03*
X1788841D03*
X1807440Y165530D03*
X1836100Y179700D03*
X1807440Y169030D03*
Y162030D03*
X1826682Y196841D03*
X1782452Y237712D03*
X1820281Y250498D03*
X1809281D03*
X1801384D03*
X1790383D03*
X1835936Y235604D03*
X1784440Y232938D03*
X1831700Y252272D03*
X1804388Y249904D03*
X1826662Y232191D03*
X1822638Y232106D03*
X1826287Y250000D03*
X1824300Y251800D03*
X1826085Y236034D03*
X1822877Y235852D03*
X1793600Y235100D03*
X1793700Y232500D03*
X1806083Y232584D03*
X1803280Y232611D03*
X1791141Y232106D03*
X1828936Y249900D03*
X1819488Y232106D03*
X1810040D03*
X1800591D03*
X1781693D03*
X1817282Y250498D03*
X1798384D03*
X1779451Y237712D03*
X1793384Y250498D03*
X1812282D03*
X1775590Y448100D03*
X1778740D03*
X1828600Y450100D03*
X1825984Y448030D03*
X1816535Y448300D03*
X1813385Y447945D03*
X1804000Y447900D03*
X1800787Y447943D03*
X1791338Y448400D03*
X1788189Y448300D03*
X1785964Y450408D03*
X1780964D03*
X1836495Y450600D03*
X1823760Y450408D03*
X1811161D03*
X1798563D03*
X1831495Y450600D03*
X1818760Y450408D03*
X1806161D03*
X1793563D03*
X1776695Y512640D03*
X1779700Y472100D03*
X1784525Y491830D03*
X1781907Y467005D03*
X1785057D03*
X1779303Y497246D03*
X1832301Y467005D03*
X1835550Y466870D03*
X1789774Y476403D03*
X1801500Y471055D03*
X1795164Y476406D03*
X1789525Y491830D03*
X1801125D03*
X1796125D03*
X1817325Y481320D03*
X1806600Y471055D03*
X1812325Y481320D03*
X1806975Y491630D03*
X1830220Y479950D03*
X1824960Y473980D03*
X1824125Y491830D03*
X1822852Y467005D03*
X1819702D03*
X1819125Y491830D03*
X1807104Y467005D03*
X1810254D03*
X1811975Y491630D03*
X1797655Y467005D03*
X1794505D03*
X1810508Y515900D03*
X1804000Y498176D03*
X1834540Y519600D03*
X1790250Y522350D03*
X1834100Y523900D03*
X1791113Y496670D03*
X1788045Y496654D03*
X1825700Y514900D03*
X1828100Y516300D03*
X1828000Y513200D03*
X1814852Y519901D03*
X1809700Y506875D03*
X1820400Y501100D03*
X1806076Y523525D03*
X1798883Y515636D03*
X1810200Y513300D03*
X1815200Y501500D03*
X1801600Y515600D03*
X1794100Y521900D03*
X1803900Y491500D03*
X1796153Y514200D03*
X1783400Y522500D03*
X1780838Y522562D03*
X1836396Y481349D03*
X1789300Y520000D03*
X1836600Y521600D03*
X1828200Y519000D03*
X1833700Y497300D03*
X1786000Y522600D03*
X1796400Y498000D03*
X1804500Y526200D03*
X1795200Y525700D03*
X1816800D03*
X1810350Y525650D03*
X1813500Y526500D03*
X1824125Y488930D03*
X1811975Y488730D03*
X1801125Y488930D03*
X1789525D03*
X1819125D03*
X1806975Y488730D03*
X1796125Y488930D03*
X1784525D03*
X1829967Y476927D03*
X1817375Y478320D03*
X1794975Y479300D03*
X1779300Y475055D03*
X1825297Y476927D03*
X1812375Y478320D03*
X1789975Y479300D03*
X1801525Y473955D03*
X1806525D03*
X1784878Y496701D03*
X1825900Y523500D03*
X1779400Y582500D03*
X1818509Y527893D03*
X1829000Y536315D03*
X1792170Y583900D03*
X1783700Y576400D03*
X1798250Y529200D03*
X1810863Y560637D03*
X1816175Y567669D03*
X1785050Y584550D03*
X1792100Y566900D03*
X1816100Y576200D03*
X1816330Y545260D03*
X1816052Y584101D03*
X1809309Y555713D03*
X1831500Y548000D03*
X1835000Y550300D03*
X1781510Y546362D03*
X1786500Y562200D03*
X1783700Y579200D03*
X1828800Y546500D03*
X1828700Y540252D03*
X1828900Y552300D03*
X1834000Y534900D03*
X1811704Y554341D03*
X1807600Y552047D03*
X1806200Y549200D03*
X1786900Y552500D03*
X1801200Y529800D03*
X1806200Y582900D03*
X1780500Y570718D03*
Y568000D03*
X1781000Y565000D03*
X1780394Y561076D03*
X1782300Y555900D03*
X1779500Y579500D03*
X1779000Y585500D03*
X1810387Y571435D03*
X1794000Y568800D03*
X1793320Y557968D03*
X1828700Y569474D03*
X1836281Y589122D03*
X1828800Y575600D03*
X1828875Y563674D03*
X1828824Y557663D03*
X1810385Y568821D03*
X1807958Y565690D03*
X1781300Y537800D03*
X1808057Y573125D03*
Y570125D03*
X1813456Y583500D03*
X1803752Y529301D03*
X1810052Y545103D03*
X1816584Y530542D03*
X1793900Y550100D03*
X1793660Y560570D03*
X1829300Y572900D03*
X1816280Y550400D03*
Y553500D03*
X1792805Y574675D03*
X1812952Y545501D03*
X1794000Y552800D03*
X1811100Y586800D03*
X1816458Y587480D03*
X1829176Y584287D03*
X1779000Y588500D03*
X1793452Y586701D03*
X1831600Y529000D03*
X1832500Y539500D03*
X1788300Y585100D03*
X1791349Y589122D03*
X1832200Y567760D03*
X1831500Y544500D03*
X1831800Y552300D03*
X1809600Y582800D03*
X1793100Y578500D03*
X1816020Y571448D03*
X1812802Y578693D03*
X1812452Y538501D03*
Y533601D03*
X1807852D03*
X1807752Y538501D03*
X1779000Y598900D03*
X1776500Y621200D03*
X1778400Y618900D03*
X1800352Y596101D03*
X1795000Y599600D03*
X1791323Y594030D03*
X1805000Y606500D03*
X1787500Y600500D03*
X1778675Y592224D03*
X1784200Y593924D03*
X1787500Y597791D03*
X1825014Y593695D03*
X1811500Y603500D03*
X1794500Y612500D03*
X1791500Y606500D03*
X1800378Y593527D03*
X1819654Y593803D03*
X1805500Y603100D03*
X1782700Y610900D03*
X1829051Y591299D03*
X1822273Y595046D03*
X1788290Y612006D03*
X1808152Y591601D03*
X1812852Y596401D03*
X1808252D03*
X1812852Y591601D03*
X1837900Y9700D03*
X1837800Y-3600D03*
X1838850Y13160D03*
X1883041Y15814D03*
X1882999Y7383D03*
X1845420Y13310D03*
X1893094Y-10142D03*
X1838100Y3900D03*
X1868286Y12848D03*
X1871163Y13186D03*
X1870600Y25000D03*
X1848322Y12723D03*
X1841289Y21631D03*
X1876792Y18461D03*
X1876881Y22181D03*
X1843426Y9528D03*
X1840400Y9700D03*
X1893081Y-20735D03*
X1893094Y-12642D03*
X1858600Y74300D03*
X1837500Y35700D03*
X1853467Y35000D03*
X1841060Y35540D03*
X1846527Y34435D03*
X1849027Y34426D03*
X1873956Y60299D03*
X1883200Y76600D03*
X1850600Y41348D03*
X1858198Y41108D03*
X1860786Y41200D03*
X1855400Y40800D03*
X1878800Y43207D03*
Y40200D03*
X1878997Y37546D03*
X1889218Y43530D03*
Y53530D03*
X1846800Y95400D03*
X1847000Y86500D03*
X1848000Y56500D03*
X1850500D03*
X1890803Y63189D03*
X1884500Y79300D03*
X1882000D03*
X1895330Y64390D03*
X1877270Y63473D03*
X1889218Y56030D03*
Y61030D03*
Y46030D03*
Y51030D03*
X1880230Y76820D03*
X1879500Y79300D03*
X1880986Y53299D03*
X1868670Y42765D03*
X1878000Y73950D03*
X1848208Y49427D03*
X1896970Y73460D03*
X1867619Y39779D03*
X1895354Y75650D03*
X1842250Y84000D03*
X1849426Y90700D03*
Y95500D03*
X1893961Y73365D03*
X1860995Y84509D03*
X1856873Y91200D03*
X1856778Y87397D03*
X1864208Y87724D03*
X1864195Y84509D03*
X1864153Y91241D03*
X1860815Y91184D03*
X1842250Y90750D03*
X1877103Y60791D03*
X1838500Y40400D03*
X1856333Y34518D03*
X1875100Y51300D03*
X1854250Y138600D03*
X1854115Y131121D03*
X1864904Y114735D03*
X1872254Y138618D03*
X1839667Y151994D03*
X1837090Y149830D03*
X1848100Y134750D03*
X1839941Y156858D03*
X1845469Y135500D03*
X1872340Y147236D03*
X1895800Y149200D03*
X1885400Y147000D03*
X1878550Y99470D03*
X1882550D03*
X1894834Y139286D03*
X1863908Y140992D03*
X1878950Y137400D03*
X1871855Y104188D03*
X1856700Y110167D03*
X1843107Y97988D03*
X1857110Y113600D03*
X1890974Y105600D03*
X1898102Y107325D03*
X1897536Y120510D03*
Y114600D03*
X1874258Y103196D03*
X1885700Y141200D03*
X1862400Y124500D03*
X1851341Y106358D03*
X1857020Y129619D03*
Y126619D03*
X1861015Y130815D03*
X1867280Y135406D03*
X1878096Y152843D03*
X1871521Y153593D03*
X1881324Y153250D03*
X1869000Y153900D03*
X1875425Y152925D03*
X1875600Y156300D03*
X1886050Y151431D03*
X1886299Y153928D03*
X1895673Y151800D03*
X1865577Y124450D03*
X1878753Y139893D03*
X1866606Y109967D03*
X1860969Y136369D03*
Y133769D03*
X1872400Y144619D03*
X1857919Y156123D03*
X1895060Y136099D03*
X1848590Y141360D03*
X1857250Y138600D03*
X1853317Y108197D03*
X1887830Y102227D03*
X1852600Y97500D03*
X1857849Y148079D03*
X1854962Y133613D03*
X1887300Y121500D03*
X1850700Y156000D03*
X1875700Y115700D03*
Y121500D03*
X1881500Y115700D03*
Y121500D03*
Y127300D03*
X1887300D03*
X1875700D03*
X1887300Y115700D03*
X1846663Y153748D03*
X1894855Y142122D03*
X1893640Y147042D03*
X1888639D03*
X1887497Y105444D03*
X1881165Y105561D03*
X1886000Y156700D03*
X1885102Y101134D03*
X1876001Y105438D03*
X1861932Y146431D03*
X1869668Y146750D03*
X1848532Y144360D03*
X1897507Y124450D03*
X1864637Y201861D03*
X1868843Y207920D03*
X1839873Y159358D03*
X1854942Y181655D03*
X1836932Y170486D03*
X1854900Y175900D03*
X1877517Y217988D03*
X1839500Y212700D03*
X1876700Y207600D03*
X1875700Y184800D03*
X1895614Y204785D03*
X1895100Y201770D03*
X1883539Y199813D03*
X1883350Y202410D03*
X1858470Y206335D03*
X1855670Y206430D03*
X1897450Y213951D03*
Y216551D03*
X1882452Y195888D03*
X1877880Y203780D03*
X1863650Y189750D03*
X1893238Y208042D03*
X1857044Y186292D03*
X1863750Y163750D03*
X1868375Y171900D03*
X1846163Y168448D03*
X1886400Y172600D03*
Y170000D03*
X1886200Y161000D03*
X1883930Y176137D03*
X1883800Y179100D03*
X1857400Y175900D03*
X1862000Y177500D03*
X1876832Y173919D03*
X1875066Y175782D03*
X1886800Y210600D03*
X1886952Y213125D03*
X1883800Y213436D03*
X1884340Y217866D03*
X1859604Y213206D03*
X1861497Y211481D03*
X1874236Y213800D03*
X1871708Y213442D03*
X1850876Y212946D03*
X1847699D03*
X1847000Y198600D03*
X1864464Y198466D03*
X1886093Y202184D03*
X1878789Y213663D03*
X1864000Y184900D03*
X1858500Y200100D03*
X1861243Y183100D03*
X1872100Y207900D03*
X1884400Y183700D03*
X1891880Y204370D03*
X1854663Y158248D03*
X1846663D03*
X1886400Y178700D03*
X1883800Y210575D03*
X1854868Y184667D03*
X1836900Y165800D03*
X1889400Y191200D03*
X1896710Y194380D03*
X1847200Y202050D03*
X1840900Y179700D03*
X1845700D03*
X1858686Y180377D03*
X1885465Y166285D03*
X1855000Y167100D03*
X1864170Y211869D03*
X1892791Y200069D03*
X1884000Y188100D03*
X1865100Y174600D03*
X1836900Y232700D03*
X1850723Y219250D03*
X1843449Y244425D03*
X1856874Y219443D03*
X1896529Y235080D03*
X1884651Y234975D03*
X1854374Y248790D03*
X1844444Y224035D03*
X1850220Y253500D03*
X1858420Y253700D03*
X1843600Y239000D03*
X1840300Y239300D03*
X1861605Y253925D03*
X1881900Y224100D03*
X1884400D03*
X1882200Y234400D03*
X1882345Y231837D03*
X1840149Y244425D03*
X1864305Y253825D03*
X1872323Y264167D03*
X1852300Y252000D03*
X1858400Y251200D03*
X1843700Y253400D03*
X1892274Y235080D03*
X1846517Y253500D03*
X1854720Y253700D03*
X1885000Y227500D03*
X1870815Y453022D03*
X1858633Y452803D03*
X1839400Y450440D03*
X1838768Y454120D03*
X1847185Y454368D03*
X1860158Y450322D03*
X1864300Y447900D03*
X1882677Y447930D03*
X1895275Y454422D03*
X1898425Y447930D03*
Y454422D03*
X1844630Y454321D03*
X1878100Y450200D03*
X1859059Y448076D03*
X1872860Y450550D03*
Y447950D03*
X1875900Y453600D03*
X1866050Y451100D03*
X1868015Y452987D03*
X1841630Y454321D03*
X1863137Y452710D03*
X1867500Y447900D03*
X1837300Y472276D03*
X1837200Y525700D03*
X1866688Y517128D03*
X1845330Y466870D03*
X1843000Y505000D03*
X1857480Y466800D03*
X1861300D03*
X1881285Y467049D03*
X1849795Y493379D03*
X1850290Y486610D03*
X1872908Y471338D03*
X1870138Y485732D03*
X1852340Y509140D03*
X1859530Y516430D03*
X1842400Y516800D03*
X1843100Y494100D03*
X1840500D03*
X1843100Y491500D03*
X1840500D03*
Y484650D03*
Y487250D03*
X1842450Y507520D03*
X1896700Y472600D03*
X1896800Y470200D03*
X1894100Y472600D03*
X1894200Y470200D03*
X1864339Y509560D03*
X1843750Y475724D03*
X1840750D03*
X1841900Y498800D03*
X1852719Y487575D03*
Y492575D03*
X1873632Y500904D03*
X1860280Y520200D03*
X1847000Y487500D03*
X1860000Y495500D03*
X1844490Y509230D03*
X1875973Y499838D03*
X1869914Y517225D03*
X1877518Y527560D03*
X1857450Y473654D03*
X1837857Y468630D03*
X1842857D03*
X1868167Y467855D03*
X1863000Y480000D03*
X1859600Y476200D03*
X1876945Y471316D03*
X1877407Y479046D03*
X1855206Y471112D03*
X1842764Y528136D03*
X1838000Y549700D03*
X1837475Y573835D03*
X1837534Y579322D03*
X1838224Y586650D03*
X1889800Y580200D03*
X1878000Y539000D03*
X1861080Y537090D03*
X1870100Y561150D03*
X1854508Y552708D03*
X1858528Y544528D03*
X1857108Y550108D03*
X1875850Y567200D03*
X1857108Y552708D03*
X1840690Y557190D03*
X1878500Y553500D03*
X1858500Y540000D03*
X1852250Y547900D03*
X1858681Y568087D03*
X1879862Y581862D03*
X1896899Y557790D03*
X1845407Y533178D03*
X1868110Y536000D03*
X1878736Y533040D03*
X1864580Y537060D03*
X1852400Y554900D03*
X1869800Y557100D03*
X1878875Y565475D03*
X1897300Y548800D03*
X1855750Y548000D03*
X1882300Y565550D03*
X1885100Y584300D03*
X1873510Y541710D03*
X1840700Y563800D03*
X1848800Y551400D03*
X1848900Y548200D03*
X1854530Y533132D03*
X1859708Y552708D03*
X1856573Y576534D03*
X1857812Y557245D03*
X1842500Y534500D03*
X1844100Y551000D03*
X1848900Y545500D03*
X1878450Y548650D03*
X1870250Y541950D03*
X1896500Y555300D03*
X1879800Y579000D03*
X1858000Y574000D03*
X1870892Y583245D03*
X1874825Y564125D03*
X1859167Y559350D03*
X1894299Y557790D03*
X1895523Y586365D03*
X1844018Y586482D03*
X1858000Y586250D03*
X1866800Y588000D03*
X1875600Y588500D03*
X1856040Y588704D03*
X1837000Y534900D03*
X1839126Y583354D03*
X1847070Y537610D03*
X1896358Y595255D03*
X1868200Y590939D03*
X1848900Y590750D03*
X1845000Y590800D03*
X1900256Y-14760D03*
Y-18911D03*
X1906438Y-15968D03*
X1916078Y-16368D03*
X1903160Y-19416D03*
X1918352Y89300D03*
X1923300Y94300D03*
X1909406Y76790D03*
X1907986Y82393D03*
X1907929Y84793D03*
X1907907Y87223D03*
X1918379Y84788D03*
X1956891Y92513D03*
X1952110Y95513D03*
X1954391Y92513D03*
X1951670Y90363D03*
Y92863D03*
X1951770Y87863D03*
X1954169Y84111D03*
X1954861Y95163D03*
X1949610Y95513D03*
X1949270Y87863D03*
X1949170Y92863D03*
Y90363D03*
X1946670Y87863D03*
X1946570Y92863D03*
Y90363D03*
X1946670Y85363D03*
X1949270D03*
X1951770D03*
X1957361Y95163D03*
X1918113Y93576D03*
X1926890Y73106D03*
X1920300Y68300D03*
X1917600Y66000D03*
X1948472Y80362D03*
X1905501Y79790D03*
X1902796Y79820D03*
X1927918Y126156D03*
X1900100Y145100D03*
X1918210Y96103D03*
X1921199Y140499D03*
X1929711Y155759D03*
X1904136Y140160D03*
X1937000Y150000D03*
X1946500Y104974D03*
X1950934Y143730D03*
X1936187Y144013D03*
X1951700Y141000D03*
X1940700Y136300D03*
X1904215Y142812D03*
X1927810Y123544D03*
X1937900Y153600D03*
X1921264Y153000D03*
X1943752Y137548D03*
X1947078Y139300D03*
X1919484Y149500D03*
X1911961Y153000D03*
X1905092Y150170D03*
X1927000Y152200D03*
X1906414Y118004D03*
X1906467Y115305D03*
X1919702Y125920D03*
X1919195Y134396D03*
X1926952Y156049D03*
X1952726Y102950D03*
X1914500Y113300D03*
X1944609Y149184D03*
X1944600Y151700D03*
X1932998Y119438D03*
X1923329Y99475D03*
X1947000Y142600D03*
X1905540Y153000D03*
X1919702Y128501D03*
X1926892Y121203D03*
X1923837Y118800D03*
X1937728Y99441D03*
X1949389Y152083D03*
X1934000Y147100D03*
X1925358Y140685D03*
X1929756Y131037D03*
X1906871Y106049D03*
X1911231Y137097D03*
X1908715Y104512D03*
X1912100Y142600D03*
X1915030Y147250D03*
X1911440Y128840D03*
X1952440Y98520D03*
X1942637Y100877D03*
X1914152Y115928D03*
X1950983Y147344D03*
X1928100Y136078D03*
X1934544Y127957D03*
X1933914Y96040D03*
X1946770Y98150D03*
X1914690Y152580D03*
X1929736Y128337D03*
X1899855Y142122D03*
X1909216Y142812D03*
X1908327Y149353D03*
X1923800Y151000D03*
X1916310Y149676D03*
X1919514Y131701D03*
X1943660Y98180D03*
X1918002Y98902D03*
X1934256Y99459D03*
X1913392Y149381D03*
X1934100Y193400D03*
X1927064Y207564D03*
X1938400Y178200D03*
X1932837Y186700D03*
X1918489Y212513D03*
X1903917Y201472D03*
X1935600Y198700D03*
X1950981Y191218D03*
X1939200Y194300D03*
X1930500Y209464D03*
X1943500Y209500D03*
X1925000Y192000D03*
X1904042Y204895D03*
X1931483Y199350D03*
X1901100Y194200D03*
X1921500Y193600D03*
X1917024D03*
X1917568Y201215D03*
X1910123Y217349D03*
X1957334Y201269D03*
X1939300Y204300D03*
X1953200Y195530D03*
X1937100Y206800D03*
X1908967Y201609D03*
X1909186Y211906D03*
X1944500Y183900D03*
X1903524Y208156D03*
X1905074Y198163D03*
X1943200Y214800D03*
X1928400Y212500D03*
X1926000Y212400D03*
X1933898Y216707D03*
X1945156Y160236D03*
X1950994Y173745D03*
X1939316Y173600D03*
X1931639Y178396D03*
X1939550Y165600D03*
X1940647Y161600D03*
X1928218Y175443D03*
X1928249Y178179D03*
X1930300Y170147D03*
X1944550Y176450D03*
X1950981Y168064D03*
X1903150Y217250D03*
X1944300Y190200D03*
X1952717Y198614D03*
X1944611Y193400D03*
X1956901Y215241D03*
X1935600Y176300D03*
X1943217Y217645D03*
X1956901Y218391D03*
X1900740Y178720D03*
X1900700Y172990D03*
Y167290D03*
X1906440Y178720D03*
X1906500Y173100D03*
X1906400Y167290D03*
X1912190Y178870D03*
X1912230Y167330D03*
Y173030D03*
X1940500Y157600D03*
X1925400Y196300D03*
X1909438Y204307D03*
X1929700Y163400D03*
X1940240Y169970D03*
X1931065Y175520D03*
X1927500Y170400D03*
X1929000Y158600D03*
X1939400Y198400D03*
X1929090Y193190D03*
X1909421Y208805D03*
X1918143Y219848D03*
X1925835Y233735D03*
X1926100Y231200D03*
X1944463Y228458D03*
X1910340Y220741D03*
X1902907Y231294D03*
X1903032Y228368D03*
X1944925Y226001D03*
X1946105Y230344D03*
X1902909Y223195D03*
X1943517Y223637D03*
X1943800Y241800D03*
X1943900Y238500D03*
X1934750Y242700D03*
Y240300D03*
X1925600Y242700D03*
X1899816Y235035D03*
X1943217Y221154D03*
X1903020Y225776D03*
X1929000Y445800D03*
X1910500Y435600D03*
X1927100Y436200D03*
X1930100D03*
X1914173Y448200D03*
X1917700Y435600D03*
X1920700D03*
X1914700D03*
X1917322Y447930D03*
X1920472D03*
X1942000Y440500D03*
X1904724Y447930D03*
X1901574Y454422D03*
X1935300Y450600D03*
X1939845Y445055D03*
X1904724Y454422D03*
X1901574Y447930D03*
X1907500Y435600D03*
X1911023Y448400D03*
X1907874Y454422D03*
Y448400D03*
X1937430Y464785D03*
X1933100Y436200D03*
X1957212Y479521D03*
X1957100Y502990D03*
X1955790Y499790D03*
X1947380Y482450D03*
X1928620Y482710D03*
X1919230Y483430D03*
X1899100Y472600D03*
X1899200Y470200D03*
X1945000Y474000D03*
X1909800Y510700D03*
X1915100Y480050D03*
X1905010Y479410D03*
X1939000Y479400D03*
X1952500Y508000D03*
X1959260Y506010D03*
X1938410Y490650D03*
X1947550Y485350D03*
X1956500Y507470D03*
X1910500Y472000D03*
Y475000D03*
X1904200Y472700D03*
X1901700Y472600D03*
X1904300Y470300D03*
X1901800Y470200D03*
X1938300Y486250D03*
X1957250Y512050D03*
X1937300Y508900D03*
X1919510Y475100D03*
Y479200D03*
X1939000Y476600D03*
X1956300Y515900D03*
X1908300Y514500D03*
X1942328Y508712D03*
X1912800Y510700D03*
X1956606Y526671D03*
X1919000Y487210D03*
X1929480Y472880D03*
X1959300Y518000D03*
X1957063Y474769D03*
X1948200Y474300D03*
X1900890Y477200D03*
X1914750Y544863D03*
X1915050Y547900D03*
X1907200Y551600D03*
X1951900Y534900D03*
X1900250Y533700D03*
X1898850Y545250D03*
X1899800Y548100D03*
X1926600Y559500D03*
X1923600Y565100D03*
X1923000Y568700D03*
X1959120Y547050D03*
X1958940Y538890D03*
X1911000Y556700D03*
X1939800Y543700D03*
X1922500Y546700D03*
X1934600Y561900D03*
X1922000Y543750D03*
X1956191Y548700D03*
X1958500Y535000D03*
X1907500Y545600D03*
X1905000Y533900D03*
X1906050Y569100D03*
X1923600Y554200D03*
X1955400Y530500D03*
X1923600Y572300D03*
X1908400Y556800D03*
X1915593Y576807D03*
X1953500Y551900D03*
X1943300Y535700D03*
X1921244Y533750D03*
X1900729Y569557D03*
X1913800Y555500D03*
X1937250Y578200D03*
X1934400Y569400D03*
X1937200Y545100D03*
X1937300Y541600D03*
X1934200Y573700D03*
Y577700D03*
X1939700Y540900D03*
X1935400Y583000D03*
X1940800Y537300D03*
X1945900Y549900D03*
X1932800Y564300D03*
X1935400Y550800D03*
X1936900Y568000D03*
X1937800Y549700D03*
X1923500Y579500D03*
X1939800Y546300D03*
X1948100Y538700D03*
X1923400Y583000D03*
X1923600Y575500D03*
X1921800Y586100D03*
X1918880Y586460D03*
X1932390Y590100D03*
X1936770Y607210D03*
X1938130Y601480D03*
X1938000Y597320D03*
X1937870Y594480D03*
X1923504Y592500D03*
X1911750Y592800D03*
X1927000Y614500D03*
X1914700Y594600D03*
X1930500Y618900D03*
Y616100D03*
X1906200Y607800D03*
X1916050Y604450D03*
X1924000Y611391D03*
X1922900Y604450D03*
X1919900Y604550D03*
X1959400Y601100D03*
X1934350Y609250D03*
X1968179Y77969D03*
X1965679D03*
Y75369D03*
X1968179D03*
X1965679Y82969D03*
Y80469D03*
X1968179D03*
X1966212Y72897D03*
X1970679Y75369D03*
Y80469D03*
Y77969D03*
X1962800Y143700D03*
X1971200Y152500D03*
X1965400Y149700D03*
X1973328Y147303D03*
X1963400Y141100D03*
X1967580Y104721D03*
X1973004Y143120D03*
X1964382Y147318D03*
X1962800Y149300D03*
X1966700Y152400D03*
X1961472Y165760D03*
X1963300Y191000D03*
X1967817Y201029D03*
X1965900Y184600D03*
X1965057Y176447D03*
X1966542Y179606D03*
X1965973Y166190D03*
X1972598Y165236D03*
X1963092Y167936D03*
X1970270Y474640D03*
X1968870Y481710D03*
X1970500Y502720D03*
X1963500Y521000D03*
X1967200Y521600D03*
X1964270Y511410D03*
X1968375Y509375D03*
X1964890Y534940D03*
X1961500Y561700D03*
Y582700D03*
X1972700Y552700D03*
X1963000Y573000D03*
X1963097Y551000D03*
X1972700Y576400D03*
Y549950D03*
X1972800Y536800D03*
Y565200D03*
X1962950Y566600D03*
X1961715Y555639D03*
X1962500Y578500D03*
X1961700Y616700D03*
Y619500D03*
X1965400D03*
X1973000Y597200D03*
X1961771Y591744D03*
X1963300Y612800D03*
X2088977Y1778952D03*
G54D21*
X12290Y264640D03*
X18450Y267010D03*
X22970Y244400D03*
X28720Y244450D03*
X17120Y244220D03*
X24200Y267060D03*
X2088977Y1342152D03*
G54D22*
X40512Y458744D03*
X2088977Y233352D03*
G54D31*
X133563Y183126D03*
Y419626D03*
X783171Y183126D03*
Y419626D03*
X1454685Y338189D03*
X1600355Y527165D03*
X2088977Y31752D03*
G54D40*
X1466693Y375787D03*
X1572599Y505315D03*
X2088977Y535752D03*
G54D13*
X-15748Y101221D03*
Y116969D03*
Y132717D03*
Y148465D03*
Y357362D03*
Y373110D03*
Y388858D03*
Y404606D03*
X12205Y156339D03*
X-4331D03*
X17323Y101221D03*
Y116969D03*
Y132717D03*
Y148465D03*
X787Y101221D03*
Y116969D03*
Y132717D03*
Y148465D03*
X33858Y101221D03*
Y116969D03*
Y132717D03*
Y148465D03*
X28740Y109095D03*
Y124843D03*
Y140591D03*
Y156339D03*
X12205Y109095D03*
Y124843D03*
Y140591D03*
X-4331Y109095D03*
Y124843D03*
Y140591D03*
X17323Y357362D03*
Y373110D03*
Y388858D03*
Y404606D03*
X787Y357362D03*
Y373110D03*
Y388858D03*
Y404606D03*
X33858Y357362D03*
Y373110D03*
Y388858D03*
Y404606D03*
X28740Y365236D03*
Y380984D03*
Y396732D03*
X12205Y365236D03*
Y380984D03*
Y396732D03*
X-4331Y365236D03*
Y380984D03*
Y396732D03*
X12205Y412480D03*
X-4331D03*
X28740D03*
X2088977Y1510152D03*
G54D14*
X-15354Y109095D03*
Y124843D03*
Y140591D03*
Y156339D03*
Y365236D03*
Y380984D03*
Y396732D03*
Y412480D03*
X22835Y101221D03*
X6299D03*
X-10236D03*
X17716Y109095D03*
X1181D03*
X22835Y116969D03*
X6299D03*
X1181Y124843D03*
X22835Y132717D03*
X1181Y140591D03*
X22835Y148465D03*
X6299D03*
X-10236D03*
X17716Y156339D03*
X1181D03*
X-10236Y116969D03*
X-4725D03*
X23228Y124843D03*
X17716D03*
X-10236Y132717D03*
X-4725D03*
X6299D03*
X11811D03*
X17716Y140591D03*
X23228D03*
X-9843Y156339D03*
X23228Y109095D03*
X6693D03*
Y124843D03*
X-9843Y109095D03*
Y124843D03*
X-4725Y101221D03*
X11811Y148465D03*
Y101221D03*
Y116969D03*
X28346Y101221D03*
Y116969D03*
Y132717D03*
X6693Y140591D03*
X-9843D03*
X28346Y148465D03*
X6693Y156339D03*
X-4725Y148465D03*
X23228Y156339D03*
X22835Y357362D03*
X6299D03*
X-10236D03*
X17716Y365236D03*
X1181D03*
X22835Y373110D03*
X6299D03*
X1181Y380984D03*
X22835Y388858D03*
X1181Y396732D03*
X22835Y404606D03*
X6299D03*
X-10236D03*
Y373110D03*
X-4725D03*
X23228Y380984D03*
X17716D03*
X-10236Y388858D03*
X-4725D03*
X6299D03*
X11811D03*
X17716Y396732D03*
X23228D03*
Y365236D03*
X6693D03*
Y380984D03*
X-9843Y365236D03*
Y380984D03*
X-4725Y357362D03*
X11811Y404606D03*
Y357362D03*
Y373110D03*
X28346Y357362D03*
Y373110D03*
Y388858D03*
X6693Y396732D03*
X-9843D03*
X28346Y404606D03*
X-4725D03*
X17716Y412480D03*
X1181D03*
X-9843D03*
X6693D03*
X23228D03*
X2088977Y1610952D03*
G54D41*
X1526871Y23968D03*
X1881595D03*
X2088977Y1006152D03*
G54D50*
X1712012Y195587D03*
X2088977Y266952D03*
G54D23*
X-4488Y425472D03*
X99980Y136909D03*
X2088977Y401352D03*
G54D32*
X224410Y301378D03*
X326772Y163582D03*
Y439173D03*
X500000Y163582D03*
Y439173D03*
X602362Y214764D03*
Y387992D03*
X874016Y301378D03*
X976378Y163582D03*
Y439173D03*
X1149606Y163582D03*
Y439173D03*
X1251969Y214764D03*
Y387992D03*
X2088977Y-1848D03*
G54D51*
X1699600Y235400D03*
Y454297D03*
X1866923Y235400D03*
X1955506Y454297D03*
X2088977Y-270648D03*
G54D33*
X267859Y209109D03*
X271239Y203260D03*
X277999Y218860D03*
X281379Y209109D03*
X288139Y201309D03*
Y209109D03*
X277999Y199360D03*
X274619Y201309D03*
Y209109D03*
Y205210D03*
X271239Y207159D03*
X264092Y242260D03*
X271239D03*
X267859Y248109D03*
X264179Y261760D03*
X271239D03*
Y253960D03*
X288139Y228610D03*
X277999Y226660D03*
X288139Y220809D03*
X281379Y236409D03*
X284759Y250060D03*
X288139Y240309D03*
X281379Y244209D03*
X277999Y257860D03*
X288139Y267609D03*
Y259809D03*
X277999Y265660D03*
X274619Y271509D03*
X291519Y273460D03*
X277999D03*
X288139Y322209D03*
X281379D03*
X284759Y335860D03*
X277999D03*
X288139Y330009D03*
X281379Y341709D03*
Y330009D03*
X271239Y339760D03*
X291519Y320260D03*
X284759D03*
X291519Y324160D03*
X277999D03*
X264179Y331960D03*
X271239D03*
Y394359D03*
X267859Y392410D03*
X271239Y398260D03*
X284759Y355360D03*
X274619Y400209D03*
X281379D03*
X277999Y398260D03*
X274619Y396309D03*
X288139Y388509D03*
X291519Y394359D03*
X281379Y388509D03*
X284759Y394359D03*
X277999Y355360D03*
X284759Y347560D03*
X281379Y361209D03*
X284759Y374860D03*
X271239Y347560D03*
X264179D03*
X277999Y374860D03*
X288139Y369010D03*
X281379Y380709D03*
Y369010D03*
X267859Y345609D03*
X308418Y216909D03*
X294899D03*
X301659D03*
X294899Y205210D03*
Y197409D03*
X352357Y218860D03*
X345598D03*
X338838Y214960D03*
X342218Y216909D03*
X338838Y207158D03*
Y203258D03*
X345598Y211060D03*
X348978Y213009D03*
X342218Y205210D03*
X298279Y222760D03*
X305039D03*
X328698Y236409D03*
Y244209D03*
X321938Y240309D03*
X294899Y232509D03*
X301659Y244209D03*
Y232509D03*
X318558Y222760D03*
X311798Y234460D03*
X305039Y238360D03*
X294899Y240309D03*
X311798Y226660D03*
X318558Y230559D03*
X332078Y222760D03*
X328698Y224709D03*
Y228610D03*
X332078Y230560D03*
X311798Y242260D03*
X315178Y248109D03*
X308418D03*
X305039Y257860D03*
X328698Y255909D03*
X325318Y261760D03*
X294899Y252009D03*
X301659Y263709D03*
Y252009D03*
X294899Y259809D03*
X332078Y261760D03*
X315178Y271509D03*
X311798Y265660D03*
X321938Y271509D03*
X308418D03*
X318558Y265660D03*
X294899Y271509D03*
Y267609D03*
X332078Y273460D03*
X298279D03*
X328698Y275409D03*
X332078Y277360D03*
X325318D03*
X328698Y279310D03*
X321938D03*
X301659Y271509D03*
X328698D03*
X298279Y269560D03*
X342218Y224709D03*
X345598Y230559D03*
X348978Y224709D03*
X355737D03*
X352357Y230559D03*
X335458Y220809D03*
X345598Y222760D03*
X335458Y228610D03*
X338838Y230560D03*
Y273460D03*
Y269560D03*
X335458Y275409D03*
X338838Y277360D03*
X335458Y279310D03*
Y271509D03*
X348978Y236409D03*
X355737D03*
X342218D03*
X332078Y226660D03*
X315178Y244209D03*
X311798Y246160D03*
X321938Y252009D03*
X345598Y242260D03*
X335458Y232510D03*
X352357Y250060D03*
X345598D03*
X342218Y248109D03*
X335458Y240309D03*
X338838Y261760D03*
X335458Y255909D03*
X355737Y252009D03*
X348978D03*
X352357Y253960D03*
X345598D03*
X355737Y255909D03*
X348978D03*
X345598Y261760D03*
X348978Y259809D03*
X345598Y257860D03*
X352357D03*
X342218Y252009D03*
X338838Y250060D03*
X345598Y234460D03*
X352357Y242260D03*
X298279Y320260D03*
X294899Y330009D03*
X352357Y339760D03*
X355737Y341709D03*
X298279Y335860D03*
X321938Y326110D03*
X311798Y331960D03*
X325318D03*
X315178Y326110D03*
X318558Y331960D03*
X335458Y341709D03*
X301659D03*
X294899D03*
X305039Y335860D03*
X338838D03*
X328698Y341709D03*
X342218D03*
X332078Y335860D03*
X298279Y324160D03*
X294899Y326109D03*
X321938Y341709D03*
X335458Y322209D03*
X332078Y370959D03*
X328698Y369010D03*
X294899Y400209D03*
X315178Y384609D03*
Y380709D03*
X332078Y374860D03*
X328698Y372909D03*
X355737Y345609D03*
X335458Y369010D03*
X338838Y363160D03*
X352357Y343660D03*
X348978Y384609D03*
X335458Y376809D03*
X345598Y374860D03*
X301659Y361209D03*
X332078Y351460D03*
X321938Y357309D03*
X335458D03*
X325318Y351460D03*
X301659Y380709D03*
X328698Y361209D03*
X305039Y374860D03*
X294899Y380709D03*
X308418D03*
X298279Y374860D03*
X345598Y386560D03*
X341892Y396301D03*
X311798Y363160D03*
X318558Y374860D03*
Y363160D03*
X294899Y361209D03*
X305039Y355360D03*
X298279Y367060D03*
X342218Y369010D03*
Y357309D03*
X345598Y363160D03*
Y351460D03*
X348978Y357309D03*
Y369010D03*
X355737Y380709D03*
X352357Y374860D03*
X294899Y388509D03*
X338838Y374860D03*
X348978Y380709D03*
X351192Y402800D03*
X342218Y380709D03*
X355737Y357309D03*
Y369010D03*
X352357Y363160D03*
Y351460D03*
X315178Y369010D03*
X298279Y355360D03*
Y347560D03*
X321938Y369010D03*
X308418Y349509D03*
X332078Y367060D03*
X321938Y345609D03*
X342218Y349509D03*
X345598Y347560D03*
X335458Y365109D03*
X352357Y347560D03*
X365877Y218860D03*
X372637D03*
X386157Y211060D03*
X379397Y207159D03*
Y218860D03*
X359117Y211060D03*
Y218860D03*
X386157D03*
X357987Y193507D03*
X378267D03*
X372637Y211060D03*
X399676D03*
X392916D03*
X399676Y218860D03*
X407706Y216909D03*
X392916Y218860D03*
X376017Y224709D03*
X369257D03*
X362497D03*
X389537D03*
X382777D03*
X396296D03*
X407706Y236409D03*
Y244209D03*
X415634Y243496D03*
Y231797D03*
X396296Y236409D03*
X359117Y230559D03*
X379397Y234460D03*
X386157Y230559D03*
X407706Y224709D03*
X392916Y230559D03*
X399676D03*
X389537Y236409D03*
X362497D03*
X369257D03*
X365877Y230559D03*
X372637D03*
X365877Y242260D03*
X372637D03*
X362497Y248109D03*
X359117Y250060D03*
X389537Y240309D03*
X382777D03*
X386157Y242260D03*
X379397D03*
X389537Y244209D03*
X382777D03*
X376017D03*
X386157Y246160D03*
X379397D03*
X372637D03*
X365877D03*
X369257Y248109D03*
X365877Y250060D03*
X359117Y253960D03*
X362497Y252009D03*
X399676Y242260D03*
X392916D03*
Y246160D03*
X396296Y244209D03*
Y240309D03*
X359117Y242260D03*
X389537Y357309D03*
X365877Y351460D03*
X372637D03*
X362497Y345609D03*
X359117Y343660D03*
X403056Y396309D03*
X411086Y394359D03*
X399676Y386560D03*
X411086D03*
Y382660D03*
Y378760D03*
X398546Y402900D03*
X402892Y400400D03*
X403056Y369010D03*
X399676Y363160D03*
X382777Y369010D03*
X365877Y363160D03*
X372637D03*
X362497Y369010D03*
X369257D03*
X389537Y380709D03*
X392916Y374860D03*
X359117D03*
Y386560D03*
X379397Y374860D03*
X382777Y380709D03*
X369257D03*
X379397Y386560D03*
X399676Y374860D03*
X403056Y380709D03*
X386157Y386560D03*
X396296Y369010D03*
X386157Y374860D03*
X376017Y380709D03*
X365877Y374860D03*
X372637D03*
X362497Y380709D03*
X396296D03*
X392916Y386560D03*
X372637D03*
X376017Y369010D03*
X389537D03*
X392916Y363160D03*
X386157D03*
X359117Y351460D03*
Y363160D03*
X362497Y357309D03*
X379397Y363160D03*
X369257Y357309D03*
X379397Y351460D03*
X362497Y349509D03*
X376017D03*
X382777Y353409D03*
Y357309D03*
X379397Y355360D03*
X359117Y347560D03*
X396296Y357309D03*
X399676Y355360D03*
X369257Y361209D03*
X376017Y357309D03*
X419214Y218147D03*
X436113Y235696D03*
Y220096D03*
Y227896D03*
X446253Y222047D03*
Y225947D03*
X432733Y222047D03*
Y225947D03*
X442873Y220096D03*
Y227896D03*
X453013Y225947D03*
X439493Y229847D03*
Y222047D03*
Y225947D03*
X425974Y222047D03*
X419214Y225947D03*
X442873Y235696D03*
X429354Y231797D03*
X449633D03*
Y239596D03*
X452865Y270081D03*
X439764Y263699D03*
X449288Y266435D03*
X444752Y264188D03*
X453013Y253247D03*
X463153Y220096D03*
Y227896D03*
X473292Y222047D03*
Y225947D03*
X459773Y229847D03*
Y222047D03*
X466533Y241547D03*
X463153Y235696D03*
X473292Y241547D03*
X469913Y235696D03*
X456393D03*
Y247396D03*
X463153D03*
X476672D03*
X456393Y220096D03*
X466533Y225947D03*
Y253247D03*
X473292D03*
X459773D03*
X476672Y262996D03*
X469913Y266896D03*
X422594Y235696D03*
Y247396D03*
X429354Y239596D03*
X476672Y220096D03*
Y235696D03*
X447800Y335900D03*
X466066Y292452D03*
X466734Y287074D03*
X466100Y300021D03*
X471033Y339047D03*
X430474Y358547D03*
X433854Y356596D03*
X467653Y379996D03*
X443993Y354647D03*
X460893Y368296D03*
X450753Y374146D03*
X464273D03*
X454133Y368296D03*
X423714Y366347D03*
Y358547D03*
X437233Y366347D03*
X477792Y374146D03*
X427094Y387796D03*
X471033Y374146D03*
X474413Y368296D03*
X430474Y381947D03*
X423714Y378047D03*
X433854Y387796D03*
X423714Y393647D03*
X467653Y387796D03*
X447373Y383896D03*
X460893D03*
X474413D03*
X450753Y389747D03*
X440613Y383896D03*
X454133D03*
X443993Y389747D03*
X467653Y360496D03*
X447373D03*
X457513Y374146D03*
X430474Y362447D03*
Y370247D03*
X471033Y354647D03*
X460893Y360496D03*
X474413D03*
X464273Y354647D03*
X450753D03*
X440613Y360496D03*
X454133D03*
X443993Y370247D03*
X437233Y378047D03*
X440613Y376096D03*
X443993Y374147D03*
X464273Y342947D03*
X457513Y350747D03*
X460893Y344896D03*
X474413D03*
X518352Y210345D03*
X528491Y212296D03*
X494692D03*
X501452Y216196D03*
X504832Y218147D03*
X511592Y214247D03*
X514972Y216196D03*
X518352Y214247D03*
X531871D03*
X514972Y212296D03*
Y208397D03*
X521731Y212296D03*
X525111Y210346D03*
X504832Y214247D03*
X498072D03*
X508212Y216196D03*
X535251Y212296D03*
X483432Y216196D03*
X480052Y210346D03*
X483432Y212296D03*
X531871Y202547D03*
X525111D03*
X483432Y247396D03*
X508212Y243496D03*
X486812Y253247D03*
X480052D03*
X491312Y272747D03*
X494692Y266896D03*
X528491Y259096D03*
X483432Y220096D03*
X480052Y222047D03*
X501452Y251296D03*
Y255196D03*
X491312Y280547D03*
X486812Y261047D03*
X483432Y262996D03*
X498072Y280547D03*
X511592Y272747D03*
X504832Y276647D03*
X498072D03*
X491312D03*
X511592D03*
X504832Y272747D03*
X498072Y253247D03*
Y257147D03*
X504832Y280547D03*
X511592D03*
X498072Y272747D03*
X501452Y262996D03*
X498072Y261047D03*
X494692Y259096D03*
X525111Y249347D03*
X528491Y251296D03*
X525111Y241547D03*
X528491Y239596D03*
X531871Y253247D03*
X521731Y262996D03*
X525111Y264947D03*
X528491Y266896D03*
X521731Y278596D03*
X518352Y280547D03*
Y276646D03*
X484552D03*
X504832Y249347D03*
X501452Y270796D03*
X518352Y268847D03*
X538631Y276646D03*
Y245447D03*
X535251Y274696D03*
X494692Y239596D03*
Y231797D03*
X504832Y237647D03*
X508212Y227896D03*
X525111Y233746D03*
X511592Y237647D03*
X538631Y268847D03*
Y264947D03*
X531871Y245447D03*
X501452Y243496D03*
X535251Y262996D03*
X538631Y253247D03*
X531871Y280547D03*
X538631Y241547D03*
X521731Y270796D03*
X504832Y257147D03*
X508212Y251296D03*
X518352Y225947D03*
X531871Y233746D03*
Y225947D03*
X538631Y233746D03*
X531871Y272747D03*
X501452Y227896D03*
X514972Y231797D03*
X525111Y225947D03*
X494692Y220096D03*
X535251D03*
X504832Y222047D03*
X538631Y272747D03*
X483432Y231797D03*
X480052Y225947D03*
X483432Y239596D03*
X504832Y307847D03*
X487932Y305896D03*
X491312Y303947D03*
X501452Y305896D03*
X494692Y298096D03*
X498072Y307847D03*
X484552Y303947D03*
X487932Y294196D03*
X491312Y296147D03*
X494692Y301996D03*
X487932D03*
X501452Y309797D03*
X487932Y298096D03*
X511592Y311747D03*
Y303947D03*
X481172Y321496D03*
X487932Y313696D03*
X481172Y325396D03*
X491312Y315647D03*
X481172Y317596D03*
X518352Y311747D03*
X528491Y305896D03*
X484552Y311747D03*
X481172Y286396D03*
X491312Y288347D03*
Y284447D03*
X498072D03*
Y288347D03*
X501452Y286396D03*
X494692Y290296D03*
X498072Y292247D03*
X504832D03*
X508212Y282496D03*
X504832Y288347D03*
Y284447D03*
X494692Y282496D03*
X508212Y286396D03*
X511592Y292245D03*
X484552Y319546D03*
X481172Y333196D03*
X484552Y331247D03*
X514972Y282496D03*
X521731D03*
X518352Y284447D03*
X538631Y307847D03*
Y303947D03*
Y300047D03*
X535251Y298096D03*
Y305896D03*
X538631Y296147D03*
X531871D03*
X535251Y317596D03*
X525111Y315647D03*
X531871D03*
X535251Y313696D03*
X538631Y315647D03*
X528491Y282496D03*
X535251Y286396D03*
Y282496D03*
X501452Y337096D03*
X538631Y331247D03*
Y327347D03*
X535251Y340996D03*
Y337096D03*
X528491Y340996D03*
X531871Y339047D03*
Y331247D03*
X538631Y323446D03*
X525111Y319547D03*
X518352Y335147D03*
X521731Y333196D03*
Y329296D03*
X525111Y331247D03*
X528491Y333196D03*
X521731Y340996D03*
X525111Y323446D03*
X528491Y325396D03*
Y329296D03*
Y321496D03*
X531871Y323446D03*
X525111Y327347D03*
X521731Y337096D03*
X484552Y342947D03*
X481172Y364396D03*
Y383896D03*
X535251Y376096D03*
X518352Y401447D03*
X504832Y385847D03*
Y393647D03*
X508212Y376096D03*
X498072Y370247D03*
X504832D03*
X501452Y372197D03*
X487932Y356596D03*
X491312Y342947D03*
Y354647D03*
X511592Y389747D03*
Y401447D03*
X508212Y383896D03*
X504832Y401446D03*
X535251Y348796D03*
Y344896D03*
X538631Y346847D03*
Y342947D03*
X535251Y360496D03*
X531871Y358547D03*
X535251Y364396D03*
Y368296D03*
X525111Y346847D03*
X528491Y348796D03*
X531871Y342947D03*
X528491Y344896D03*
Y352696D03*
X538631Y354647D03*
Y358547D03*
Y362447D03*
X531871D03*
Y366347D03*
X535251Y372197D03*
X538631Y350747D03*
X535251Y379996D03*
X538631Y374146D03*
X531871Y378047D03*
X514972Y376096D03*
X528491Y387796D03*
X521731D03*
Y391696D03*
X518352Y393647D03*
X514972Y395597D03*
X528491Y379996D03*
Y383896D03*
X525111Y385847D03*
X521731Y383896D03*
X525111Y389747D03*
X521731Y395597D03*
X514972Y391696D03*
Y387796D03*
X528491Y376096D03*
X531871Y381947D03*
X494692Y387796D03*
X514972Y364396D03*
X518352Y350747D03*
X504832Y374146D03*
X508212Y368296D03*
X514972Y360496D03*
X508212Y372197D03*
X511592Y354647D03*
X498072Y378047D03*
Y381947D03*
X518352Y354647D03*
X511592Y366347D03*
X494692Y379996D03*
X501452Y376096D03*
X511592Y362447D03*
X508212Y364396D03*
X514972Y368296D03*
X511592Y358547D03*
X498072Y374146D03*
X521731Y352696D03*
X494692Y383896D03*
X518352Y346847D03*
X484552Y374146D03*
X487932Y383896D03*
X491312Y393647D03*
X494692Y399496D03*
X484552Y389747D03*
X518352Y405347D03*
X566051Y211555D03*
X562861Y205503D03*
X545391Y214247D03*
Y218147D03*
X548771Y216196D03*
X542011Y212296D03*
X552151Y237647D03*
X542011Y231797D03*
X548771D03*
X552151Y280547D03*
X548771Y274696D03*
Y220096D03*
X555531D03*
Y227896D03*
X542011Y278596D03*
Y262996D03*
X555531Y270796D03*
X552151Y264947D03*
X542011Y259096D03*
X545391Y257147D03*
Y249347D03*
X548771Y223996D03*
X542011Y243496D03*
X552151Y222047D03*
X562616Y223996D03*
X542011Y251296D03*
X545391Y245447D03*
X555531Y243496D03*
Y259096D03*
X552151Y253247D03*
X548771Y259096D03*
X562640Y231735D03*
X542011Y220096D03*
X548771Y305896D03*
X552151Y300047D03*
X548771Y301996D03*
X552151Y307847D03*
Y303947D03*
X555831Y301996D03*
X548771Y298096D03*
X542011Y317596D03*
Y309797D03*
X545391Y311747D03*
X542011Y305896D03*
Y301996D03*
X552151Y311747D03*
X542011Y313696D03*
X548771Y321496D03*
X545391Y323446D03*
X552151Y319547D03*
Y315647D03*
X559211Y331103D03*
X555531Y329296D03*
X559211Y323446D03*
X555531Y321496D03*
X548771Y317596D03*
X555831Y313696D03*
X559211Y327347D03*
X552151D03*
X555531Y325396D03*
X555831Y317446D03*
X552151Y292245D03*
X559211Y284447D03*
X542011Y290296D03*
X560884D03*
X542011Y282496D03*
X552151Y331247D03*
Y335147D03*
X548771Y333196D03*
X552151Y339047D03*
X555531Y340996D03*
X542011D03*
Y337096D03*
X545391Y327347D03*
Y339047D03*
X542011Y333196D03*
Y329296D03*
Y325396D03*
X562591Y340996D03*
X558911Y339047D03*
X562591Y337096D03*
X555531D03*
X545391Y389747D03*
X542011Y391696D03*
Y395597D03*
Y387796D03*
X545391Y393647D03*
X552151Y366347D03*
Y370247D03*
X563500Y360500D03*
X555531Y372197D03*
X548771Y364396D03*
X552151Y393647D03*
X559212Y389747D03*
X548990Y403670D03*
X555750Y399770D03*
X552151Y342947D03*
X548771Y344896D03*
X552151Y346847D03*
X542011Y344896D03*
Y356596D03*
X559211Y366347D03*
X558911Y354647D03*
X552151Y362447D03*
X545391Y350747D03*
X548771Y348796D03*
X555531Y352696D03*
Y348796D03*
X552151Y354647D03*
X558911Y350747D03*
X555531Y344896D03*
X548771Y387796D03*
X552151Y385847D03*
X555531Y379996D03*
X552151Y381947D03*
X660600Y170000D03*
X670600Y144900D03*
Y150000D03*
X680200Y432100D03*
X746130Y430130D03*
X930987Y209109D03*
X937747Y201309D03*
Y209109D03*
X927607Y199360D03*
X924227Y201309D03*
Y209109D03*
Y205210D03*
X930987Y216909D03*
X934367Y203260D03*
Y211060D03*
X958026Y216909D03*
X944507D03*
X951267Y213009D03*
Y216909D03*
X944507Y197409D03*
Y205210D03*
Y209109D03*
X930987Y248109D03*
X937747Y244209D03*
X927607Y246160D03*
X934367Y242260D03*
X930987Y228610D03*
X937747D03*
X927607Y222760D03*
X913700Y242260D03*
X920847D03*
Y250060D03*
X927607Y226660D03*
X917467Y248109D03*
X934367Y222760D03*
X927607Y238360D03*
X934367Y250060D03*
Y238360D03*
X917467Y271509D03*
X927607Y273460D03*
X924227Y271509D03*
X913787Y257860D03*
X920847Y261760D03*
Y253960D03*
X930987Y255909D03*
X934367Y269560D03*
X937747Y267609D03*
X927607Y261760D03*
X937747Y259809D03*
X934367Y261760D03*
X930987Y263709D03*
X947887Y222760D03*
X954647D03*
X951267Y220809D03*
X971546Y240309D03*
Y244209D03*
X961406Y242260D03*
X964786Y244209D03*
X961406Y246160D03*
X964786Y248109D03*
X958026D03*
X968166Y250060D03*
X971546Y279310D03*
X944507Y271509D03*
X964786Y263709D03*
Y275409D03*
X961406Y265660D03*
X971546Y271509D03*
X958026D03*
X968166Y265660D03*
Y273460D03*
X944507Y267609D03*
X947887Y269560D03*
X951267Y271509D03*
X947887Y273460D03*
X941127D03*
X944507Y232509D03*
X971546Y228610D03*
X968166Y222760D03*
X951267Y232509D03*
Y252009D03*
Y244209D03*
X947887Y257860D03*
X968166Y230559D03*
X964786Y228610D03*
X944507Y259809D03*
X954647Y234460D03*
X961406Y226660D03*
X944507Y240309D03*
X954647Y253960D03*
Y238360D03*
Y261760D03*
X951267Y263709D03*
X947887Y250060D03*
X944507Y252009D03*
X964786Y236409D03*
X961406Y234460D03*
X954647Y257860D03*
X968166Y234460D03*
X971546Y252009D03*
X913787Y335860D03*
X920847Y331960D03*
Y339760D03*
X930987Y330009D03*
Y341709D03*
X937747Y330009D03*
X927607Y335860D03*
X934367D03*
Y320260D03*
X927607Y324160D03*
X947887Y335860D03*
X954647D03*
X944507Y341709D03*
X951267D03*
X968166Y331960D03*
X964786Y326110D03*
X947887Y320260D03*
X941127D03*
X944507Y330009D03*
X961406Y331960D03*
X971546Y326110D03*
Y341709D03*
X944507Y326110D03*
X937747Y322209D03*
X930987D03*
X947887Y324160D03*
X941127D03*
X934367Y367060D03*
X913787Y351460D03*
X920847D03*
X927607Y370959D03*
X917467Y345609D03*
X934367Y347560D03*
X927607Y359260D03*
X934367Y355360D03*
X927607Y351460D03*
X937747Y372909D03*
X927607Y378760D03*
X934367D03*
Y386560D03*
X930987Y392410D03*
X937747Y396309D03*
X930987Y400209D03*
X917467Y392410D03*
X924227Y396309D03*
X971546Y357309D03*
X951267Y365109D03*
Y353409D03*
X944507Y365109D03*
X961406Y367060D03*
X964786Y361209D03*
X947887Y347560D03*
X954647Y359260D03*
X971546Y345609D03*
X944507Y357309D03*
X971546Y365109D03*
X958026Y349509D03*
X947887Y382660D03*
X958026Y376809D03*
X944507D03*
X954647Y382660D03*
X951267Y372909D03*
X944507Y392410D03*
X941127Y386560D03*
X971546Y372909D03*
X964786D03*
X944507Y400209D03*
X964786Y384609D03*
Y380709D03*
X991826Y213009D03*
X988446Y214960D03*
X991826Y216909D03*
X988446Y207158D03*
Y203258D03*
X995206Y211060D03*
X998586Y213009D03*
X1025625Y216909D03*
X1015485Y218860D03*
X1022245D03*
X1032385Y213009D03*
X1029005Y207159D03*
X1012105Y213009D03*
X1008725Y218860D03*
X1005345Y216909D03*
X1025625Y213009D03*
X991826Y209109D03*
X995206Y207159D03*
X1022245D03*
X1005345Y213009D03*
X1029005Y218860D03*
X1001965D03*
X1018865Y213009D03*
X995206Y218860D03*
X978306Y236409D03*
Y240309D03*
Y244209D03*
X974926Y246160D03*
X985066Y240309D03*
X981686Y246160D03*
X991826Y224709D03*
X988446Y222760D03*
X998586Y228610D03*
X985066Y220809D03*
X981686Y222760D03*
X978306Y224709D03*
X981686Y226660D03*
X985066Y228610D03*
X978306D03*
X981686Y230559D03*
X985066Y232509D03*
X995206Y250060D03*
X998586Y252009D03*
X995206Y253960D03*
X998586Y255909D03*
X995206Y257860D03*
X998586Y259809D03*
X995206Y261760D03*
X988446Y269560D03*
X985066Y271509D03*
X978306D03*
X988446Y273460D03*
X981686D03*
X985066Y275409D03*
X978306D03*
X988446Y277360D03*
X981686D03*
X974926D03*
X985066Y279310D03*
X978306D03*
X1025625Y224709D03*
X1022245Y222760D03*
X1018865Y224709D03*
X1012105D03*
X1032385D03*
X1029005Y222760D03*
X1005345Y224709D03*
X1001965Y230559D03*
X1012105Y248109D03*
X1008725Y250060D03*
X1001965D03*
X1032385Y240309D03*
X1029005Y242260D03*
X1032385Y244209D03*
X1025625D03*
X1029005Y246160D03*
X1022245D03*
X1015485D03*
X1018865Y248109D03*
X1015485Y250060D03*
X1005345Y252009D03*
X1008725Y253960D03*
X1001965D03*
X1005345Y255909D03*
X1001965Y257860D03*
X1012105Y252009D03*
X985066Y263709D03*
X988446Y257860D03*
X1022245Y242260D03*
X1018865Y228610D03*
X1012105Y236409D03*
X1018865D03*
X1015485Y230559D03*
X1022245D03*
X991826Y236409D03*
Y228610D03*
X995206Y242260D03*
X1015485D03*
X1029005Y230559D03*
X998586Y236409D03*
Y224709D03*
X1008725Y246160D03*
X1001965Y242260D03*
X1005345Y236409D03*
X1008725Y230559D03*
Y242260D03*
X1001965Y246160D03*
X1025625Y236409D03*
X981686Y257860D03*
Y265660D03*
Y253960D03*
X974926Y261760D03*
Y257860D03*
X978306Y263709D03*
X1032385Y236409D03*
X995206Y222760D03*
X1022245Y234460D03*
X991826Y240309D03*
X995206Y234460D03*
X1008725D03*
X1032385Y228610D03*
X998586Y337809D03*
X991826D03*
X978306D03*
X985066Y333909D03*
X974926Y331960D03*
X1001965Y339760D03*
X1005345Y341709D03*
X998586D03*
X978306Y361209D03*
X974926Y351460D03*
X981686D03*
X995206Y367060D03*
X988446Y370959D03*
X981686Y343660D03*
X991826Y349509D03*
X995206Y347560D03*
X981686Y370959D03*
X978306Y369010D03*
X985066D03*
Y365109D03*
X988446Y363160D03*
X995206Y378760D03*
X998586Y372909D03*
X988446Y378760D03*
X998586Y384609D03*
X985066Y376809D03*
X981686Y374860D03*
X995206D03*
X991826Y384609D03*
X991500Y396301D03*
X1032385Y357309D03*
X1022245Y351460D03*
X1029005D03*
X1001965Y347560D03*
X1012105Y345609D03*
X1015485Y347560D03*
X1008725D03*
X1001965Y367060D03*
X1015485Y355360D03*
X1008725Y367060D03*
X1022245Y390460D03*
X1000800Y402800D03*
X1025625Y372909D03*
X1018865Y384609D03*
Y372909D03*
X1012105D03*
X1022245Y378760D03*
X1032385Y384609D03*
X1001965Y378760D03*
X1032385Y372909D03*
X1029005Y378760D03*
X1012105Y384609D03*
X1008725Y378760D03*
X1005345Y372909D03*
Y384609D03*
X1025625D03*
X988446Y343660D03*
X1015485Y378760D03*
Y367060D03*
X1022245D03*
X1012105Y361209D03*
X1018865D03*
X991826D03*
X998586D03*
X1029005Y367060D03*
X995206Y355360D03*
X1001965D03*
X1005345Y361209D03*
X1008725Y355360D03*
X1025625Y361209D03*
X1032385D03*
X985066Y357309D03*
X998586Y345609D03*
X981686Y367060D03*
X978306Y372909D03*
X1029005Y355360D03*
X1015485Y351460D03*
X1012105Y349509D03*
X1025625D03*
X1001965Y343660D03*
X1018865Y369010D03*
X995206Y363160D03*
X1032385Y369010D03*
X1049284Y218860D03*
X1057314Y216909D03*
X1035765Y218860D03*
X1049284Y211060D03*
X1089101Y218147D03*
X1065242Y216196D03*
X1039145Y213009D03*
X1042524Y211060D03*
X1049284Y207159D03*
X1045904Y216909D03*
X1042524Y218860D03*
X1045904Y213009D03*
Y244209D03*
Y240309D03*
X1035765Y222760D03*
X1039145Y224709D03*
X1042524Y222760D03*
X1045904Y224709D03*
X1049284Y242260D03*
X1039145Y240309D03*
X1042524Y242260D03*
X1035765D03*
X1039145Y244209D03*
X1042524Y246160D03*
X1035765D03*
X1092481Y220096D03*
Y227896D03*
X1089101Y229847D03*
X1075582Y222047D03*
X1065242Y227896D03*
Y231797D03*
X1072202Y220096D03*
Y227896D03*
X1068822Y225947D03*
Y222047D03*
X1095861Y241547D03*
X1092481Y235696D03*
Y239596D03*
X1072202Y247396D03*
X1065242Y243496D03*
X1085721Y220096D03*
X1095861Y225947D03*
X1082341D03*
X1095700Y265900D03*
X1078962Y231797D03*
X1082341Y241547D03*
X1085721Y235696D03*
X1075582Y241547D03*
X1045904Y236409D03*
X1035765Y230559D03*
X1072202Y235696D03*
X1057314Y228610D03*
X1042524Y230559D03*
X1049284D03*
X1057314Y236409D03*
X1045904Y228610D03*
X1078962Y235696D03*
Y243496D03*
X1042524Y234460D03*
X1035765D03*
X1049284D03*
X1039145Y236409D03*
X1049284Y355360D03*
X1052664Y361209D03*
X1035765Y367060D03*
X1045904Y384609D03*
X1039145D03*
X1049284Y390460D03*
X1052664Y396309D03*
X1049284Y386560D03*
X1048154Y402900D03*
X1052500Y400400D03*
X1049284Y378760D03*
X1039145Y372909D03*
X1042524Y378760D03*
X1035765D03*
X1045904Y372909D03*
X1083462Y356596D03*
X1086841Y370247D03*
X1073322Y358547D03*
X1083462Y364396D03*
X1093601Y354647D03*
X1090221Y360496D03*
X1080082Y358547D03*
X1093601Y381947D03*
X1090221Y387796D03*
X1073322Y393647D03*
X1083462Y383896D03*
X1073322Y378047D03*
X1080082Y389747D03*
X1060694Y394359D03*
Y386560D03*
Y382660D03*
Y378760D03*
X1086841Y378047D03*
X1090221Y376096D03*
X1093601Y374146D03*
X1061055Y363160D03*
X1060963Y370959D03*
X1064371Y367060D03*
X1076702Y364396D03*
X1073322Y370247D03*
X1080082Y374146D03*
X1045904Y361209D03*
X1052664Y372909D03*
X1042524Y367060D03*
X1049284D03*
X1039145Y361209D03*
X1076702Y383896D03*
X1093601Y370247D03*
X1109381Y218147D03*
X1116141Y206446D03*
X1133040Y216196D03*
X1129660Y218147D03*
X1133040Y212296D03*
X1129660Y210346D03*
X1136420D03*
X1144300Y212296D03*
X1147680Y214247D03*
X1144300Y216196D03*
X1147680Y218147D03*
X1154440D03*
X1106001Y220096D03*
X1116141Y225947D03*
X1102621Y222047D03*
Y225947D03*
X1112761Y220096D03*
Y227896D03*
X1109381Y229847D03*
X1116141Y241547D03*
X1112761Y235696D03*
X1119521Y243496D03*
Y235696D03*
X1106001D03*
X1102621Y241547D03*
X1099241Y231797D03*
Y243496D03*
Y235696D03*
X1107600Y271900D03*
X1114340Y280560D03*
X1151060Y251296D03*
X1126280Y220096D03*
X1133040Y231797D03*
X1122900Y222047D03*
Y225947D03*
X1133040Y220096D03*
X1129660Y229847D03*
X1126280Y235696D03*
X1122900Y241547D03*
X1157820Y243496D03*
X1133040Y239596D03*
X1136420Y261047D03*
X1133040Y262996D03*
X1151060Y255196D03*
X1147680Y261047D03*
X1144300Y259096D03*
X1151060Y262996D03*
X1147680Y253247D03*
Y257147D03*
X1134160Y272747D03*
X1109381Y264947D03*
X1129660Y249347D03*
X1109381D03*
X1126280Y247396D03*
X1102621Y249347D03*
X1116141D03*
X1129660Y257147D03*
X1122900Y253247D03*
X1133040Y247396D03*
Y255196D03*
X1136420Y253247D03*
X1140920Y280547D03*
X1157820Y274696D03*
X1154440Y268847D03*
X1140920Y272747D03*
X1154440Y280547D03*
Y276647D03*
X1147680D03*
X1140920D03*
X1154440Y272747D03*
X1147680D03*
X1151060Y270796D03*
X1144300Y220096D03*
X1154440Y237647D03*
X1147680Y241547D03*
X1157820Y227896D03*
X1147680Y229847D03*
X1109381Y257147D03*
X1112761Y255196D03*
X1102621Y253247D03*
X1106001Y255196D03*
X1116096Y295809D03*
X1099391Y337001D03*
X1105800Y336830D03*
X1114839Y320075D03*
X1157820Y309797D03*
X1134160Y303947D03*
X1130780Y321496D03*
X1137540Y313696D03*
X1130780Y325396D03*
X1140920Y315647D03*
X1134160Y319547D03*
X1130780Y317596D03*
Y333196D03*
X1134160Y331247D03*
X1115230Y289252D03*
X1144300Y290296D03*
X1147680Y292247D03*
X1154440D03*
X1157820Y282496D03*
X1154440Y288347D03*
Y284447D03*
X1144300Y282496D03*
X1157820Y286396D03*
X1137540D03*
X1140920Y288347D03*
Y284447D03*
X1147680D03*
Y288347D03*
X1151060Y286396D03*
X1137540Y301996D03*
X1151060Y337096D03*
X1120641Y339047D03*
X1113881Y370247D03*
X1100361D03*
X1103741Y360496D03*
X1100361Y354647D03*
Y362447D03*
X1113881Y354647D03*
X1110501Y356596D03*
Y360496D03*
X1096981Y356596D03*
X1117261D03*
X1096981Y364396D03*
X1117261D03*
X1107121Y366347D03*
X1103741Y387796D03*
X1100361Y381947D03*
X1113881Y389747D03*
X1110501Y383896D03*
X1117261Y379996D03*
X1096981Y391696D03*
X1117261Y383896D03*
Y387796D03*
X1103741Y376096D03*
X1110501D03*
X1124021Y368296D03*
X1130780Y364396D03*
X1124021Y360496D03*
X1120641Y354647D03*
Y362447D03*
X1140920Y354647D03*
X1137540Y356596D03*
X1124021Y383896D03*
X1120641Y389747D03*
X1144300Y399496D03*
X1130780Y383896D03*
Y387796D03*
X1140920Y393647D03*
X1137540Y379996D03*
Y383896D03*
Y387796D03*
X1134160Y374146D03*
X1120641D03*
X1127400D03*
X1157820Y383896D03*
X1156699Y401447D03*
X1127400Y370247D03*
X1147680D03*
X1157820Y364396D03*
X1110501Y344896D03*
X1107121Y350747D03*
X1113881Y342947D03*
X1154440Y370246D03*
X1151060Y372196D03*
X1157820D03*
X1140920Y342947D03*
Y401447D03*
X1154440Y374146D03*
X1147680D03*
X1124021Y344896D03*
X1127400Y350747D03*
X1120641Y346847D03*
X1151060Y376096D03*
X1157820Y368296D03*
X1144300Y379996D03*
Y387796D03*
X1157820Y376096D03*
X1144300Y383896D03*
X1147680Y381947D03*
Y378047D03*
X1208519Y218147D03*
X1210070Y195300D03*
X1191619Y212296D03*
X1167960Y214247D03*
X1164580Y208397D03*
X1181479Y214247D03*
X1194999Y218147D03*
X1174719Y214247D03*
X1161200D03*
X1178099Y223996D03*
X1174719Y241547D03*
X1178099Y239596D03*
X1174719Y245447D03*
X1178099Y251296D03*
X1171339Y270796D03*
X1178099Y266896D03*
Y262996D03*
X1191619Y223996D03*
X1181479Y253247D03*
X1164580Y243496D03*
Y274696D03*
X1167960Y280547D03*
X1171339Y262996D03*
X1174719Y264947D03*
X1171339Y278596D03*
X1161200Y276646D03*
Y280547D03*
X1167960Y268847D03*
X1188239D03*
X1205139Y278596D03*
X1184859Y227896D03*
X1198379Y223996D03*
X1188239Y245447D03*
X1194999Y229847D03*
X1178099Y231797D03*
X1171339Y227896D03*
X1174719Y222047D03*
X1208519Y253247D03*
X1205139Y262996D03*
X1181479Y280547D03*
X1191619Y235696D03*
X1164580Y231797D03*
X1205139Y270796D03*
X1198379Y274696D03*
X1201759Y253247D03*
X1194999Y261047D03*
X1188239Y253247D03*
X1181479Y245447D03*
X1212199Y227896D03*
X1184859Y220096D03*
X1205139Y223996D03*
X1161200Y237647D03*
X1205139Y243496D03*
Y235696D03*
Y255196D03*
X1181479Y331247D03*
X1198379Y321496D03*
X1194999Y323446D03*
X1181479Y315647D03*
X1191619Y337096D03*
X1181479Y323446D03*
X1171339Y337096D03*
X1174719Y331247D03*
X1178099Y321496D03*
X1174719Y327347D03*
X1167960Y335147D03*
X1171339Y329296D03*
X1178099Y333196D03*
Y325396D03*
X1171339Y333196D03*
X1178099Y329296D03*
X1174719Y319547D03*
X1171339Y282496D03*
X1167960Y284447D03*
X1164580Y282496D03*
X1184859Y298096D03*
X1191619Y313696D03*
X1188239Y300047D03*
X1191619Y340996D03*
X1188239Y331247D03*
Y327347D03*
X1194999Y311747D03*
X1184859Y305896D03*
X1188239Y296147D03*
X1181479D03*
X1191619Y325396D03*
X1188239Y307847D03*
X1208819Y284447D03*
X1174719Y323446D03*
X1161200Y288347D03*
Y292247D03*
X1201759D03*
X1171339Y340996D03*
X1161201Y401447D03*
X1178099Y368296D03*
X1164580Y391696D03*
X1171339Y352696D03*
X1164580Y364396D03*
X1167960Y350747D03*
X1161200Y362447D03*
Y358547D03*
X1178099Y352696D03*
X1164580Y376096D03*
X1194999Y350747D03*
X1198379Y348796D03*
X1184859Y379996D03*
X1188239Y350747D03*
X1191619Y356596D03*
X1184859Y372197D03*
X1181479Y366347D03*
Y362447D03*
X1188239D03*
Y358547D03*
Y354647D03*
X1198379Y383896D03*
X1191619Y379996D03*
X1184859Y376096D03*
X1198379D03*
X1171339Y391696D03*
X1191619Y344896D03*
X1178099Y376096D03*
X1171339Y395596D03*
X1174719Y389747D03*
X1171339Y383896D03*
X1161200Y389747D03*
X1164580Y395597D03*
X1178099Y387796D03*
X1167960Y346847D03*
X1164580Y360496D03*
X1161200Y366347D03*
X1167960Y354647D03*
X1161200D03*
X1164580Y368296D03*
X1181479Y378047D03*
X1188239Y374146D03*
X1184859Y368296D03*
Y364396D03*
X1181479Y358547D03*
X1184859Y360496D03*
X1197100Y408200D03*
X1325100Y145000D03*
X1315180Y169950D03*
X1315130Y164870D03*
X1380100Y165000D03*
Y160000D03*
X1350100Y170000D03*
X1390100Y432500D03*
X1377028Y458125D03*
X1375100Y447500D03*
X1390100Y452500D03*
X1372028Y458125D03*
X1395375Y453561D03*
X1524575Y387654D03*
X1503878Y364717D03*
X1487525Y384274D03*
X1505075Y394414D03*
X1501175Y387654D03*
X1505075Y401174D03*
X1501175D03*
X1522625Y391034D03*
X1495325Y397794D03*
X1499225D03*
X1493375Y401174D03*
X1489475D03*
X1507025Y384274D03*
X1501175Y380894D03*
X1522625Y397794D03*
X1507025Y377514D03*
X1518725Y384274D03*
X1510925Y397794D03*
X1483868Y390233D03*
X1516775Y394414D03*
X1510925Y377514D03*
X1512875Y380894D03*
X1518725Y377514D03*
X1522625Y384274D03*
X1510925Y391034D03*
X1512875Y387654D03*
X1510925Y384274D03*
X1489475Y380894D03*
X1493375D03*
X1487525Y397794D03*
Y377514D03*
X1498183Y365405D03*
X1505075Y387654D03*
X1499225Y377514D03*
X1505075Y463826D03*
X1515500Y448250D03*
X1507025Y404554D03*
X1499225D03*
Y440166D03*
X1522625Y404554D03*
X1491425Y418074D03*
X1487525D03*
X1499225Y446926D03*
Y453686D03*
X1520675Y463826D03*
X1512875D03*
X1508975D03*
X1501175Y421454D03*
X1495325Y418074D03*
X1493375Y443546D03*
X1489475Y414694D03*
X1493375D03*
X1489475Y407934D03*
X1493375D03*
Y421454D03*
X1489475D03*
X1493375Y428214D03*
Y436786D03*
X1499225Y460446D03*
X1489475Y457066D03*
X1487525Y460446D03*
Y480726D03*
X1520675Y470586D03*
X1510925Y467206D03*
X1507025D03*
X1520675Y477346D03*
X1514825Y467206D03*
X1512875Y470586D03*
X1491425Y480726D03*
X1495325Y473966D03*
X1491425Y487486D03*
X1499225Y467206D03*
X1520675Y484106D03*
X1524575Y477346D03*
X1512875D03*
X1526525Y480726D03*
X1524575Y484106D03*
X1522625Y480726D03*
X1516775Y477346D03*
X1540175Y387654D03*
X1551875D03*
X1565525Y397794D03*
X1528475Y401174D03*
Y387654D03*
Y394414D03*
X1530425Y377514D03*
X1534325Y384274D03*
Y397794D03*
Y377514D03*
X1542300Y376717D03*
X1551875Y394414D03*
X1540175Y380894D03*
Y401174D03*
X1536275D03*
X1540175Y394414D03*
X1563575Y387654D03*
X1551875Y401174D03*
X1559675Y380894D03*
X1563575D03*
X1565525Y384274D03*
Y460446D03*
X1567475Y414694D03*
Y443546D03*
Y463826D03*
X1565525Y453686D03*
Y418074D03*
X1571375Y421454D03*
X1569425Y418074D03*
X1565525Y424834D03*
X1571375Y414694D03*
Y407934D03*
X1565525Y446926D03*
X1528475Y463826D03*
X1559675D03*
X1542125Y460446D03*
X1536275Y463826D03*
X1555775Y407934D03*
X1561625Y411314D03*
Y440166D03*
X1551875Y443546D03*
X1557725Y460446D03*
X1553825D03*
X1563575Y450306D03*
X1546025Y460446D03*
X1563575Y463826D03*
X1557725Y440166D03*
Y418074D03*
X1563575Y421454D03*
X1567475Y477346D03*
X1565525Y473966D03*
X1569425Y467206D03*
X1565525D03*
X1571545Y482842D03*
X1571375Y477346D03*
X1530425Y467206D03*
X1561625D03*
X1563575Y470586D03*
X1561625Y473966D03*
X1551875Y470586D03*
X1549925Y467206D03*
X1559675Y470586D03*
X1557725Y467206D03*
X1547975Y484106D03*
X1551875D03*
X1549925Y480726D03*
X1559675Y477346D03*
X1563575Y484106D03*
X1561625Y480726D03*
X1536275Y477346D03*
X1559675Y484106D03*
X1530425Y480726D03*
Y487486D03*
X1557725D03*
X1561625D03*
X1534325Y473966D03*
X1613741Y112341D03*
X1654685Y121790D03*
X1664135Y131239D03*
X1657835D03*
X2088977Y1745352D03*
G54D15*
X-14488Y434094D03*
X-4488D03*
X5512D03*
X15512D03*
X89980Y145531D03*
X99980D03*
X109980D03*
X119980D03*
X2088977Y938952D03*
G54D24*
X10512Y467244D03*
X20512D03*
X30512D03*
X40512D03*
X50512D03*
X60512D03*
X1884100Y493000D03*
X1894100D03*
X1891086Y612105D03*
Y602105D03*
Y592105D03*
X1904100Y493000D03*
X2088977Y972552D03*
G54D42*
X1527844Y80791D03*
X2088977Y434952D03*
G54D60*
X1854501Y195587D03*
X1859854Y501441D03*
Y525063D03*
X2088977Y502152D03*
G54D61*
X1887327Y511202D03*
X1929453Y532541D03*
X2088977Y-69048D03*
G54D25*
X42724Y644684D03*
Y644656D03*
Y654684D03*
Y654656D03*
X67724Y644684D03*
Y644656D03*
Y654684D03*
Y654656D03*
X221656Y644656D03*
X196656D03*
X231446Y644756D03*
Y644784D03*
X221656Y644684D03*
X196656D03*
X221656Y654656D03*
X196656D03*
X231446Y654756D03*
Y654784D03*
X221656Y654684D03*
X196656D03*
X256446Y644756D03*
Y644784D03*
Y654756D03*
Y654784D03*
X409240Y644564D03*
X384240D03*
X418914Y644486D03*
Y644514D03*
X409240Y644536D03*
X384240D03*
X409240Y654564D03*
X384240D03*
X418914Y654486D03*
Y654514D03*
X409240Y654536D03*
X384240D03*
X443914Y644486D03*
Y644514D03*
Y654486D03*
Y654514D03*
X596707Y644293D03*
X571707D03*
X596708Y644266D03*
X571708D03*
X596707Y654293D03*
X571707D03*
X596708Y654266D03*
X571708D03*
X606462Y644245D03*
X631462D03*
X606462Y644217D03*
X631462D03*
X606462Y654245D03*
X631462D03*
X606462Y654217D03*
X631462D03*
X912351Y644245D03*
X887351D03*
X912351Y644273D03*
X887351D03*
X912351Y654245D03*
X887351D03*
X912351Y654273D03*
X887351D03*
X922116Y644206D03*
X947116D03*
X922116Y644234D03*
X947116D03*
X922116Y654206D03*
X947116D03*
X922116Y654234D03*
X947116D03*
X1200877Y644262D03*
Y644234D03*
Y654262D03*
Y654234D03*
X1225877Y644262D03*
X1235614Y644236D03*
X1260614D03*
X1235614Y644264D03*
X1260614D03*
X1225877Y644234D03*
Y654262D03*
X1235614Y654236D03*
X1260614D03*
X1235614Y654264D03*
X1260614D03*
X1225877Y654234D03*
X1514375Y644292D03*
Y644264D03*
Y654292D03*
Y654264D03*
X1539375Y644292D03*
Y644264D03*
Y654292D03*
Y654264D03*
X2088977Y1039752D03*
G54D70*
X1952756Y589960D03*
X1944882Y582086D03*
X1952756D03*
X1944882Y574212D03*
X1952756D03*
X1944882Y566338D03*
X1952756D03*
X1944882Y558464D03*
Y589960D03*
X1952756Y558464D03*
X1944882Y605708D03*
X1952756D03*
X1944882Y597834D03*
X1952756D03*
X2088977Y1073352D03*
G54D34*
X324407Y9114D03*
X317714D03*
X307675Y17057D03*
Y28014D03*
X321061D03*
X324407D03*
X314368D03*
X331100D03*
Y17057D03*
X334446Y9114D03*
X354525Y28022D03*
X351179D03*
X344486D03*
X341140D03*
X334446Y28014D03*
X334447Y17057D03*
X311021Y9114D03*
X314368Y17057D03*
X324407D03*
X327754Y9114D03*
X321061Y17057D03*
X341140D03*
X337793Y9114D03*
X344486Y17057D03*
Y9122D03*
X347833D03*
X351179Y17057D03*
X354525Y9122D03*
X354526Y17057D03*
X317714Y46914D03*
Y35957D03*
X307928Y67802D03*
X307675Y54857D03*
X321061Y65814D03*
X324407D03*
X314368D03*
X331100D03*
X321061Y54857D03*
X327754Y35957D03*
Y46914D03*
X324407Y54857D03*
Y35957D03*
Y46914D03*
X314368Y54857D03*
X311021Y46914D03*
X331100Y54857D03*
X317714Y73757D03*
X327754D03*
X324407D03*
X354525Y65822D03*
X351179D03*
X344486D03*
X341140D03*
X334446Y46914D03*
X354526Y54857D03*
X354525Y46922D03*
X354526Y35957D03*
X351179Y54857D03*
X347833Y46922D03*
X344486D03*
Y35957D03*
Y54857D03*
X337793Y46914D03*
Y35957D03*
X341140Y54857D03*
X334447D03*
X347833Y73757D03*
X344486D03*
X337793D03*
X334447D03*
X354526D03*
X311021Y35957D03*
X334446Y65814D03*
X334447Y35957D03*
X347833D03*
X320784Y203219D03*
X330948Y201258D03*
X308198Y528863D03*
X317714Y536957D03*
Y547914D03*
Y585714D03*
X307675Y555857D03*
X307984Y566743D03*
X317714Y574757D03*
X324407Y585714D03*
X344486Y585722D03*
X327754Y536957D03*
X321061Y529014D03*
X334447Y555857D03*
X341140D03*
X337793Y547914D03*
X344486Y555857D03*
Y547922D03*
X347833D03*
X351179Y555857D03*
X354525Y547922D03*
X354526Y555857D03*
X331100D03*
X334446Y547914D03*
X311021D03*
X314368Y555857D03*
X324407Y547914D03*
Y555857D03*
X327754Y547914D03*
X321061Y555857D03*
X334446Y529014D03*
X341140Y529022D03*
X337793Y536957D03*
X347833D03*
X351179Y529022D03*
X354526Y536957D03*
X331100Y529014D03*
X311021Y536957D03*
X324407D03*
X311021Y574757D03*
X324407D03*
Y566814D03*
X327754Y574757D03*
X337793Y585714D03*
X347833Y585722D03*
X354525D03*
X334446Y585714D03*
X311021D03*
X327754D03*
X334446Y566814D03*
X341140Y566822D03*
X337793Y574757D03*
X344486D03*
X347833D03*
X351179Y566822D03*
X354526Y574757D03*
X354525Y566822D03*
X331100Y566814D03*
X334447Y574757D03*
X344486Y529022D03*
Y536957D03*
X354525Y529022D03*
X334447Y536957D03*
X324407Y529014D03*
X314368Y566814D03*
X321061D03*
X344486Y566822D03*
X307675Y593657D03*
X334447D03*
X341140D03*
X344486D03*
X351179D03*
X354526D03*
X331100D03*
X314368D03*
X324407D03*
X321061D03*
X361218Y28014D03*
X401376Y9121D03*
X404722D03*
X411416Y9122D03*
X404723Y28022D03*
X401377D03*
X411416D03*
X404723Y17057D03*
X408069Y17042D03*
X414763Y9122D03*
X398029Y17042D03*
X414762Y17058D03*
X364565Y28014D03*
X414762Y28021D03*
X364265Y46914D03*
X361518D03*
X411416Y46922D03*
X411415Y36058D03*
X404723Y65822D03*
X414763D03*
X404723Y54857D03*
X401377Y46922D03*
Y35957D03*
X414763Y54857D03*
X398029Y54842D03*
X404723Y46922D03*
X414763Y35957D03*
Y46922D03*
X408069Y54842D03*
X394684Y35957D03*
X401377Y65822D03*
X411416D03*
Y73757D03*
X401377D03*
X404723D03*
X414763D03*
X404723Y35957D03*
X401377Y529022D03*
X411416D03*
Y536957D03*
X411415Y547921D03*
X411416Y574757D03*
Y585722D03*
X401377Y566822D03*
X411416D03*
X414763Y585722D03*
X404723Y529022D03*
X408069Y555842D03*
X414763Y547922D03*
X404723D03*
X398029Y555842D03*
X414763Y555857D03*
X401376Y547922D03*
X404723Y555857D03*
Y536957D03*
X401377Y574757D03*
X404723Y566822D03*
Y585722D03*
X401377D03*
X394684Y574757D03*
X414763D03*
X404723D03*
X401377Y536957D03*
X414763D03*
Y566822D03*
X408069Y593642D03*
X398029D03*
X404723Y593657D03*
X414763D03*
X438187Y9120D03*
X428147D03*
X434840D03*
X421455Y9121D03*
X444880Y28022D03*
X421456D03*
Y17057D03*
X428149Y28022D03*
X434842Y28268D03*
X438187Y17059D03*
X424801Y17042D03*
X444880Y9122D03*
Y17059D03*
X431494Y17042D03*
X438189Y28022D03*
X421455Y46921D03*
X444880Y65822D03*
X421456D03*
X438189D03*
Y46922D03*
Y35957D03*
X431494Y54842D03*
X444880Y54859D03*
Y46922D03*
X428149Y35957D03*
Y46922D03*
X421456Y54857D03*
X434842Y46922D03*
Y35957D03*
X424801Y54842D03*
X438187Y54859D03*
X421456Y35957D03*
X434842Y65822D03*
X428149D03*
X421456Y73757D03*
X438189D03*
X428149D03*
X444882Y35957D03*
X434842Y73757D03*
X458640Y200596D03*
X421456Y585722D03*
X428149Y529022D03*
X434842D03*
X421456Y547922D03*
X428149Y566822D03*
X434842D03*
X438189Y536957D03*
X438187Y555859D03*
X424801Y555842D03*
X434842Y547922D03*
X421456Y555857D03*
X428149Y547922D03*
X444880D03*
Y555859D03*
X431494Y555842D03*
X438189Y547922D03*
X428149Y536957D03*
X444880Y585722D03*
X438189D03*
Y566822D03*
X434842Y574757D03*
X421456Y566822D03*
X428149Y574757D03*
X444882D03*
X438189D03*
X434842Y585722D03*
X428149D03*
X444882Y536957D03*
X434842D03*
X421456Y529022D03*
X444880Y566822D03*
Y593659D03*
X431494Y593642D03*
X424801D03*
X421456Y593657D03*
X438187Y593659D03*
X957283Y28014D03*
Y17057D03*
X970669Y28014D03*
X963976D03*
X967322Y9114D03*
X960629D03*
X963976Y17057D03*
X970669D03*
X957536Y67802D03*
X957283Y54857D03*
X970669D03*
X960629Y35957D03*
X963976Y54857D03*
X960629Y46914D03*
X967322Y35957D03*
Y73757D03*
X963976Y65814D03*
X970669D03*
X967322Y46914D03*
X970392Y203219D03*
X967322Y536957D03*
X957806Y528863D03*
X960629Y547914D03*
X967322Y574757D03*
X957283Y555857D03*
X957592Y566743D03*
X970669Y555857D03*
Y566814D03*
X963976Y555857D03*
X967322Y585714D03*
Y547914D03*
X960629Y585714D03*
X963976Y566814D03*
X960629Y574757D03*
Y536957D03*
X970669Y529014D03*
X957283Y593657D03*
X963976D03*
X970669D03*
X974015Y28014D03*
X994094Y28022D03*
X990748D03*
X1004133D03*
X1000787D03*
X984055Y17057D03*
X990748D03*
X987401Y9114D03*
X994094Y17057D03*
Y9122D03*
X997441D03*
X1000787Y17057D03*
X1004133Y9122D03*
X1004134Y17057D03*
X980708D03*
X984054Y9114D03*
X974015D03*
Y17057D03*
X977362Y9114D03*
X984054Y28014D03*
X980708D03*
X977362Y35957D03*
Y46914D03*
X974015Y54857D03*
X997441Y46922D03*
Y35957D03*
X994094Y46922D03*
Y35957D03*
Y54857D03*
X987401Y46914D03*
Y35957D03*
X990748Y54857D03*
X1004134D03*
Y35957D03*
X1004133Y46922D03*
X1000787Y54857D03*
X984054Y65814D03*
X990748Y65822D03*
X994094D03*
X1000787D03*
X1004133D03*
X980708Y65814D03*
X974015D03*
X987401Y73757D03*
X994094D03*
X997441D03*
X1004134D03*
X984055D03*
X974015D03*
X977362D03*
X974015Y35957D03*
Y46914D03*
X984055Y54857D03*
X980708D03*
X984054Y46914D03*
X984055Y35957D03*
X980556Y201258D03*
X977362Y536957D03*
X974015D03*
X984055D03*
X980708Y529014D03*
X977362Y547914D03*
X974015D03*
X984054D03*
X997441Y547922D03*
X994094D03*
X987401Y547914D03*
X997441Y585722D03*
X977362Y574757D03*
X974015Y555857D03*
Y566814D03*
Y574757D03*
X984055D03*
X980708Y555857D03*
Y566814D03*
X994094Y574757D03*
Y555857D03*
Y566822D03*
X990748Y555857D03*
Y566822D03*
X984055Y555857D03*
X984054Y566814D03*
X977362Y585714D03*
X1004133Y547922D03*
X1004134Y555857D03*
X1004133Y566822D03*
X1004134Y574757D03*
X1000787Y555857D03*
Y566822D03*
X1004133Y585722D03*
X974015Y529014D03*
X990748Y529022D03*
X987401Y536957D03*
X994094D03*
X997441D03*
X1000787Y529022D03*
X1004134Y536957D03*
X987401Y585714D03*
X994094Y585722D03*
X984054Y585714D03*
X974015D03*
X984054Y529014D03*
X997441Y574757D03*
X987401D03*
X994094Y529022D03*
X1004133D03*
X980708Y593657D03*
X984055D03*
X990748D03*
X994094D03*
X1000787D03*
X1004134D03*
X974015D03*
X1054331Y28022D03*
X1050985D03*
X1071064Y9122D03*
X1064371Y28022D03*
X1094488D03*
X1087797D03*
X1061024D03*
X1077757D03*
X1084450Y28098D03*
X1071064Y17057D03*
X1061024Y9122D03*
X1094488D03*
Y17059D03*
X1081102Y17042D03*
X1064371Y17057D03*
X1087797Y9122D03*
X1050985D03*
X1054331Y17057D03*
X1071064Y28022D03*
X1087795Y17059D03*
X1074409Y17042D03*
X1084450Y9122D03*
X1057677Y17042D03*
X1064371Y9122D03*
X1077757D03*
X1054331D03*
X1047637Y17042D03*
X1054331Y54857D03*
X1047637Y54842D03*
X1057677D03*
X1044292Y35957D03*
X1050985Y65822D03*
X1071064Y46922D03*
X1094490Y35957D03*
X1064371Y54857D03*
X1081102Y54842D03*
X1094488Y54859D03*
Y46922D03*
X1064371Y35957D03*
Y46922D03*
X1074409Y54842D03*
X1087795Y54859D03*
X1071064Y35957D03*
X1061024Y65822D03*
X1084450D03*
X1077757D03*
X1071064Y73757D03*
X1061024D03*
X1071064Y65822D03*
X1064371D03*
X1054331D03*
X1064371Y73757D03*
X1054331D03*
X1050985D03*
X1087797Y65822D03*
X1094488D03*
X1087797Y73757D03*
X1084450D03*
X1077757D03*
X1061024Y46922D03*
Y35957D03*
X1084450D03*
Y46922D03*
X1071064Y54857D03*
X1077757Y35957D03*
Y46922D03*
X1054331Y35957D03*
Y46922D03*
X1087797Y35957D03*
Y46922D03*
X1050985Y35957D03*
Y46922D03*
Y536957D03*
X1054331D03*
X1050984Y547922D03*
X1054331D03*
X1050985Y529022D03*
Y566822D03*
X1054331Y555857D03*
Y566822D03*
X1050985Y574757D03*
X1047637Y555842D03*
X1054331Y574757D03*
X1057677Y555842D03*
X1044292Y574757D03*
X1050985Y585722D03*
X1054331D03*
X1064371Y547922D03*
X1084450D03*
X1061024Y529022D03*
X1084450D03*
X1077757D03*
X1067716Y547907D03*
X1061024Y536957D03*
Y547922D03*
X1071064D03*
X1087797Y536957D03*
X1077757D03*
X1071064Y529022D03*
X1084450Y536957D03*
X1087797Y547922D03*
X1094488D03*
X1064371Y574757D03*
X1071064Y555857D03*
Y566822D03*
X1084450Y574757D03*
X1074409Y555842D03*
X1087795Y555859D03*
X1087797Y585722D03*
X1064371D03*
X1084450D03*
X1071064Y574757D03*
X1061024Y566822D03*
X1084450D03*
X1077757D03*
X1061024Y574757D03*
Y585722D03*
X1071064D03*
X1087797Y574757D03*
X1064371Y566822D03*
X1094488D03*
X1064371Y555857D03*
X1081102Y555842D03*
X1094488Y555859D03*
X1064371Y536957D03*
X1077757Y547922D03*
Y585722D03*
Y574757D03*
X1094488Y585722D03*
X1087797Y566822D03*
X1094490Y574757D03*
X1054331Y529022D03*
X1094490Y536957D03*
X1071064Y593657D03*
X1087795Y593659D03*
X1057677Y593642D03*
X1047637D03*
X1094488Y593659D03*
X1081102Y593642D03*
X1064371Y593657D03*
X1054331D03*
X1108248Y200596D03*
X1111631Y198327D03*
X1445454Y267304D03*
X1458102Y270402D03*
X1458052Y273603D03*
Y276753D03*
X1445454D03*
X1442304Y279902D03*
X1461400Y264700D03*
X1458052Y279902D03*
X1451753Y270454D03*
X1461202Y276753D03*
X1448603Y279902D03*
X1464351Y276753D03*
X1461202Y279902D03*
Y273603D03*
X1451753D03*
Y267304D03*
X1448603Y270454D03*
Y267304D03*
X1442303Y267303D03*
X1454902Y276753D03*
X1451753Y279902D03*
X1442303Y270454D03*
X1461300Y270400D03*
X1445454Y279902D03*
X1448603Y276753D03*
X1442304Y273603D03*
X1454902D03*
X1451753Y276753D03*
X1454902Y279902D03*
X1445454Y270454D03*
X1448603Y273603D03*
X1454902Y270454D03*
X1464424Y273676D03*
X1445454Y273603D03*
X1464351Y279902D03*
X1454902Y311397D03*
X1463610Y321329D03*
X1451753Y301948D03*
X1445454D03*
X1464351Y311397D03*
X1461202D03*
X1458052Y308247D03*
X1464351Y301948D03*
X1451753Y298798D03*
X1458052Y311397D03*
X1454902Y295649D03*
X1445454Y311397D03*
X1442304D03*
X1454902Y298798D03*
X1464351Y305098D03*
X1458052Y295649D03*
X1448603Y301948D03*
X1442304Y308247D03*
X1448603Y298798D03*
X1445454D03*
X1458052Y314546D03*
X1462776Y318200D03*
X1451753Y314546D03*
X1448603Y308247D03*
X1454902Y305098D03*
X1448603Y311397D03*
X1458051Y301949D03*
X1464351Y295649D03*
X1442304Y305098D03*
X1445454Y308247D03*
X1448603Y314546D03*
X1454928Y317723D03*
X1461202Y305098D03*
X1440910Y316693D03*
X1458052Y298798D03*
X1451753Y317696D03*
X1458052Y305098D03*
X1448603Y317696D03*
X1458400Y318500D03*
X1445454Y305098D03*
X1448603D03*
X1454902Y308247D03*
X1451753Y305098D03*
X1442303Y298799D03*
X1464351Y298798D03*
X1461202D03*
Y295649D03*
X1445528Y317772D03*
X1454902Y301948D03*
X1461202D03*
Y314546D03*
X1464350Y308247D03*
X1445427Y295624D03*
X1448577D03*
X1451751Y295649D03*
X1454902Y314546D03*
X1448603Y283053D03*
X1461202Y283052D03*
X1445454Y289351D03*
X1451753D03*
X1454902Y283052D03*
X1442304Y289350D03*
X1458052Y286202D03*
X1454902Y289351D03*
Y286202D03*
X1454751Y292651D03*
X1442304Y292499D03*
X1448603Y289351D03*
X1458052D03*
X1464351Y283052D03*
X1461202Y286202D03*
X1464351D03*
X1461202Y289351D03*
X1451754Y283053D03*
X1448603Y286202D03*
X1451753D03*
X1464351Y289351D03*
X1458051Y283051D03*
X1451753Y311397D03*
X1445427Y292526D03*
X1470649Y279902D03*
Y270454D03*
Y276753D03*
X1469829Y266909D03*
X1470649Y273603D03*
X1480098Y270454D03*
X1483247Y273603D03*
Y270454D03*
X1489546Y279902D03*
X1473798Y276753D03*
X1476948Y273603D03*
X1480098Y267304D03*
X1476948Y270454D03*
X1473798D03*
X1480098Y273603D03*
X1486397Y270454D03*
X1483247Y267304D03*
X1476948Y279902D03*
X1473798D03*
X1480098Y276753D03*
X1483247Y279902D03*
X1476948Y276753D03*
X1486574Y267127D03*
X1496030Y267665D03*
X1473798Y273603D03*
X1489546Y270454D03*
X1486397Y273603D03*
X1483247Y276753D03*
X1470649Y305098D03*
Y311397D03*
Y301948D03*
Y308247D03*
Y314546D03*
Y295649D03*
Y298798D03*
Y283052D03*
Y286202D03*
Y289351D03*
X1480098Y305098D03*
X1476949Y301949D03*
X1486397Y311397D03*
X1489546Y314546D03*
X1473798Y305098D03*
X1480098Y301948D03*
Y298798D03*
X1495651Y311350D03*
X1493400Y300800D03*
X1486397Y298798D03*
X1480098Y295649D03*
X1476948Y298798D03*
X1489546Y286202D03*
X1486397Y305098D03*
X1473798Y295649D03*
X1483247Y305098D03*
X1480098Y308247D03*
X1473798Y298798D03*
X1492696Y314546D03*
X1473798Y308247D03*
X1476948Y305098D03*
X1497509Y303120D03*
X1489546Y308247D03*
X1476948Y311397D03*
X1489546Y317696D03*
X1486397Y295649D03*
Y308247D03*
X1483247Y298798D03*
X1473798Y301948D03*
X1476948Y295649D03*
X1486396Y317696D03*
X1495699Y314546D03*
X1476948Y308247D03*
X1473798Y314546D03*
X1483247D03*
X1489546Y301948D03*
Y311397D03*
X1486397Y314546D03*
X1483247Y311397D03*
X1492700Y311376D03*
X1495300Y297300D03*
X1478524Y318900D03*
X1480098Y311397D03*
X1483247Y301948D03*
X1473798Y311397D03*
X1493500Y304400D03*
X1486397Y301948D03*
X1483247Y308247D03*
X1476948Y286202D03*
X1483247D03*
Y289351D03*
Y283052D03*
X1473798D03*
X1486397Y286202D03*
X1480098D03*
X1476948Y289351D03*
X1480098Y283052D03*
X1473798Y289351D03*
Y286202D03*
X1486397Y283052D03*
X1476949Y283051D03*
X1480098Y314546D03*
X1588176Y157600D03*
X1604000Y93925D03*
X1606470Y93759D03*
X1632574Y106107D03*
X1594565Y148720D03*
X1635750Y128240D03*
X1648393Y153280D03*
X1642150Y118660D03*
X1651536Y134388D03*
X1642087Y143837D03*
X1648386Y156435D03*
X1651532Y137534D03*
X1590569Y152464D03*
X1595390Y151778D03*
X1638938Y109192D03*
X1638250Y125750D03*
X1651536Y121790D03*
X1638938Y118641D03*
X1645378Y128378D03*
X1638902Y112305D03*
X1648430Y150163D03*
X1638937Y131239D03*
Y143837D03*
Y137538D03*
X1638938Y153286D03*
X1648387Y115491D03*
X1651536D03*
X1645237D03*
X1641770Y112340D03*
X1645237Y112341D03*
X1651536D03*
Y128089D03*
X1642087Y124940D03*
X1645237D03*
X1637363Y149484D03*
X1651536Y140687D03*
Y143837D03*
Y131239D03*
Y124939D03*
X1645237Y118640D03*
X1642087Y153286D03*
X1642084Y115494D03*
X1648387Y112341D03*
Y109191D03*
X1651536D03*
X1645237D03*
X1600182Y148562D03*
X1607401Y146947D03*
X1604292Y150137D03*
X1600148Y142262D03*
X1610645Y143783D03*
X1613741Y118640D03*
X1629489Y153286D03*
X1620040Y134388D03*
Y128089D03*
X1616891D03*
X1607441Y112341D03*
X1610591Y118640D03*
X1600490Y110766D03*
X1607441Y115491D03*
X1598190Y110711D03*
X1610591Y112341D03*
X1613741Y153286D03*
X1616848Y115449D03*
X1616890Y112341D03*
X1632638Y115491D03*
Y112341D03*
X1632615Y109215D03*
X1629489Y115491D03*
X1610591Y121790D03*
X1613741D03*
X1620100Y153300D03*
X1613741Y146987D03*
X1616891Y150137D03*
X1616900Y153200D03*
X1629489Y150136D03*
X1616891Y146987D03*
X1616893Y140782D03*
X1635788Y137538D03*
Y143837D03*
Y131239D03*
X1616891Y134389D03*
X1629489Y137538D03*
Y143837D03*
Y131239D03*
X1620040Y106042D03*
X1623189Y118640D03*
X1629489D03*
X1610793Y109190D03*
X1607441Y118640D03*
X1616891Y124939D03*
X1596220Y109470D03*
X1613741Y115491D03*
X1602717Y102240D03*
X1610591Y115491D03*
Y128089D03*
X1604292Y134388D03*
X1607441Y137538D03*
X1607239Y131358D03*
X1604292Y137538D03*
X1607441Y121790D03*
X1626339Y124940D03*
X1626313Y153312D03*
X1632638Y153286D03*
X1620100Y150200D03*
X1620040Y146987D03*
Y140687D03*
X1632639Y124940D03*
Y118640D03*
X1635788D03*
X1626364Y121765D03*
X1626339Y150136D03*
X1635788Y153286D03*
X1623190Y146987D03*
Y140687D03*
Y134388D03*
Y128089D03*
Y124940D03*
X1607441Y124939D03*
X1623200Y153100D03*
X1626300Y112300D03*
X1626339Y109191D03*
Y118651D03*
X1613741Y128089D03*
X1626339Y115491D03*
X1613741Y156436D03*
Y150137D03*
X1607441Y106042D03*
X1610591Y146987D03*
X1607441Y143837D03*
X1608000Y99400D03*
X1613741Y134389D03*
X1613690Y124990D03*
X1613741Y140688D03*
X1610591Y134389D03*
X1600900Y131900D03*
X1607441Y153286D03*
X1613741Y137538D03*
X1610591Y150137D03*
Y124939D03*
Y137538D03*
Y140688D03*
X1607441Y134389D03*
X1616900Y143880D03*
X1616890Y118641D03*
X1613741Y109191D03*
Y106042D03*
X1607441Y156436D03*
X1610591Y153286D03*
X1604169Y156407D03*
X1610591Y156436D03*
X1600148Y151711D03*
X1651536Y146988D03*
Y156435D03*
X1629489Y112341D03*
X1629487Y109280D03*
X1629400Y106131D03*
X1648320Y172690D03*
X1635788Y162735D03*
X1591950Y158250D03*
X1595042Y172184D03*
X1600490Y158010D03*
X1596427Y157975D03*
X1645237Y165884D03*
X1648387Y159585D03*
X1651536D03*
X1645151Y162649D03*
X1642101Y162749D03*
X1651536Y165884D03*
X1642088Y165885D03*
X1638938Y165884D03*
X1651536Y162735D03*
X1642087Y159585D03*
X1645237D03*
X1648326Y162674D03*
X1648386Y165885D03*
X1635788Y159585D03*
X1629489D03*
X1616890Y162735D03*
X1613741Y159585D03*
X1613650Y173750D03*
X1609222Y173389D03*
X1620041Y165885D03*
X1620006Y168956D03*
X1615900Y172800D03*
X1608731Y180819D03*
X1635788Y165885D03*
X1597642Y172184D03*
X1616891Y165885D03*
X1613741D03*
X1610591Y159585D03*
X1622217Y177809D03*
X1610591Y162735D03*
X1611500Y172900D03*
X1629489Y165884D03*
X1621942Y173237D03*
X1624966Y172936D03*
X1629489Y162735D03*
X1600490Y167459D03*
X1623276Y165798D03*
X1626339Y162735D03*
X1607441D03*
X1613741D03*
X1607442Y159585D03*
X1620040Y162735D03*
X1627998Y172854D03*
X1601142Y172185D03*
X1616890Y159585D03*
X1626339Y165884D03*
X1623189Y159585D03*
X1623250Y162611D03*
X1626339Y159585D03*
X1620040D03*
X1610591Y165885D03*
X1643662Y172609D03*
X1638938Y162735D03*
Y159585D03*
X1616286Y176515D03*
X1674685Y134217D03*
X1693625Y133220D03*
X1680402Y128652D03*
X1678127Y117293D03*
X1673883Y124308D03*
X1660985Y156435D03*
X1667348Y156500D03*
X1660985Y118640D03*
X1667284Y115491D03*
X1654686Y109191D03*
X1654673Y118628D03*
X1654685Y112341D03*
X1653111Y102240D03*
X1654685Y146987D03*
X1654686Y156436D03*
X1654678Y137530D03*
X1657835Y134389D03*
X1671000Y103000D03*
X1670434Y115491D03*
X1657835Y112341D03*
X1660985Y115491D03*
X1657835Y118640D03*
X1664135Y115491D03*
Y118640D03*
X1709000Y127200D03*
X1691207Y139891D03*
X1681586Y141438D03*
X1660986Y137538D03*
X1667238Y112387D03*
X1667284Y137537D03*
X1657835Y124940D03*
Y150136D03*
X1667284Y121790D03*
Y128089D03*
Y150136D03*
X1658154Y99400D03*
X1657835Y115491D03*
Y109191D03*
X1660985D03*
Y112341D03*
X1664134Y140688D03*
Y156436D03*
X1664135Y112341D03*
X1695236Y135788D03*
Y138938D03*
X1676886Y120038D03*
Y123188D03*
X1660985Y146987D03*
X1657836Y137538D03*
X1654686Y153288D03*
Y134389D03*
X1693586Y142438D03*
X1654686Y150138D03*
X1660985Y131239D03*
X1657835Y121790D03*
X1660985D03*
X1667284Y131239D03*
X1654685D03*
X1664135Y128089D03*
X1657836Y140688D03*
X1660985Y124939D03*
X1654685Y140687D03*
X1664135Y153286D03*
X1664136Y137538D03*
X1657836Y153288D03*
X1657835Y143837D03*
X1664135Y121790D03*
X1660985Y128089D03*
Y150137D03*
X1664186Y147038D03*
X1657835Y146987D03*
X1654685Y143837D03*
X1660985D03*
X1677386Y132788D03*
Y129638D03*
X1660985Y140688D03*
X1654686Y124940D03*
X1657835Y162735D03*
X1660985D03*
X1654685D03*
X1654638Y159685D03*
X1668213Y172608D03*
X1657835Y165884D03*
X1660985Y165885D03*
X1657835Y159585D03*
X1665063Y172608D03*
X1660985Y159585D03*
X1688207Y168972D03*
X1689785Y161180D03*
X1729444Y123782D03*
X1726294Y101785D03*
X1735912Y123750D03*
X1742212Y117451D03*
X1717014Y148950D03*
X1714114D03*
X1717014Y97550D03*
Y104850D03*
Y108000D03*
Y111150D03*
Y133200D03*
Y139500D03*
X1743500Y96400D03*
X1739064Y108000D03*
X1742214Y101700D03*
X1735914D03*
X1745364Y117450D03*
Y114300D03*
Y98550D03*
X1745363Y108004D03*
X1746189Y153250D03*
X1755089Y150750D03*
X1752189Y136750D03*
X1746189Y134777D03*
Y131624D03*
X1752389Y132250D03*
X1754189Y124250D03*
X1757689Y123850D03*
X1752889Y146250D03*
X1745364Y145800D03*
Y142650D03*
X1731903Y133712D03*
X1745500Y104500D03*
X1726464Y117450D03*
X1720164Y97550D03*
Y111150D03*
X1723314D03*
X1720164Y117451D03*
X1723314Y117450D03*
X1720164Y120600D03*
Y123750D03*
X1723314D03*
X1720164Y133200D03*
Y126800D03*
X1751800Y141700D03*
X1745768Y111743D03*
X1742214Y98550D03*
Y126900D03*
X1745364Y123750D03*
X1742214D03*
X1745364Y120600D03*
X1742214Y114300D03*
Y111150D03*
X1739064Y114300D03*
X1720164Y139500D03*
X1723314Y101700D03*
X1731789Y139450D03*
X1717014Y142650D03*
X1723314Y133200D03*
Y108000D03*
X1726464Y111150D03*
X1723314Y139500D03*
X1739064D03*
X1726464Y133200D03*
X1735914Y108000D03*
X1739064Y123750D03*
X1726464Y120600D03*
X1742214D03*
X1739064Y130050D03*
Y142650D03*
X1726464Y123750D03*
X1720164Y104850D03*
X1742214Y142650D03*
X1726464Y145800D03*
X1723314Y104850D03*
X1720164Y108000D03*
X1734989Y142750D03*
X1723314Y98550D03*
X1735914Y117450D03*
X1728789Y136250D03*
X1723264Y145850D03*
X1739064Y145800D03*
X1723314Y130050D03*
X1735914Y104850D03*
X1735989Y149050D03*
X1742214Y130050D03*
X1726539Y139450D03*
X1720164Y145800D03*
X1739064Y117450D03*
X1723314Y126900D03*
X1735989Y133250D03*
X1739064Y120600D03*
X1723314Y120601D03*
X1739064Y126900D03*
X1735914Y139500D03*
X1739064Y136350D03*
X1723314Y142650D03*
X1742214Y145800D03*
X2088977Y1812552D03*
G54D16*
X-13780Y598560D03*
X-3937Y-43307D03*
Y646063D03*
X1956693Y-43307D03*
Y646063D03*
X2088977Y98952D03*
G54D52*
X1674921Y528523D03*
Y545059D03*
X1773347Y528523D03*
Y545059D03*
X2088977Y166152D03*
G54D43*
X1527844Y159531D03*
X2088977Y199752D03*
G54D35*
X388187Y-5822D03*
Y31978D03*
Y13078D03*
Y69778D03*
Y50878D03*
Y88678D03*
Y514079D03*
Y532955D03*
Y570755D03*
Y589679D03*
Y551879D03*
Y608555D03*
X1037797Y-5822D03*
Y31978D03*
Y13078D03*
Y69778D03*
Y88678D03*
Y50878D03*
Y514079D03*
Y570755D03*
Y532955D03*
Y589679D03*
Y551879D03*
Y608555D03*
X2088977Y-203448D03*
G54D71*
X1970670Y207007D03*
Y242441D03*
X2088977Y-102648D03*
G54D44*
X1627642Y-14488D03*
X1647327Y-315D03*
X1667012Y-14488D03*
X2088977Y1140552D03*
G54D17*
X30500Y-42250D03*
Y-52250D03*
X40500Y-42250D03*
Y-52250D03*
X50500Y-42250D03*
X70500D03*
X90500D03*
X110500D03*
X50500Y-52250D03*
X70500D03*
X90500D03*
X110500D03*
X60500Y-42250D03*
X80500D03*
X100500D03*
X60500Y-52250D03*
X80500D03*
X100500D03*
X130500Y-42250D03*
Y-52250D03*
X120500Y-42250D03*
X140500D03*
X120500Y-52250D03*
X140500D03*
X457246Y-52301D03*
Y-42301D03*
X477246Y-52301D03*
Y-42301D03*
X467246Y-52301D03*
Y-42301D03*
X497246Y-52301D03*
Y-42301D03*
X517246Y-52301D03*
Y-42301D03*
X537246Y-52301D03*
Y-42301D03*
X487246Y-52301D03*
Y-42301D03*
X507246Y-52301D03*
Y-42301D03*
X527246Y-52301D03*
Y-42301D03*
X557246Y-52301D03*
Y-42301D03*
X547246Y-52301D03*
Y-42301D03*
X567246Y-52301D03*
Y-42301D03*
X788984Y-52057D03*
Y-42057D03*
X808984Y-52057D03*
Y-42057D03*
X828984Y-52057D03*
Y-42057D03*
X848984Y-52057D03*
Y-42057D03*
X798984Y-52057D03*
Y-42057D03*
X818984Y-52057D03*
Y-42057D03*
X838984Y-52057D03*
Y-42057D03*
X868984Y-52057D03*
Y-42057D03*
X888984Y-52057D03*
Y-42057D03*
X858984Y-52057D03*
Y-42057D03*
X878984Y-52057D03*
Y-42057D03*
X898984Y-52057D03*
Y-42057D03*
X1125583Y-52285D03*
Y-42285D03*
X1145583Y-52285D03*
Y-42285D03*
X1135583Y-52285D03*
Y-42285D03*
X1155583Y-52285D03*
Y-42285D03*
X1382258Y-52257D03*
Y-42257D03*
X1402258Y-52257D03*
Y-42257D03*
X1392258Y-52257D03*
Y-42257D03*
X1422258Y-52257D03*
Y-42257D03*
X1442258Y-52257D03*
Y-42257D03*
X1412258Y-52257D03*
Y-42257D03*
X1432258Y-52257D03*
Y-42257D03*
X1452258Y-52257D03*
Y-42257D03*
X1895945Y-2322D03*
Y5670D03*
Y13662D03*
Y21654D03*
Y29646D03*
Y37638D03*
Y45630D03*
X1900945Y-6318D03*
Y1674D03*
Y9666D03*
Y17658D03*
Y25650D03*
Y33642D03*
Y41634D03*
Y49626D03*
X2088977Y1174152D03*
G54D53*
X1712205Y536791D03*
X1707205D03*
X1702205D03*
X1697205D03*
X1692205D03*
X1687205D03*
X1712205D03*
X1707205D03*
X1702205D03*
X1697205D03*
X1692205D03*
X1687205D03*
X1717205D03*
D03*
X2088977Y1409352D03*
G54D62*
X1892720Y525415D03*
X1894689Y518328D03*
X1900595Y525415D03*
X1908469D03*
X1916343D03*
X1924217D03*
X1922248Y518328D03*
X1912406D03*
X1904532D03*
X2088977Y1308552D03*
G54D26*
X0Y610630D03*
X677165Y-7874D03*
Y610630D03*
X1405512Y-7874D03*
Y610630D03*
X1854331Y-7874D03*
Y610630D03*
X2088977Y1678152D03*
G54D72*
X1961890Y211043D03*
Y238405D03*
X2088977Y1543752D03*
G54D27*
X94683Y-5822D03*
Y31978D03*
Y13078D03*
Y69778D03*
Y50878D03*
Y88678D03*
Y514079D03*
Y532955D03*
Y570755D03*
Y589679D03*
Y551879D03*
Y608555D03*
X637793Y-5822D03*
Y31978D03*
Y13078D03*
Y69778D03*
Y50878D03*
Y88678D03*
Y514079D03*
Y532955D03*
Y570755D03*
Y589679D03*
Y551879D03*
Y608555D03*
X744293Y-5822D03*
Y31978D03*
Y13078D03*
Y69778D03*
Y88678D03*
Y50878D03*
Y514079D03*
Y570755D03*
Y532955D03*
Y589679D03*
Y551879D03*
Y608555D03*
X1287403Y-5822D03*
Y31978D03*
Y13078D03*
Y69778D03*
Y88678D03*
Y50878D03*
Y514079D03*
Y570755D03*
Y532955D03*
Y589679D03*
Y551879D03*
Y608555D03*
X2088977Y871752D03*
G54D63*
X1887327Y532541D03*
X1929453Y511202D03*
X2088977Y-169848D03*
G54D45*
X1628142Y240199D03*
Y263999D03*
X2088977Y636552D03*
G54D18*
X-7874Y216181D03*
Y325315D03*
X2088977Y132552D03*
G54D54*
X1724606Y235430D03*
X1930319Y451179D03*
X2088977Y367752D03*
G54D36*
X638541Y171945D03*
Y454425D03*
X752641Y159945D03*
Y442425D03*
X1288068Y171945D03*
Y454425D03*
X1402168Y159945D03*
Y442425D03*
X1536123Y23968D03*
X1872343Y29874D03*
X2088977Y300552D03*
G54D46*
X1613069Y302692D03*
X2088977Y804552D03*
G54D19*
X18228Y178386D03*
X-1969D03*
X44291D03*
X2088977Y838152D03*
G54D64*
X1851250Y584622D03*
Y576748D03*
Y568874D03*
Y561000D03*
X2088977Y1241352D03*
G54D28*
X107249Y105000D03*
X102328D03*
X97406D03*
X92485D03*
X87564D03*
X82643D03*
X77721D03*
X72800D03*
X2088977Y1442952D03*
G54D73*
X1969291Y486064D03*
Y497874D03*
X2088977Y569352D03*
G54D37*
X1401516Y23976D03*
X1504666Y29882D03*
X2088977Y334152D03*
G54D55*
X1724807Y451179D03*
X1841929Y235430D03*
X2088977Y602952D03*
G54D74*
G01X430749Y-124922D02*
G02I-12000J0D01*
G01X425599D02*
G02I-6850J0D01*
G01X434749D02*
X402749D01*
G01X434749Y-140922D02*
Y-220922D01*
G01D02*
X1729349D01*
G01X434749Y-176422D02*
X1729349D01*
G01X418749Y-140922D02*
Y-108922D01*
G01X434749Y-140922D02*
X1729349D01*
G01X941849D02*
Y-220922D01*
G01X1079349Y-140922D02*
Y-220922D01*
G01X1194349Y-140922D02*
Y-220922D01*
G01X1361849Y-140922D02*
Y-220922D01*
G01X1531849Y-140922D02*
Y-220922D01*
G01X1729349Y-140922D02*
Y-220922D01*
G01X1757349Y-124922D02*
G02I-12000J0D01*
G01X1752199D02*
G02I-6850J0D01*
G01X1745349Y-140922D02*
Y-108922D01*
G01X1761349Y-124922D02*
X1729349D01*
G54D65*
X1952756Y-14960D03*
Y58268D03*
X2088977Y-136248D03*
G54D47*
X1638131Y525946D03*
Y475946D03*
X2088977Y737352D03*
G54D38*
X1392264Y23976D03*
X1513918D03*
X2088977Y1207752D03*
G54D29*
X63093Y202300D03*
X72936D03*
X82779D03*
X1914911Y495775D03*
X1934597D03*
X1924754D03*
X2088977Y1274952D03*
G54D56*
X1761339Y536791D03*
X1757402D03*
X1753465D03*
X1749528D03*
X1745591D03*
X1741654D03*
X1761339D03*
X1757402D03*
X1753465D03*
X1749528D03*
X1745591D03*
X1741654D03*
X2088977Y1476552D03*
G54D75*
G01X548049Y-193422D02*
Y-210922D01*
G01X543027Y-193422D02*
X553071D01*
G01X565549Y-199256D02*
Y-210922D01*
G01Y-194589D02*
X565112Y-194297D01*
Y-193714D01*
X565549Y-193422D01*
X565986Y-193714D01*
Y-194297D01*
X565549Y-194589D01*
G01X583049Y-210922D02*
X581739Y-210630D01*
X580429Y-209464D01*
X579555Y-207422D01*
X579119Y-205089D01*
X579555Y-202755D01*
X580429Y-200714D01*
X581739Y-199547D01*
X583049Y-199256D01*
X584359Y-199547D01*
X585669Y-200714D01*
X586542Y-202755D01*
X586761Y-205089D01*
X586542Y-207422D01*
X585669Y-209464D01*
X584359Y-210630D01*
X583049Y-210922D01*
G01X597492Y-215297D02*
X599021Y-216464D01*
X600767Y-216755D01*
X602295Y-216464D01*
X603606Y-215006D01*
X604479Y-212964D01*
Y-199256D01*
G01Y-201589D02*
X603606Y-200422D01*
X602295Y-199547D01*
X600767Y-199256D01*
X599021Y-199839D01*
X597929Y-201005D01*
X597055Y-203047D01*
X596619Y-205089D01*
X596837Y-206839D01*
X597711Y-208881D01*
X599021Y-210339D01*
X600767Y-210922D01*
X602077Y-210630D01*
X603606Y-209464D01*
X604479Y-208298D01*
G01X621979Y-210922D02*
Y-199256D01*
G01Y-201297D02*
X621106Y-200131D01*
X619795Y-199547D01*
X618267Y-199256D01*
X616739Y-199839D01*
X615429Y-201005D01*
X614555Y-202755D01*
X614119Y-205089D01*
X614555Y-207422D01*
X615429Y-209172D01*
X616739Y-210339D01*
X618267Y-210922D01*
X619795Y-210630D01*
X621106Y-209756D01*
X621979Y-208589D01*
G01X648682Y-210922D02*
Y-193422D01*
X653922D01*
X655669Y-194297D01*
X656979Y-196339D01*
X657416Y-198672D01*
X656979Y-201005D01*
X655887Y-202755D01*
X653922Y-203631D01*
X648682D01*
G01X674479Y-210922D02*
Y-199256D01*
G01Y-201297D02*
X673606Y-200131D01*
X672295Y-199547D01*
X670767Y-199256D01*
X669239Y-199839D01*
X667929Y-201005D01*
X667055Y-202755D01*
X666619Y-205089D01*
X667055Y-207422D01*
X667929Y-209172D01*
X669239Y-210339D01*
X670767Y-210922D01*
X672295Y-210630D01*
X673606Y-209756D01*
X674479Y-208589D01*
G01X684774Y-208881D02*
X685866Y-210047D01*
X687394Y-210922D01*
X688704D01*
X690014Y-210339D01*
X690887Y-209464D01*
X691324Y-208298D01*
X691106Y-206547D01*
X690232Y-205672D01*
X686302Y-203922D01*
X685429Y-201880D01*
X685866Y-200422D01*
X686739Y-199547D01*
X688049Y-199256D01*
X689359Y-199547D01*
X690669Y-200422D01*
G01X702274Y-208881D02*
X703366Y-210047D01*
X704894Y-210922D01*
X706204D01*
X707514Y-210339D01*
X708387Y-209464D01*
X708824Y-208298D01*
X708606Y-206547D01*
X707732Y-205672D01*
X703802Y-203922D01*
X702929Y-201880D01*
X703366Y-200422D01*
X704239Y-199547D01*
X705549Y-199256D01*
X706859Y-199547D01*
X708169Y-200422D01*
G01X735746Y-210922D02*
Y-193422D01*
X740112D01*
X741859Y-194297D01*
X743169Y-195464D01*
X744261Y-197213D01*
X745134Y-199256D01*
X745352Y-202172D01*
X745134Y-205089D01*
X744261Y-207131D01*
X743169Y-208881D01*
X741859Y-210047D01*
X740112Y-210922D01*
X735746D01*
G01X752590Y-193422D02*
X758049Y-210922D01*
X763508Y-193422D01*
G01X775549D02*
Y-210922D01*
G01X770527Y-193422D02*
X780571D01*
G01X804872Y-210922D02*
Y-193422D01*
X810549Y-208005D01*
X816226Y-193422D01*
Y-210922D01*
G01X829795Y-201589D02*
X830669Y-200714D01*
X831324Y-199256D01*
X831761Y-197213D01*
X831324Y-195464D01*
X830451Y-194297D01*
X828922Y-193422D01*
X823027D01*
Y-210922D01*
X830232D01*
X831761Y-209756D01*
X832634Y-208005D01*
X833071Y-205964D01*
X832634Y-203922D01*
X831324Y-202172D01*
X829795Y-201589D01*
X823027D01*
G01X647372Y-165922D02*
Y-148422D01*
X653049Y-163005D01*
X658726Y-148422D01*
Y-165922D01*
G01X670549D02*
X669239Y-165630D01*
X667929Y-164464D01*
X667055Y-162422D01*
X666619Y-160089D01*
X667055Y-157755D01*
X667929Y-155714D01*
X669239Y-154547D01*
X670549Y-154256D01*
X671859Y-154547D01*
X673169Y-155714D01*
X674042Y-157755D01*
X674261Y-160089D01*
X674042Y-162422D01*
X673169Y-164464D01*
X671859Y-165630D01*
X670549Y-165922D01*
G01X691979Y-148422D02*
Y-165922D01*
G01Y-163298D02*
X691106Y-164756D01*
X689795Y-165630D01*
X688267Y-165922D01*
X686521Y-165339D01*
X685211Y-163881D01*
X684337Y-162131D01*
X684119Y-160089D01*
X684337Y-158047D01*
X685211Y-156297D01*
X686521Y-154839D01*
X688267Y-154256D01*
X689795Y-154547D01*
X690887Y-155131D01*
X691979Y-156297D01*
G01X702274Y-158047D02*
X709261D01*
X708606Y-156005D01*
X707514Y-154839D01*
X705986Y-154256D01*
X704457Y-154547D01*
X703147Y-155422D01*
X702274Y-157464D01*
X701837Y-159214D01*
Y-160964D01*
X702274Y-162714D01*
X703366Y-164464D01*
X704676Y-165630D01*
X706204Y-165922D01*
X707732Y-165339D01*
X709261Y-163589D01*
G01X723049Y-165922D02*
Y-148422D01*
G01X975549Y-210922D02*
Y-193422D01*
X972929Y-196922D01*
G01Y-210922D02*
X978169D01*
G01X988246Y-208298D02*
X989555Y-209756D01*
X991084Y-210630D01*
X993049Y-210922D01*
X995014Y-210339D01*
X996542Y-209172D01*
X997634Y-207131D01*
X997852Y-204797D01*
X997416Y-202464D01*
X996324Y-201005D01*
X994795Y-199839D01*
X993267Y-199547D01*
X991739Y-199839D01*
X989774Y-201005D01*
X990429Y-193422D01*
X996324D01*
G01X1010549Y-210922D02*
Y-193422D01*
X1007929Y-196922D01*
G01Y-210922D02*
X1013169D01*
G01X1023901Y-196339D02*
X1025211Y-194589D01*
X1026739Y-193714D01*
X1028486Y-193422D01*
X1030669Y-194005D01*
X1032197Y-195464D01*
X1032634Y-197213D01*
X1032416Y-198964D01*
X1031542Y-200422D01*
X1027176Y-203339D01*
X1025211Y-205380D01*
X1023901Y-208298D01*
X1023464Y-210922D01*
X1032634D01*
G01X1041401Y-203631D02*
X1042929Y-201589D01*
X1044239Y-200422D01*
X1045986Y-199839D01*
X1047514Y-200422D01*
X1048606Y-201589D01*
X1049479Y-203339D01*
X1049697Y-205380D01*
X1049479Y-207131D01*
X1048606Y-208881D01*
X1047295Y-210339D01*
X1045767Y-210922D01*
X1044021Y-210339D01*
X1042492Y-208589D01*
X1041619Y-205964D01*
X1041401Y-203047D01*
X1041837Y-199256D01*
X1042492Y-197213D01*
X1043584Y-195172D01*
X1045112Y-193714D01*
X1046641Y-193422D01*
X1048169Y-194005D01*
X1049261Y-195464D01*
G01X962432Y-165922D02*
Y-148422D01*
X967672D01*
X969419Y-149297D01*
X970729Y-151339D01*
X971166Y-153672D01*
X970729Y-156005D01*
X969637Y-157755D01*
X967672Y-158631D01*
X962432D01*
G01X989102Y-149881D02*
X987792Y-149005D01*
X986264Y-148422D01*
X984517D01*
X982552Y-149297D01*
X981024Y-150755D01*
X979932Y-152506D01*
X979059Y-155422D01*
X978840Y-158047D01*
X979277Y-160672D01*
X979932Y-162422D01*
X981242Y-164172D01*
X982771Y-165339D01*
X984299Y-165922D01*
X985827D01*
X987356Y-165339D01*
X988666Y-164464D01*
X989758Y-163298D01*
G01X1003545Y-156589D02*
X1004419Y-155714D01*
X1005074Y-154256D01*
X1005511Y-152213D01*
X1005074Y-150464D01*
X1004201Y-149297D01*
X1002672Y-148422D01*
X996777D01*
Y-165922D01*
X1003982D01*
X1005511Y-164756D01*
X1006384Y-163005D01*
X1006821Y-160964D01*
X1006384Y-158922D01*
X1005074Y-157172D01*
X1003545Y-156589D01*
X996777D01*
G01X1012749Y-171755D02*
X1025849D01*
G01X1031777Y-165922D02*
Y-148422D01*
X1041821Y-165922D01*
Y-148422D01*
G01X1054299Y-165922D02*
X1052552Y-165630D01*
X1051024Y-164464D01*
X1049714Y-162714D01*
X1048840Y-160672D01*
X1048404Y-158339D01*
Y-156005D01*
X1048840Y-153672D01*
X1049714Y-151630D01*
X1051024Y-149881D01*
X1052552Y-148714D01*
X1054299Y-148422D01*
X1056045Y-148714D01*
X1057574Y-149881D01*
X1058884Y-151630D01*
X1059758Y-153672D01*
X1060194Y-156005D01*
Y-158339D01*
X1059758Y-160672D01*
X1058884Y-162714D01*
X1057574Y-164464D01*
X1056045Y-165630D01*
X1054299Y-165922D01*
G01X1128099Y-210922D02*
Y-193422D01*
X1125479Y-196922D01*
G01Y-210922D02*
X1130719D01*
G01X1147345Y-201589D02*
X1148219Y-200714D01*
X1148874Y-199256D01*
X1149311Y-197213D01*
X1148874Y-195464D01*
X1148001Y-194297D01*
X1146472Y-193422D01*
X1140577D01*
Y-210922D01*
X1147782D01*
X1149311Y-209756D01*
X1150184Y-208005D01*
X1150621Y-205964D01*
X1150184Y-203922D01*
X1148874Y-202172D01*
X1147345Y-201589D01*
X1140577D01*
G01X1105140Y-148422D02*
X1110599Y-165922D01*
X1116058Y-148422D01*
G01X1132466Y-165922D02*
X1123732D01*
Y-148422D01*
X1132466D01*
G01X1128972Y-156880D02*
X1123732D01*
G01X1141232Y-165922D02*
Y-148422D01*
X1146691D01*
X1148437Y-149297D01*
X1149529Y-150464D01*
X1149966Y-152797D01*
X1149529Y-155131D01*
X1148219Y-156589D01*
X1146691Y-157464D01*
X1141232D01*
G01X1146691D02*
X1149966Y-165922D01*
G01X1163099Y-166505D02*
X1162662Y-166214D01*
Y-165630D01*
X1163099Y-165339D01*
X1163536Y-165630D01*
Y-166214D01*
X1163099Y-166505D01*
G01X1238246Y-210922D02*
Y-193422D01*
X1242612D01*
X1244359Y-194297D01*
X1245669Y-195464D01*
X1246761Y-197213D01*
X1247634Y-199256D01*
X1247852Y-202172D01*
X1247634Y-205089D01*
X1246761Y-207131D01*
X1245669Y-208881D01*
X1244359Y-210047D01*
X1242612Y-210922D01*
X1238246D01*
G01X1256182D02*
Y-193422D01*
X1261641D01*
X1263387Y-194297D01*
X1264479Y-195464D01*
X1264916Y-197797D01*
X1264479Y-200131D01*
X1263169Y-201589D01*
X1261641Y-202464D01*
X1256182D01*
G01X1261641D02*
X1264916Y-210922D01*
G01X1275429Y-193422D02*
X1280669D01*
G01X1278049D02*
Y-210922D01*
G01X1275429D02*
X1280669D01*
G01X1291182Y-193422D02*
Y-210922D01*
X1299916D01*
G01X1308682Y-193422D02*
Y-210922D01*
X1317416D01*
G01X1238682Y-148422D02*
Y-165922D01*
X1247416D01*
G01X1264479D02*
Y-154256D01*
G01Y-156297D02*
X1263606Y-155131D01*
X1262295Y-154547D01*
X1260767Y-154256D01*
X1259239Y-154839D01*
X1257929Y-156005D01*
X1257055Y-157755D01*
X1256619Y-160089D01*
X1257055Y-162422D01*
X1257929Y-164172D01*
X1259239Y-165339D01*
X1260767Y-165922D01*
X1262295Y-165630D01*
X1263606Y-164756D01*
X1264479Y-163589D01*
G01X1273464Y-171172D02*
X1274774Y-171755D01*
X1276521Y-171172D01*
X1277612Y-170006D01*
X1278486Y-168547D01*
X1279795Y-163881D01*
X1282634Y-154256D01*
G01X1275647D02*
X1279795Y-163881D01*
G01X1292274Y-158047D02*
X1299261D01*
X1298606Y-156005D01*
X1297514Y-154839D01*
X1295986Y-154256D01*
X1294457Y-154547D01*
X1293147Y-155422D01*
X1292274Y-157464D01*
X1291837Y-159214D01*
Y-160964D01*
X1292274Y-162714D01*
X1293366Y-164464D01*
X1294676Y-165630D01*
X1296204Y-165922D01*
X1297732Y-165339D01*
X1299261Y-163589D01*
G01X1309992Y-165922D02*
Y-154256D01*
G01Y-156589D02*
X1311084Y-155422D01*
X1312176Y-154547D01*
X1313704Y-154256D01*
X1314795Y-154547D01*
X1316106Y-155422D01*
G01X1380796Y-165922D02*
Y-148422D01*
X1385162D01*
X1386909Y-149297D01*
X1388219Y-150464D01*
X1389311Y-152213D01*
X1390184Y-154256D01*
X1390402Y-157172D01*
X1390184Y-160089D01*
X1389311Y-162131D01*
X1388219Y-163881D01*
X1386909Y-165047D01*
X1385162Y-165922D01*
X1380796D01*
G01X1399824Y-158047D02*
X1406811D01*
X1406156Y-156005D01*
X1405064Y-154839D01*
X1403536Y-154256D01*
X1402007Y-154547D01*
X1400697Y-155422D01*
X1399824Y-157464D01*
X1399387Y-159214D01*
Y-160964D01*
X1399824Y-162714D01*
X1400916Y-164464D01*
X1402226Y-165630D01*
X1403754Y-165922D01*
X1405282Y-165339D01*
X1406811Y-163589D01*
G01X1417324Y-163881D02*
X1418416Y-165047D01*
X1419944Y-165922D01*
X1421254D01*
X1422564Y-165339D01*
X1423437Y-164464D01*
X1423874Y-163298D01*
X1423656Y-161547D01*
X1422782Y-160672D01*
X1418852Y-158922D01*
X1417979Y-156880D01*
X1418416Y-155422D01*
X1419289Y-154547D01*
X1420599Y-154256D01*
X1421909Y-154547D01*
X1423219Y-155422D01*
G01X1438099Y-154256D02*
Y-165922D01*
G01Y-149589D02*
X1437662Y-149297D01*
Y-148714D01*
X1438099Y-148422D01*
X1438536Y-148714D01*
Y-149297D01*
X1438099Y-149589D01*
G01X1452542Y-170297D02*
X1454071Y-171464D01*
X1455817Y-171755D01*
X1457345Y-171464D01*
X1458656Y-170006D01*
X1459529Y-167964D01*
Y-154256D01*
G01Y-156589D02*
X1458656Y-155422D01*
X1457345Y-154547D01*
X1455817Y-154256D01*
X1454071Y-154839D01*
X1452979Y-156005D01*
X1452105Y-158047D01*
X1451669Y-160089D01*
X1451887Y-161839D01*
X1452761Y-163881D01*
X1454071Y-165339D01*
X1455817Y-165922D01*
X1457127Y-165630D01*
X1458656Y-164464D01*
X1459529Y-163298D01*
G01X1469387Y-165922D02*
Y-154256D01*
G01Y-157172D02*
X1470261Y-155714D01*
X1471571Y-154547D01*
X1473317Y-154256D01*
X1474845Y-154547D01*
X1476156Y-155714D01*
X1476811Y-157755D01*
Y-165922D01*
G01X1487324Y-158047D02*
X1494311D01*
X1493656Y-156005D01*
X1492564Y-154839D01*
X1491036Y-154256D01*
X1489507Y-154547D01*
X1488197Y-155422D01*
X1487324Y-157464D01*
X1486887Y-159214D01*
Y-160964D01*
X1487324Y-162714D01*
X1488416Y-164464D01*
X1489726Y-165630D01*
X1491254Y-165922D01*
X1492782Y-165339D01*
X1494311Y-163589D01*
G01X1505042Y-165922D02*
Y-154256D01*
G01Y-156589D02*
X1506134Y-155422D01*
X1507226Y-154547D01*
X1508754Y-154256D01*
X1509845Y-154547D01*
X1511156Y-155422D01*
G01X1426729Y-193422D02*
X1431969D01*
G01X1429349D02*
Y-210922D01*
G01X1426729D02*
X1431969D01*
G01X1441390Y-193422D02*
X1446849Y-210922D01*
X1452308Y-193422D01*
G01X1464349Y-210922D02*
Y-203047D01*
X1459982Y-193422D01*
G01X1468716D02*
X1464349Y-203047D01*
G01X1551799Y-193422D02*
X1550052Y-194005D01*
X1548742Y-195464D01*
X1547869Y-197213D01*
X1547214Y-199547D01*
X1546996Y-202172D01*
X1547214Y-204797D01*
X1547869Y-207131D01*
X1548742Y-208881D01*
X1550052Y-210339D01*
X1551799Y-210922D01*
X1553545Y-210339D01*
X1554856Y-208881D01*
X1555729Y-207131D01*
X1556384Y-204797D01*
X1556602Y-202172D01*
X1556384Y-199547D01*
X1555729Y-197213D01*
X1554856Y-195464D01*
X1553545Y-194005D01*
X1551799Y-193422D01*
G01X1565151Y-196339D02*
X1566461Y-194589D01*
X1567989Y-193714D01*
X1569736Y-193422D01*
X1571919Y-194005D01*
X1573447Y-195464D01*
X1573884Y-197213D01*
X1573666Y-198964D01*
X1572792Y-200422D01*
X1568426Y-203339D01*
X1566461Y-205380D01*
X1565151Y-208298D01*
X1564714Y-210922D01*
X1573884D01*
G01X1582869Y-211505D02*
X1590729Y-193422D01*
G01X1604299Y-210922D02*
Y-193422D01*
X1601679Y-196922D01*
G01Y-210922D02*
X1606919D01*
G01X1621799Y-193422D02*
X1620052Y-194005D01*
X1618742Y-195464D01*
X1617869Y-197213D01*
X1617214Y-199547D01*
X1616996Y-202172D01*
X1617214Y-204797D01*
X1617869Y-207131D01*
X1618742Y-208881D01*
X1620052Y-210339D01*
X1621799Y-210922D01*
X1623545Y-210339D01*
X1624856Y-208881D01*
X1625729Y-207131D01*
X1626384Y-204797D01*
X1626602Y-202172D01*
X1626384Y-199547D01*
X1625729Y-197213D01*
X1624856Y-195464D01*
X1623545Y-194005D01*
X1621799Y-193422D01*
G01X1635369Y-211505D02*
X1643229Y-193422D01*
G01X1652651Y-196339D02*
X1653961Y-194589D01*
X1655489Y-193714D01*
X1657236Y-193422D01*
X1659419Y-194005D01*
X1660947Y-195464D01*
X1661384Y-197213D01*
X1661166Y-198964D01*
X1660292Y-200422D01*
X1655926Y-203339D01*
X1653961Y-205380D01*
X1652651Y-208298D01*
X1652214Y-210922D01*
X1661384D01*
G01X1674299Y-193422D02*
X1672552Y-194005D01*
X1671242Y-195464D01*
X1670369Y-197213D01*
X1669714Y-199547D01*
X1669496Y-202172D01*
X1669714Y-204797D01*
X1670369Y-207131D01*
X1671242Y-208881D01*
X1672552Y-210339D01*
X1674299Y-210922D01*
X1676045Y-210339D01*
X1677356Y-208881D01*
X1678229Y-207131D01*
X1678884Y-204797D01*
X1679102Y-202172D01*
X1678884Y-199547D01*
X1678229Y-197213D01*
X1677356Y-195464D01*
X1676045Y-194005D01*
X1674299Y-193422D01*
G01X1691799Y-210922D02*
Y-193422D01*
X1689179Y-196922D01*
G01Y-210922D02*
X1694419D01*
G01X1708862D02*
X1709299Y-207131D01*
X1709954Y-203922D01*
X1710827Y-201005D01*
X1711919Y-197797D01*
X1713666Y-193422D01*
X1704932D01*
G01X1599496Y-165922D02*
Y-148422D01*
X1603862D01*
X1605609Y-149297D01*
X1606919Y-150464D01*
X1608011Y-152213D01*
X1608884Y-154256D01*
X1609102Y-157172D01*
X1608884Y-160089D01*
X1608011Y-162131D01*
X1606919Y-163881D01*
X1605609Y-165047D01*
X1603862Y-165922D01*
X1599496D01*
G01X1625729D02*
Y-154256D01*
G01Y-156297D02*
X1624856Y-155131D01*
X1623545Y-154547D01*
X1622017Y-154256D01*
X1620489Y-154839D01*
X1619179Y-156005D01*
X1618305Y-157755D01*
X1617869Y-160089D01*
X1618305Y-162422D01*
X1619179Y-164172D01*
X1620489Y-165339D01*
X1622017Y-165922D01*
X1623545Y-165630D01*
X1624856Y-164756D01*
X1625729Y-163589D01*
G01X1639299Y-148422D02*
Y-165922D01*
G01X1636242Y-154256D02*
X1642356D01*
G01X1653524Y-158047D02*
X1660511D01*
X1659856Y-156005D01*
X1658764Y-154839D01*
X1657236Y-154256D01*
X1655707Y-154547D01*
X1654397Y-155422D01*
X1653524Y-157464D01*
X1653087Y-159214D01*
Y-160964D01*
X1653524Y-162714D01*
X1654616Y-164464D01*
X1655926Y-165630D01*
X1657454Y-165922D01*
X1658982Y-165339D01*
X1660511Y-163589D01*
G01X1955134Y-13960D02*
X1968256Y10154D01*
G01X1956206Y-8851D02*
X1955134Y-13960D01*
X1958841Y-10285D01*
X1956206Y-8851D01*
G01X1955306Y-13960D02*
G02Y-15960I0J-1000D01*
G01X1950206D01*
G02Y-13960I0J1000D01*
G01X1955306D01*
G01X1955347Y57269D02*
X1967756Y31654D01*
G01X1958877Y53423D02*
X1955347Y57269D01*
X1956177Y52115D01*
X1958877Y53423D01*
G01X1955306Y59268D02*
G02Y57268I0J-1000D01*
G01X1950206D01*
G02Y59268I0J1000D01*
G01X1955306D01*
G01X1955890Y207724D02*
X1963740Y207974D01*
X1969790Y214174D01*
G01X1960343Y209373D02*
X1955840Y207724D01*
X1960433Y206374D01*
X1960343Y209373D01*
G01X1955900Y207893D02*
G02X1954500Y206493I-1400J0D01*
G01X1950000D01*
G02X1948600Y207893I0J1400D01*
G01Y210293D01*
G02X1951400I1400J0D01*
G01Y209693D01*
G03X1951800Y209293I400J0D01*
G01X1954500D01*
G02X1955900Y207893I0J-1400D01*
G01X1949000Y228903D02*
X1943990Y224524D01*
G01X1946222Y224483D02*
X1949000Y228903D01*
X1944248Y226742D01*
X1946222Y224483D01*
G01X1949000Y221165D02*
X1943940Y224474D01*
G01X1943994Y222646D02*
X1949000Y221165D01*
X1945636Y225157D01*
X1943994Y222646D01*
G01X1955940Y241574D02*
X1964040Y241724D01*
X1969740Y235974D01*
G01X1960363Y243160D02*
X1955890Y241574D01*
X1960415Y240161D01*
X1960363Y243160D01*
G01X1955900Y241555D02*
G03X1954500Y242955I-1400J0D01*
G01X1950000D01*
G03X1948600Y241555I0J-1400D01*
G01Y239155D01*
G03X1951400I1400J0D01*
G01Y239755D01*
G02X1951800Y240155I400J0D01*
G01X1954500D01*
G03X1955900Y241555I0J1400D01*
G01X1951000Y220187D02*
Y221387D01*
G03X1949000I-1000J0D01*
G01Y220187D01*
G03X1951000I1000J0D01*
G01Y228061D02*
Y229261D01*
G03X1949000I-1000J0D01*
G01Y228061D01*
G03X1951000I1000J0D01*
G01X1973240Y207874D02*
X1980740Y213374D01*
G01X1976385Y212040D02*
X1973240Y207874D01*
X1978159Y209621D01*
X1976385Y212040D01*
G01X1972670Y206007D02*
X1968670D01*
G02Y208007I0J1000D01*
G01X1972670D01*
G02Y206007I0J-1000D01*
G01X1973190Y241474D02*
X1980090Y235974D01*
G01X1978035Y239530D02*
X1973190Y241474D01*
X1976165Y237185D01*
X1978035Y239530D01*
G01X1972670Y241441D02*
X1968670D01*
G02Y243441I0J1000D01*
G01X1972670D01*
G02Y241441I0J-1000D01*
G01X2045112Y-317448D02*
Y-304948D01*
X2052242Y-317448D01*
Y-304948D01*
G01X2061077Y-317448D02*
X2060147Y-317240D01*
X2059217Y-316407D01*
X2058597Y-314948D01*
X2058287Y-313281D01*
X2058597Y-311615D01*
X2059217Y-310156D01*
X2060147Y-309323D01*
X2061077Y-309115D01*
X2062007Y-309323D01*
X2062937Y-310156D01*
X2063557Y-311615D01*
X2063712Y-313281D01*
X2063557Y-314948D01*
X2062937Y-316407D01*
X2062007Y-317240D01*
X2061077Y-317448D01*
G01X2073477Y-304948D02*
Y-317448D01*
G01X2071307Y-309115D02*
X2075647D01*
G01X2083552Y-311823D02*
X2088512D01*
X2088047Y-310365D01*
X2087272Y-309531D01*
X2086187Y-309115D01*
X2085102Y-309323D01*
X2084172Y-309948D01*
X2083552Y-311406D01*
X2083242Y-312657D01*
Y-313906D01*
X2083552Y-315156D01*
X2084327Y-316407D01*
X2085257Y-317240D01*
X2086342Y-317448D01*
X2087427Y-317031D01*
X2088512Y-315782D01*
G01X2098277Y-317865D02*
X2097967Y-317656D01*
Y-317240D01*
X2098277Y-317031D01*
X2098587Y-317240D01*
Y-317656D01*
X2098277Y-317865D01*
G01Y-312240D02*
X2097967Y-312031D01*
Y-311615D01*
X2098277Y-311406D01*
X2098587Y-311615D01*
Y-312031D01*
X2098277Y-312240D01*
G01X2107577Y-317448D02*
Y-304948D01*
X2111452D01*
X2112692Y-305573D01*
X2113467Y-306406D01*
X2113777Y-308073D01*
X2113467Y-309740D01*
X2112537Y-310781D01*
X2111452Y-311406D01*
X2107577D01*
G01X2111452D02*
X2113777Y-317448D01*
G01X2120752Y-311823D02*
X2125712D01*
X2125247Y-310365D01*
X2124472Y-309531D01*
X2123387Y-309115D01*
X2122302Y-309323D01*
X2121372Y-309948D01*
X2120752Y-311406D01*
X2120442Y-312657D01*
Y-313906D01*
X2120752Y-315156D01*
X2121527Y-316407D01*
X2122457Y-317240D01*
X2123542Y-317448D01*
X2124627Y-317031D01*
X2125712Y-315782D01*
G01X2134547Y-317448D02*
Y-306823D01*
X2134857Y-305782D01*
X2135477Y-305156D01*
X2136407Y-304948D01*
X2137337Y-305365D01*
X2137802Y-306406D01*
G01X2135942Y-309948D02*
X2132842D01*
G01X2145552Y-311823D02*
X2150512D01*
X2150047Y-310365D01*
X2149272Y-309531D01*
X2148187Y-309115D01*
X2147102Y-309323D01*
X2146172Y-309948D01*
X2145552Y-311406D01*
X2145242Y-312657D01*
Y-313906D01*
X2145552Y-315156D01*
X2146327Y-316407D01*
X2147257Y-317240D01*
X2148342Y-317448D01*
X2149427Y-317031D01*
X2150512Y-315782D01*
G01X2158107Y-317448D02*
Y-309115D01*
G01Y-310781D02*
X2158882Y-309948D01*
X2159657Y-309323D01*
X2160742Y-309115D01*
X2161517Y-309323D01*
X2162447Y-309948D01*
G01X2185077Y-304948D02*
Y-317448D01*
G01X2182907Y-309115D02*
X2187247D01*
G01X2197477Y-317448D02*
X2196547Y-317240D01*
X2195617Y-316407D01*
X2194997Y-314948D01*
X2194687Y-313281D01*
X2194997Y-311615D01*
X2195617Y-310156D01*
X2196547Y-309323D01*
X2197477Y-309115D01*
X2198407Y-309323D01*
X2199337Y-310156D01*
X2199957Y-311615D01*
X2200112Y-313281D01*
X2199957Y-314948D01*
X2199337Y-316407D01*
X2198407Y-317240D01*
X2197477Y-317448D01*
G01X2218867D02*
Y-304948D01*
X2221967D01*
X2223207Y-305573D01*
X2224137Y-306406D01*
X2224912Y-307656D01*
X2225532Y-309115D01*
X2225687Y-311198D01*
X2225532Y-313281D01*
X2224912Y-314740D01*
X2224137Y-315990D01*
X2223207Y-316823D01*
X2221967Y-317448D01*
X2218867D01*
G01X2231577D02*
Y-304948D01*
X2235452D01*
X2236692Y-305573D01*
X2237467Y-306406D01*
X2237777Y-308073D01*
X2237467Y-309740D01*
X2236537Y-310781D01*
X2235452Y-311406D01*
X2231577D01*
G01X2235452D02*
X2237777Y-317448D01*
G01X2245217Y-304948D02*
X2248937D01*
G01X2247077D02*
Y-317448D01*
G01X2245217D02*
X2248937D01*
G01X2256377Y-304948D02*
Y-317448D01*
X2262577D01*
G01X2268777Y-304948D02*
Y-317448D01*
X2274977D01*
G01X2296677D02*
Y-304948D01*
G01X2311867Y-317448D02*
Y-309115D01*
G01Y-310573D02*
X2311247Y-309740D01*
X2310317Y-309323D01*
X2309232Y-309115D01*
X2308147Y-309531D01*
X2307217Y-310365D01*
X2306597Y-311615D01*
X2306287Y-313281D01*
X2306597Y-314948D01*
X2307217Y-316198D01*
X2308147Y-317031D01*
X2309232Y-317448D01*
X2310317Y-317240D01*
X2311247Y-316615D01*
X2311867Y-315782D01*
G01X2318222Y-321198D02*
X2319152Y-321615D01*
X2320392Y-321198D01*
X2321167Y-320365D01*
X2321787Y-319323D01*
X2322717Y-315990D01*
X2324732Y-309115D01*
G01X2319772D02*
X2322717Y-315990D01*
G01X2331552Y-311823D02*
X2336512D01*
X2336047Y-310365D01*
X2335272Y-309531D01*
X2334187Y-309115D01*
X2333102Y-309323D01*
X2332172Y-309948D01*
X2331552Y-311406D01*
X2331242Y-312657D01*
Y-313906D01*
X2331552Y-315156D01*
X2332327Y-316407D01*
X2333257Y-317240D01*
X2334342Y-317448D01*
X2335427Y-317031D01*
X2336512Y-315782D01*
G01X2344107Y-317448D02*
Y-309115D01*
G01Y-310781D02*
X2344882Y-309948D01*
X2345657Y-309323D01*
X2346742Y-309115D01*
X2347517Y-309323D01*
X2348447Y-309948D01*
G01X2370147Y-317448D02*
Y-306823D01*
X2370457Y-305782D01*
X2371077Y-305156D01*
X2372007Y-304948D01*
X2372937Y-305365D01*
X2373402Y-306406D01*
G01X2371542Y-309948D02*
X2368442D01*
G01X2383477Y-317448D02*
X2382547Y-317240D01*
X2381617Y-316407D01*
X2380997Y-314948D01*
X2380687Y-313281D01*
X2380997Y-311615D01*
X2381617Y-310156D01*
X2382547Y-309323D01*
X2383477Y-309115D01*
X2384407Y-309323D01*
X2385337Y-310156D01*
X2385957Y-311615D01*
X2386112Y-313281D01*
X2385957Y-314948D01*
X2385337Y-316407D01*
X2384407Y-317240D01*
X2383477Y-317448D01*
G01X2393707D02*
Y-309115D01*
G01Y-310781D02*
X2394482Y-309948D01*
X2395257Y-309323D01*
X2396342Y-309115D01*
X2397117Y-309323D01*
X2398047Y-309948D01*
G01X2423777Y-317448D02*
X2417577D01*
Y-304948D01*
X2423777D01*
G01X2421297Y-310990D02*
X2417577D01*
G01X2429977Y-304948D02*
Y-317448D01*
X2436177D01*
G01X2442377Y-304948D02*
Y-317448D01*
X2448577D01*
G01X2456017Y-304948D02*
X2459737D01*
G01X2457877D02*
Y-317448D01*
G01X2456017D02*
X2459737D01*
G01X2467177D02*
Y-304948D01*
X2470897D01*
X2472137Y-305573D01*
X2473067Y-307031D01*
X2473377Y-308698D01*
X2473067Y-310365D01*
X2472292Y-311615D01*
X2470897Y-312240D01*
X2467177D01*
G01X2479422Y-315782D02*
X2480662Y-316823D01*
X2482057Y-317448D01*
X2483297D01*
X2484537Y-316823D01*
X2485467Y-315782D01*
X2485932Y-314323D01*
X2485622Y-312865D01*
X2484847Y-311615D01*
X2483452Y-310781D01*
X2481592Y-310365D01*
X2480507Y-309531D01*
X2480042Y-308073D01*
X2480352Y-306615D01*
X2481127Y-305573D01*
X2482212Y-304948D01*
X2483297D01*
X2484382Y-305365D01*
X2485312Y-306406D01*
G01X2498177Y-317448D02*
X2491977D01*
Y-304948D01*
X2498177D01*
G01X2495697Y-310990D02*
X2491977D01*
G01X2522667Y-304948D02*
Y-317448D01*
G01Y-315573D02*
X2522047Y-316615D01*
X2521117Y-317240D01*
X2520032Y-317448D01*
X2518792Y-317031D01*
X2517862Y-315990D01*
X2517242Y-314740D01*
X2517087Y-313281D01*
X2517242Y-311823D01*
X2517862Y-310573D01*
X2518792Y-309531D01*
X2520032Y-309115D01*
X2521117Y-309323D01*
X2521892Y-309740D01*
X2522667Y-310573D01*
G01X2530107Y-317448D02*
Y-309115D01*
G01Y-310781D02*
X2530882Y-309948D01*
X2531657Y-309323D01*
X2532742Y-309115D01*
X2533517Y-309323D01*
X2534447Y-309948D01*
G01X2544677Y-309115D02*
Y-317448D01*
G01Y-305782D02*
X2544367Y-305573D01*
Y-305156D01*
X2544677Y-304948D01*
X2544987Y-305156D01*
Y-305573D01*
X2544677Y-305782D01*
G01X2557077Y-317448D02*
Y-304948D01*
G01X2569477Y-317448D02*
Y-304948D01*
G01X2597067D02*
Y-317448D01*
G01Y-315573D02*
X2596447Y-316615D01*
X2595517Y-317240D01*
X2594432Y-317448D01*
X2593192Y-317031D01*
X2592262Y-315990D01*
X2591642Y-314740D01*
X2591487Y-313281D01*
X2591642Y-311823D01*
X2592262Y-310573D01*
X2593192Y-309531D01*
X2594432Y-309115D01*
X2595517Y-309323D01*
X2596292Y-309740D01*
X2597067Y-310573D01*
G01X2606677Y-309115D02*
Y-317448D01*
G01Y-305782D02*
X2606367Y-305573D01*
Y-305156D01*
X2606677Y-304948D01*
X2606987Y-305156D01*
Y-305573D01*
X2606677Y-305782D01*
G01X2616907Y-317448D02*
Y-309115D01*
G01Y-310781D02*
X2617682Y-309948D01*
X2618457Y-309323D01*
X2619542Y-309115D01*
X2620317Y-309323D01*
X2621247Y-309948D01*
G01X2629152Y-311823D02*
X2634112D01*
X2633647Y-310365D01*
X2632872Y-309531D01*
X2631787Y-309115D01*
X2630702Y-309323D01*
X2629772Y-309948D01*
X2629152Y-311406D01*
X2628842Y-312657D01*
Y-313906D01*
X2629152Y-315156D01*
X2629927Y-316407D01*
X2630857Y-317240D01*
X2631942Y-317448D01*
X2633027Y-317031D01*
X2634112Y-315782D01*
G01X2646357Y-310156D02*
X2645272Y-309323D01*
X2644342Y-309115D01*
X2643102Y-309531D01*
X2642172Y-310365D01*
X2641552Y-311823D01*
X2641397Y-313281D01*
X2641552Y-314740D01*
X2642172Y-315990D01*
X2643102Y-317031D01*
X2644342Y-317448D01*
X2645427Y-317031D01*
X2646357Y-316198D01*
G01X2656277Y-304948D02*
Y-317448D01*
G01X2654107Y-309115D02*
X2658447D01*
G01X2668677D02*
Y-317448D01*
G01Y-305782D02*
X2668367Y-305573D01*
Y-305156D01*
X2668677Y-304948D01*
X2668987Y-305156D01*
Y-305573D01*
X2668677Y-305782D01*
G01X2681077Y-317448D02*
X2680147Y-317240D01*
X2679217Y-316407D01*
X2678597Y-314948D01*
X2678287Y-313281D01*
X2678597Y-311615D01*
X2679217Y-310156D01*
X2680147Y-309323D01*
X2681077Y-309115D01*
X2682007Y-309323D01*
X2682937Y-310156D01*
X2683557Y-311615D01*
X2683712Y-313281D01*
X2683557Y-314948D01*
X2682937Y-316407D01*
X2682007Y-317240D01*
X2681077Y-317448D01*
G01X2690842D02*
Y-309115D01*
G01Y-311198D02*
X2691462Y-310156D01*
X2692392Y-309323D01*
X2693632Y-309115D01*
X2694717Y-309323D01*
X2695647Y-310156D01*
X2696112Y-311615D01*
Y-317448D01*
G01X2044027Y-287448D02*
Y1937952D01*
X2716727D01*
Y-287448D01*
X2044027D01*
G01Y-253848D02*
X2716727D01*
G01X2044027Y-220248D02*
X2716727D01*
G01X2044027Y-186648D02*
X2716727D01*
G01X2044027Y-153048D02*
X2716727D01*
G01X2044027Y-119448D02*
X2716727D01*
G01X2044027Y-85848D02*
X2716727D01*
G01X2044027Y-52248D02*
X2716727D01*
G01X2044027Y-18648D02*
X2716727D01*
G01X2044027Y14952D02*
X2716727D01*
G01X2044027Y48552D02*
X2716727D01*
G01X2044027Y82152D02*
X2716727D01*
G01X2044027Y115752D02*
X2716727D01*
G01X2044027Y149352D02*
X2716727D01*
G01X2044027Y182952D02*
X2716727D01*
G01X2044027Y216552D02*
X2716727D01*
G01X2044027Y250152D02*
X2716727D01*
G01X2044027Y283752D02*
X2716727D01*
G01X2044027Y317352D02*
X2716727D01*
G01X2044027Y350952D02*
X2716727D01*
G01X2044027Y384552D02*
X2716727D01*
G01X2044027Y418152D02*
X2716727D01*
G01X2044027Y451752D02*
X2716727D01*
G01X2044027Y485352D02*
X2716727D01*
G01X2044027Y518952D02*
X2716727D01*
G01X2044027Y552552D02*
X2716727D01*
G01X2044027Y586152D02*
X2716727D01*
G01X2044027Y619752D02*
X2716727D01*
G01X2044027Y653352D02*
X2716727D01*
G01X2044027Y686952D02*
X2716727D01*
G01X2044027Y720552D02*
X2716727D01*
G01X2044027Y754152D02*
X2716727D01*
G01X2044027Y787752D02*
X2716727D01*
G01X2044027Y821352D02*
X2716727D01*
G01X2044027Y854952D02*
X2716727D01*
G01X2044027Y888552D02*
X2716727D01*
G01X2044027Y922152D02*
X2716727D01*
G01X2044027Y955752D02*
X2716727D01*
G01X2044027Y989352D02*
X2716727D01*
G01X2044027Y1022952D02*
X2716727D01*
G01X2044027Y1056552D02*
X2716727D01*
G01X2044027Y1090152D02*
X2716727D01*
G01X2044027Y1123752D02*
X2716727D01*
G01X2044027Y1157352D02*
X2716727D01*
G01X2044027Y1190952D02*
X2716727D01*
G01X2044027Y1224552D02*
X2716727D01*
G01X2044027Y1258152D02*
X2716727D01*
G01X2044027Y1291752D02*
X2716727D01*
G01X2044027Y1325352D02*
X2716727D01*
G01X2044027Y1358952D02*
X2716727D01*
G01X2044027Y1392552D02*
X2716727D01*
G01X2044027Y1426152D02*
X2716727D01*
G01X2044027Y1459752D02*
X2716727D01*
G01X2044027Y1493352D02*
X2716727D01*
G01X2044027Y1526952D02*
X2716727D01*
G01X2044027Y1560552D02*
X2716727D01*
G01X2044027Y1594152D02*
X2716727D01*
G01X2044027Y1627752D02*
X2716727D01*
G01X2044027Y1661352D02*
X2716727D01*
G01X2044027Y1694952D02*
X2716727D01*
G01X2044027Y1728552D02*
X2716727D01*
G01X2044027Y1762152D02*
X2716727D01*
G01X2044027Y1795752D02*
X2716727D01*
G01X2044027Y1829352D02*
X2716727D01*
G01X2044027Y1862952D02*
X2716727D01*
G01X2055032Y1869202D02*
Y1881702D01*
X2060922D01*
G01X2058752Y1875660D02*
X2055032D01*
G01X2068517Y1881702D02*
X2072237D01*
G01X2070377D02*
Y1869202D01*
G01X2068517D02*
X2072237D01*
G01X2083707Y1875452D02*
X2086807D01*
Y1871702D01*
X2085877Y1870452D01*
X2084792Y1869619D01*
X2083242Y1869202D01*
X2081692Y1869619D01*
X2080607Y1870452D01*
X2079677Y1871702D01*
X2079057Y1873160D01*
X2078747Y1874827D01*
Y1876285D01*
X2079057Y1877535D01*
X2079677Y1878994D01*
X2080607Y1880244D01*
X2081537Y1881077D01*
X2082777Y1881702D01*
X2083862D01*
X2085102Y1881285D01*
X2086032Y1880452D01*
G01X2091767Y1881702D02*
Y1872744D01*
X2092387Y1870868D01*
X2093627Y1869619D01*
X2095177Y1869202D01*
X2096727Y1869619D01*
X2097967Y1870868D01*
X2098587Y1872744D01*
Y1881702D01*
G01X2104477Y1869202D02*
Y1881702D01*
X2108352D01*
X2109592Y1881077D01*
X2110367Y1880244D01*
X2110677Y1878577D01*
X2110367Y1876910D01*
X2109437Y1875869D01*
X2108352Y1875244D01*
X2104477D01*
G01X2108352D02*
X2110677Y1869202D01*
G01X2123077D02*
X2116877D01*
Y1881702D01*
X2123077D01*
G01X2120597Y1875660D02*
X2116877D01*
G01X2044027Y1887952D02*
X2716727D01*
G01X2044027Y1912952D02*
X2716727D01*
G01X2133927Y1887952D02*
Y-287448D01*
G01X2166477Y-276898D02*
Y-264398D01*
X2164617Y-266898D01*
G01Y-276898D02*
X2168337D01*
G01X2176242Y-275440D02*
X2177327Y-276481D01*
X2178567Y-276898D01*
X2179807Y-276481D01*
X2180892Y-275232D01*
X2181667Y-273356D01*
X2181977Y-271481D01*
Y-269190D01*
X2181667Y-267315D01*
X2180892Y-265648D01*
X2179962Y-264815D01*
X2178877Y-264398D01*
X2177637Y-264815D01*
X2176707Y-265648D01*
X2176087Y-266898D01*
X2175777Y-268565D01*
X2176087Y-270023D01*
X2176862Y-271481D01*
X2177792Y-272315D01*
X2178877Y-272523D01*
X2180117Y-272107D01*
X2181047Y-271065D01*
X2181977Y-269190D01*
G01X2191277Y-276898D02*
Y-264398D01*
X2189417Y-266898D01*
G01Y-276898D02*
X2193137D01*
G01X2203677Y-277315D02*
X2203367Y-277106D01*
Y-276690D01*
X2203677Y-276481D01*
X2203987Y-276690D01*
Y-277106D01*
X2203677Y-277315D01*
G01X2216077Y-264398D02*
X2214837Y-264815D01*
X2213907Y-265856D01*
X2213287Y-267106D01*
X2212822Y-268773D01*
X2212667Y-270648D01*
X2212822Y-272523D01*
X2213287Y-274190D01*
X2213907Y-275440D01*
X2214837Y-276481D01*
X2216077Y-276898D01*
X2217317Y-276481D01*
X2218247Y-275440D01*
X2218867Y-274190D01*
X2219332Y-272523D01*
X2219487Y-270648D01*
X2219332Y-268773D01*
X2218867Y-267106D01*
X2218247Y-265856D01*
X2217317Y-264815D01*
X2216077Y-264398D01*
G01X2226152Y-268565D02*
X2230802Y-276898D01*
G01Y-268565D02*
X2226152Y-276898D01*
G01X2240877D02*
Y-264398D01*
X2239017Y-266898D01*
G01Y-276898D02*
X2242737D01*
G01X2250332Y-266481D02*
X2251262Y-265232D01*
X2252347Y-264606D01*
X2253587Y-264398D01*
X2255137Y-264815D01*
X2256222Y-265856D01*
X2256532Y-267106D01*
X2256377Y-268357D01*
X2255757Y-269398D01*
X2252657Y-271481D01*
X2251262Y-272940D01*
X2250332Y-275023D01*
X2250022Y-276898D01*
X2256532D01*
G01X2262732Y-271690D02*
X2263817Y-270231D01*
X2264747Y-269398D01*
X2265987Y-268981D01*
X2267072Y-269398D01*
X2267847Y-270231D01*
X2268467Y-271481D01*
X2268622Y-272940D01*
X2268467Y-274190D01*
X2267847Y-275440D01*
X2266917Y-276481D01*
X2265832Y-276898D01*
X2264592Y-276481D01*
X2263507Y-275232D01*
X2262887Y-273356D01*
X2262732Y-271273D01*
X2263042Y-268565D01*
X2263507Y-267106D01*
X2264282Y-265648D01*
X2265367Y-264606D01*
X2266452Y-264398D01*
X2267537Y-264815D01*
X2268312Y-265856D01*
G01X2278077Y-277315D02*
X2277767Y-277106D01*
Y-276690D01*
X2278077Y-276481D01*
X2278387Y-276690D01*
Y-277106D01*
X2278077Y-277315D01*
G01X2290477Y-264398D02*
X2289237Y-264815D01*
X2288307Y-265856D01*
X2287687Y-267106D01*
X2287222Y-268773D01*
X2287067Y-270648D01*
X2287222Y-272523D01*
X2287687Y-274190D01*
X2288307Y-275440D01*
X2289237Y-276481D01*
X2290477Y-276898D01*
X2291717Y-276481D01*
X2292647Y-275440D01*
X2293267Y-274190D01*
X2293732Y-272523D01*
X2293887Y-270648D01*
X2293732Y-268773D01*
X2293267Y-267106D01*
X2292647Y-265856D01*
X2291717Y-264815D01*
X2290477Y-264398D01*
G01X2166477Y-243298D02*
Y-230798D01*
X2164617Y-233298D01*
G01Y-243298D02*
X2168337D01*
G01X2176242Y-241840D02*
X2177327Y-242881D01*
X2178567Y-243298D01*
X2179807Y-242881D01*
X2180892Y-241632D01*
X2181667Y-239756D01*
X2181977Y-237881D01*
Y-235590D01*
X2181667Y-233715D01*
X2180892Y-232048D01*
X2179962Y-231215D01*
X2178877Y-230798D01*
X2177637Y-231215D01*
X2176707Y-232048D01*
X2176087Y-233298D01*
X2175777Y-234965D01*
X2176087Y-236423D01*
X2176862Y-237881D01*
X2177792Y-238715D01*
X2178877Y-238923D01*
X2180117Y-238507D01*
X2181047Y-237465D01*
X2181977Y-235590D01*
G01X2191277Y-243298D02*
Y-230798D01*
X2189417Y-233298D01*
G01Y-243298D02*
X2193137D01*
G01X2203677Y-243715D02*
X2203367Y-243506D01*
Y-243090D01*
X2203677Y-242881D01*
X2203987Y-243090D01*
Y-243506D01*
X2203677Y-243715D01*
G01X2216077Y-230798D02*
X2214837Y-231215D01*
X2213907Y-232256D01*
X2213287Y-233506D01*
X2212822Y-235173D01*
X2212667Y-237048D01*
X2212822Y-238923D01*
X2213287Y-240590D01*
X2213907Y-241840D01*
X2214837Y-242881D01*
X2216077Y-243298D01*
X2217317Y-242881D01*
X2218247Y-241840D01*
X2218867Y-240590D01*
X2219332Y-238923D01*
X2219487Y-237048D01*
X2219332Y-235173D01*
X2218867Y-233506D01*
X2218247Y-232256D01*
X2217317Y-231215D01*
X2216077Y-230798D01*
G01X2226152Y-234965D02*
X2230802Y-243298D01*
G01Y-234965D02*
X2226152Y-243298D01*
G01X2240877D02*
Y-230798D01*
X2239017Y-233298D01*
G01Y-243298D02*
X2242737D01*
G01X2250332Y-232881D02*
X2251262Y-231632D01*
X2252347Y-231006D01*
X2253587Y-230798D01*
X2255137Y-231215D01*
X2256222Y-232256D01*
X2256532Y-233506D01*
X2256377Y-234757D01*
X2255757Y-235798D01*
X2252657Y-237881D01*
X2251262Y-239340D01*
X2250332Y-241423D01*
X2250022Y-243298D01*
X2256532D01*
G01X2262732Y-238090D02*
X2263817Y-236631D01*
X2264747Y-235798D01*
X2265987Y-235381D01*
X2267072Y-235798D01*
X2267847Y-236631D01*
X2268467Y-237881D01*
X2268622Y-239340D01*
X2268467Y-240590D01*
X2267847Y-241840D01*
X2266917Y-242881D01*
X2265832Y-243298D01*
X2264592Y-242881D01*
X2263507Y-241632D01*
X2262887Y-239756D01*
X2262732Y-237673D01*
X2263042Y-234965D01*
X2263507Y-233506D01*
X2264282Y-232048D01*
X2265367Y-231006D01*
X2266452Y-230798D01*
X2267537Y-231215D01*
X2268312Y-232256D01*
G01X2278077Y-243715D02*
X2277767Y-243506D01*
Y-243090D01*
X2278077Y-242881D01*
X2278387Y-243090D01*
Y-243506D01*
X2278077Y-243715D01*
G01X2290477Y-230798D02*
X2289237Y-231215D01*
X2288307Y-232256D01*
X2287687Y-233506D01*
X2287222Y-235173D01*
X2287067Y-237048D01*
X2287222Y-238923D01*
X2287687Y-240590D01*
X2288307Y-241840D01*
X2289237Y-242881D01*
X2290477Y-243298D01*
X2291717Y-242881D01*
X2292647Y-241840D01*
X2293267Y-240590D01*
X2293732Y-238923D01*
X2293887Y-237048D01*
X2293732Y-235173D01*
X2293267Y-233506D01*
X2292647Y-232256D01*
X2291717Y-231215D01*
X2290477Y-230798D01*
G01X2176242Y-208240D02*
X2177327Y-209281D01*
X2178567Y-209698D01*
X2179807Y-209281D01*
X2180892Y-208032D01*
X2181667Y-206156D01*
X2181977Y-204281D01*
Y-201990D01*
X2181667Y-200115D01*
X2180892Y-198448D01*
X2179962Y-197615D01*
X2178877Y-197198D01*
X2177637Y-197615D01*
X2176707Y-198448D01*
X2176087Y-199698D01*
X2175777Y-201365D01*
X2176087Y-202823D01*
X2176862Y-204281D01*
X2177792Y-205115D01*
X2178877Y-205323D01*
X2180117Y-204907D01*
X2181047Y-203865D01*
X2181977Y-201990D01*
G01X2188332Y-204490D02*
X2189417Y-203031D01*
X2190347Y-202198D01*
X2191587Y-201781D01*
X2192672Y-202198D01*
X2193447Y-203031D01*
X2194067Y-204281D01*
X2194222Y-205740D01*
X2194067Y-206990D01*
X2193447Y-208240D01*
X2192517Y-209281D01*
X2191432Y-209698D01*
X2190192Y-209281D01*
X2189107Y-208032D01*
X2188487Y-206156D01*
X2188332Y-204073D01*
X2188642Y-201365D01*
X2189107Y-199906D01*
X2189882Y-198448D01*
X2190967Y-197406D01*
X2192052Y-197198D01*
X2193137Y-197615D01*
X2193912Y-198656D01*
G01X2203677Y-210115D02*
X2203367Y-209906D01*
Y-209490D01*
X2203677Y-209281D01*
X2203987Y-209490D01*
Y-209906D01*
X2203677Y-210115D01*
G01X2216077Y-197198D02*
X2214837Y-197615D01*
X2213907Y-198656D01*
X2213287Y-199906D01*
X2212822Y-201573D01*
X2212667Y-203448D01*
X2212822Y-205323D01*
X2213287Y-206990D01*
X2213907Y-208240D01*
X2214837Y-209281D01*
X2216077Y-209698D01*
X2217317Y-209281D01*
X2218247Y-208240D01*
X2218867Y-206990D01*
X2219332Y-205323D01*
X2219487Y-203448D01*
X2219332Y-201573D01*
X2218867Y-199906D01*
X2218247Y-198656D01*
X2217317Y-197615D01*
X2216077Y-197198D01*
G01X2226152Y-201365D02*
X2230802Y-209698D01*
G01Y-201365D02*
X2226152Y-209698D01*
G01X2242737D02*
Y-197198D01*
X2237002Y-206156D01*
X2244752D01*
G01X2252967Y-209698D02*
X2253277Y-206990D01*
X2253742Y-204698D01*
X2254362Y-202615D01*
X2255137Y-200323D01*
X2256377Y-197198D01*
X2250177D01*
G01X2265677Y-210115D02*
X2265367Y-209906D01*
Y-209490D01*
X2265677Y-209281D01*
X2265987Y-209490D01*
Y-209906D01*
X2265677Y-210115D01*
G01X2278077Y-197198D02*
X2276837Y-197615D01*
X2275907Y-198656D01*
X2275287Y-199906D01*
X2274822Y-201573D01*
X2274667Y-203448D01*
X2274822Y-205323D01*
X2275287Y-206990D01*
X2275907Y-208240D01*
X2276837Y-209281D01*
X2278077Y-209698D01*
X2279317Y-209281D01*
X2280247Y-208240D01*
X2280867Y-206990D01*
X2281332Y-205323D01*
X2281487Y-203448D01*
X2281332Y-201573D01*
X2280867Y-199906D01*
X2280247Y-198656D01*
X2279317Y-197615D01*
X2278077Y-197198D01*
G01X2178877Y-176098D02*
X2179962Y-175890D01*
X2181202Y-175265D01*
X2181977Y-174223D01*
X2182287Y-172765D01*
X2181977Y-171307D01*
X2181047Y-170056D01*
X2179652Y-169431D01*
X2178102D01*
X2177172Y-169015D01*
X2176397Y-167973D01*
X2176087Y-166515D01*
X2176552Y-165056D01*
X2177637Y-164015D01*
X2178877Y-163598D01*
X2180117Y-164015D01*
X2181202Y-165056D01*
X2181667Y-166515D01*
X2181357Y-167973D01*
X2180582Y-169015D01*
X2179652Y-169431D01*
X2178102D01*
X2176707Y-170056D01*
X2175777Y-171307D01*
X2175467Y-172765D01*
X2175777Y-174223D01*
X2176552Y-175265D01*
X2177792Y-175890D01*
X2178877Y-176098D01*
G01X2187867Y-173598D02*
X2188797Y-175057D01*
X2190037Y-175890D01*
X2191432Y-176098D01*
X2192672Y-175890D01*
X2193912Y-174848D01*
X2194687Y-173598D01*
X2194842Y-172348D01*
X2194532Y-170890D01*
X2193447Y-169848D01*
X2192362Y-169431D01*
X2190967D01*
G01X2192362D02*
X2193292Y-168806D01*
X2194067Y-167765D01*
X2194377Y-166515D01*
X2194067Y-165265D01*
X2193292Y-164223D01*
X2191897Y-163598D01*
X2190502Y-163806D01*
X2189107Y-164640D01*
G01X2203677Y-176515D02*
X2203367Y-176306D01*
Y-175890D01*
X2203677Y-175681D01*
X2203987Y-175890D01*
Y-176306D01*
X2203677Y-176515D01*
G01X2216077Y-163598D02*
X2214837Y-164015D01*
X2213907Y-165056D01*
X2213287Y-166306D01*
X2212822Y-167973D01*
X2212667Y-169848D01*
X2212822Y-171723D01*
X2213287Y-173390D01*
X2213907Y-174640D01*
X2214837Y-175681D01*
X2216077Y-176098D01*
X2217317Y-175681D01*
X2218247Y-174640D01*
X2218867Y-173390D01*
X2219332Y-171723D01*
X2219487Y-169848D01*
X2219332Y-167973D01*
X2218867Y-166306D01*
X2218247Y-165056D01*
X2217317Y-164015D01*
X2216077Y-163598D01*
G01X2226152Y-167765D02*
X2230802Y-176098D01*
G01Y-167765D02*
X2226152Y-176098D01*
G01X2237467Y-173598D02*
X2238397Y-175057D01*
X2239637Y-175890D01*
X2241032Y-176098D01*
X2242272Y-175890D01*
X2243512Y-174848D01*
X2244287Y-173598D01*
X2244442Y-172348D01*
X2244132Y-170890D01*
X2243047Y-169848D01*
X2241962Y-169431D01*
X2240567D01*
G01X2241962D02*
X2242892Y-168806D01*
X2243667Y-167765D01*
X2243977Y-166515D01*
X2243667Y-165265D01*
X2242892Y-164223D01*
X2241497Y-163598D01*
X2240102Y-163806D01*
X2238707Y-164640D01*
G01X2253277Y-176098D02*
Y-163598D01*
X2251417Y-166098D01*
G01Y-176098D02*
X2255137D01*
G01X2265677Y-176515D02*
X2265367Y-176306D01*
Y-175890D01*
X2265677Y-175681D01*
X2265987Y-175890D01*
Y-176306D01*
X2265677Y-176515D01*
G01X2278077Y-163598D02*
X2276837Y-164015D01*
X2275907Y-165056D01*
X2275287Y-166306D01*
X2274822Y-167973D01*
X2274667Y-169848D01*
X2274822Y-171723D01*
X2275287Y-173390D01*
X2275907Y-174640D01*
X2276837Y-175681D01*
X2278077Y-176098D01*
X2279317Y-175681D01*
X2280247Y-174640D01*
X2280867Y-173390D01*
X2281332Y-171723D01*
X2281487Y-169848D01*
X2281332Y-167973D01*
X2280867Y-166306D01*
X2280247Y-165056D01*
X2279317Y-164015D01*
X2278077Y-163598D01*
G01X2178567Y-142498D02*
X2178877Y-139790D01*
X2179342Y-137498D01*
X2179962Y-135415D01*
X2180737Y-133123D01*
X2181977Y-129998D01*
X2175777D01*
G01X2191277Y-142498D02*
Y-129998D01*
X2189417Y-132498D01*
G01Y-142498D02*
X2193137D01*
G01X2203677Y-142915D02*
X2203367Y-142706D01*
Y-142290D01*
X2203677Y-142081D01*
X2203987Y-142290D01*
Y-142706D01*
X2203677Y-142915D01*
G01X2216077Y-129998D02*
X2214837Y-130415D01*
X2213907Y-131456D01*
X2213287Y-132706D01*
X2212822Y-134373D01*
X2212667Y-136248D01*
X2212822Y-138123D01*
X2213287Y-139790D01*
X2213907Y-141040D01*
X2214837Y-142081D01*
X2216077Y-142498D01*
X2217317Y-142081D01*
X2218247Y-141040D01*
X2218867Y-139790D01*
X2219332Y-138123D01*
X2219487Y-136248D01*
X2219332Y-134373D01*
X2218867Y-132706D01*
X2218247Y-131456D01*
X2217317Y-130415D01*
X2216077Y-129998D01*
G01X2226152Y-134165D02*
X2230802Y-142498D01*
G01Y-134165D02*
X2226152Y-142498D01*
G01X2237932Y-132081D02*
X2238862Y-130832D01*
X2239947Y-130206D01*
X2241187Y-129998D01*
X2242737Y-130415D01*
X2243822Y-131456D01*
X2244132Y-132706D01*
X2243977Y-133957D01*
X2243357Y-134998D01*
X2240257Y-137081D01*
X2238862Y-138540D01*
X2237932Y-140623D01*
X2237622Y-142498D01*
X2244132D01*
G01X2253277Y-129998D02*
X2252037Y-130415D01*
X2251107Y-131456D01*
X2250487Y-132706D01*
X2250022Y-134373D01*
X2249867Y-136248D01*
X2250022Y-138123D01*
X2250487Y-139790D01*
X2251107Y-141040D01*
X2252037Y-142081D01*
X2253277Y-142498D01*
X2254517Y-142081D01*
X2255447Y-141040D01*
X2256067Y-139790D01*
X2256532Y-138123D01*
X2256687Y-136248D01*
X2256532Y-134373D01*
X2256067Y-132706D01*
X2255447Y-131456D01*
X2254517Y-130415D01*
X2253277Y-129998D01*
G01X2265677Y-142915D02*
X2265367Y-142706D01*
Y-142290D01*
X2265677Y-142081D01*
X2265987Y-142290D01*
Y-142706D01*
X2265677Y-142915D01*
G01X2278077Y-129998D02*
X2276837Y-130415D01*
X2275907Y-131456D01*
X2275287Y-132706D01*
X2274822Y-134373D01*
X2274667Y-136248D01*
X2274822Y-138123D01*
X2275287Y-139790D01*
X2275907Y-141040D01*
X2276837Y-142081D01*
X2278077Y-142498D01*
X2279317Y-142081D01*
X2280247Y-141040D01*
X2280867Y-139790D01*
X2281332Y-138123D01*
X2281487Y-136248D01*
X2281332Y-134373D01*
X2280867Y-132706D01*
X2280247Y-131456D01*
X2279317Y-130415D01*
X2278077Y-129998D01*
G01X2175932Y-103690D02*
X2177017Y-102231D01*
X2177947Y-101398D01*
X2179187Y-100981D01*
X2180272Y-101398D01*
X2181047Y-102231D01*
X2181667Y-103481D01*
X2181822Y-104940D01*
X2181667Y-106190D01*
X2181047Y-107440D01*
X2180117Y-108481D01*
X2179032Y-108898D01*
X2177792Y-108481D01*
X2176707Y-107232D01*
X2176087Y-105356D01*
X2175932Y-103273D01*
X2176242Y-100565D01*
X2176707Y-99106D01*
X2177482Y-97648D01*
X2178567Y-96606D01*
X2179652Y-96398D01*
X2180737Y-96815D01*
X2181512Y-97856D01*
G01X2191277Y-96398D02*
X2190037Y-96815D01*
X2189107Y-97856D01*
X2188487Y-99106D01*
X2188022Y-100773D01*
X2187867Y-102648D01*
X2188022Y-104523D01*
X2188487Y-106190D01*
X2189107Y-107440D01*
X2190037Y-108481D01*
X2191277Y-108898D01*
X2192517Y-108481D01*
X2193447Y-107440D01*
X2194067Y-106190D01*
X2194532Y-104523D01*
X2194687Y-102648D01*
X2194532Y-100773D01*
X2194067Y-99106D01*
X2193447Y-97856D01*
X2192517Y-96815D01*
X2191277Y-96398D01*
G01X2203677Y-109315D02*
X2203367Y-109106D01*
Y-108690D01*
X2203677Y-108481D01*
X2203987Y-108690D01*
Y-109106D01*
X2203677Y-109315D01*
G01X2216077Y-96398D02*
X2214837Y-96815D01*
X2213907Y-97856D01*
X2213287Y-99106D01*
X2212822Y-100773D01*
X2212667Y-102648D01*
X2212822Y-104523D01*
X2213287Y-106190D01*
X2213907Y-107440D01*
X2214837Y-108481D01*
X2216077Y-108898D01*
X2217317Y-108481D01*
X2218247Y-107440D01*
X2218867Y-106190D01*
X2219332Y-104523D01*
X2219487Y-102648D01*
X2219332Y-100773D01*
X2218867Y-99106D01*
X2218247Y-97856D01*
X2217317Y-96815D01*
X2216077Y-96398D01*
G01X2226152Y-100565D02*
X2230802Y-108898D01*
G01Y-100565D02*
X2226152Y-108898D01*
G01X2237932Y-98481D02*
X2238862Y-97232D01*
X2239947Y-96606D01*
X2241187Y-96398D01*
X2242737Y-96815D01*
X2243822Y-97856D01*
X2244132Y-99106D01*
X2243977Y-100357D01*
X2243357Y-101398D01*
X2240257Y-103481D01*
X2238862Y-104940D01*
X2237932Y-107023D01*
X2237622Y-108898D01*
X2244132D01*
G01X2253277Y-96398D02*
X2252037Y-96815D01*
X2251107Y-97856D01*
X2250487Y-99106D01*
X2250022Y-100773D01*
X2249867Y-102648D01*
X2250022Y-104523D01*
X2250487Y-106190D01*
X2251107Y-107440D01*
X2252037Y-108481D01*
X2253277Y-108898D01*
X2254517Y-108481D01*
X2255447Y-107440D01*
X2256067Y-106190D01*
X2256532Y-104523D01*
X2256687Y-102648D01*
X2256532Y-100773D01*
X2256067Y-99106D01*
X2255447Y-97856D01*
X2254517Y-96815D01*
X2253277Y-96398D01*
G01X2265677Y-109315D02*
X2265367Y-109106D01*
Y-108690D01*
X2265677Y-108481D01*
X2265987Y-108690D01*
Y-109106D01*
X2265677Y-109315D01*
G01X2278077Y-96398D02*
X2276837Y-96815D01*
X2275907Y-97856D01*
X2275287Y-99106D01*
X2274822Y-100773D01*
X2274667Y-102648D01*
X2274822Y-104523D01*
X2275287Y-106190D01*
X2275907Y-107440D01*
X2276837Y-108481D01*
X2278077Y-108898D01*
X2279317Y-108481D01*
X2280247Y-107440D01*
X2280867Y-106190D01*
X2281332Y-104523D01*
X2281487Y-102648D01*
X2281332Y-100773D01*
X2280867Y-99106D01*
X2280247Y-97856D01*
X2279317Y-96815D01*
X2278077Y-96398D01*
G01X2175467Y-73423D02*
X2176397Y-74465D01*
X2177482Y-75090D01*
X2178877Y-75298D01*
X2180272Y-74881D01*
X2181357Y-74048D01*
X2182132Y-72590D01*
X2182287Y-70923D01*
X2181977Y-69256D01*
X2181202Y-68215D01*
X2180117Y-67381D01*
X2179032Y-67173D01*
X2177947Y-67381D01*
X2176552Y-68215D01*
X2177017Y-62798D01*
X2181202D01*
G01X2187867Y-73423D02*
X2188797Y-74465D01*
X2189882Y-75090D01*
X2191277Y-75298D01*
X2192672Y-74881D01*
X2193757Y-74048D01*
X2194532Y-72590D01*
X2194687Y-70923D01*
X2194377Y-69256D01*
X2193602Y-68215D01*
X2192517Y-67381D01*
X2191432Y-67173D01*
X2190347Y-67381D01*
X2188952Y-68215D01*
X2189417Y-62798D01*
X2193602D01*
G01X2203677Y-75715D02*
X2203367Y-75506D01*
Y-75090D01*
X2203677Y-74881D01*
X2203987Y-75090D01*
Y-75506D01*
X2203677Y-75715D01*
G01X2216077Y-62798D02*
X2214837Y-63215D01*
X2213907Y-64256D01*
X2213287Y-65506D01*
X2212822Y-67173D01*
X2212667Y-69048D01*
X2212822Y-70923D01*
X2213287Y-72590D01*
X2213907Y-73840D01*
X2214837Y-74881D01*
X2216077Y-75298D01*
X2217317Y-74881D01*
X2218247Y-73840D01*
X2218867Y-72590D01*
X2219332Y-70923D01*
X2219487Y-69048D01*
X2219332Y-67173D01*
X2218867Y-65506D01*
X2218247Y-64256D01*
X2217317Y-63215D01*
X2216077Y-62798D01*
G01X2226152Y-66965D02*
X2230802Y-75298D01*
G01Y-66965D02*
X2226152Y-75298D01*
G01X2237467Y-72798D02*
X2238397Y-74257D01*
X2239637Y-75090D01*
X2241032Y-75298D01*
X2242272Y-75090D01*
X2243512Y-74048D01*
X2244287Y-72798D01*
X2244442Y-71548D01*
X2244132Y-70090D01*
X2243047Y-69048D01*
X2241962Y-68631D01*
X2240567D01*
G01X2241962D02*
X2242892Y-68006D01*
X2243667Y-66965D01*
X2243977Y-65715D01*
X2243667Y-64465D01*
X2242892Y-63423D01*
X2241497Y-62798D01*
X2240102Y-63006D01*
X2238707Y-63840D01*
G01X2253277Y-75298D02*
Y-62798D01*
X2251417Y-65298D01*
G01Y-75298D02*
X2255137D01*
G01X2265677Y-75715D02*
X2265367Y-75506D01*
Y-75090D01*
X2265677Y-74881D01*
X2265987Y-75090D01*
Y-75506D01*
X2265677Y-75715D01*
G01X2278077Y-62798D02*
X2276837Y-63215D01*
X2275907Y-64256D01*
X2275287Y-65506D01*
X2274822Y-67173D01*
X2274667Y-69048D01*
X2274822Y-70923D01*
X2275287Y-72590D01*
X2275907Y-73840D01*
X2276837Y-74881D01*
X2278077Y-75298D01*
X2279317Y-74881D01*
X2280247Y-73840D01*
X2280867Y-72590D01*
X2281332Y-70923D01*
X2281487Y-69048D01*
X2281332Y-67173D01*
X2280867Y-65506D01*
X2280247Y-64256D01*
X2279317Y-63215D01*
X2278077Y-62798D01*
G01X2175467Y-39198D02*
X2176397Y-40657D01*
X2177637Y-41490D01*
X2179032Y-41698D01*
X2180272Y-41490D01*
X2181512Y-40448D01*
X2182287Y-39198D01*
X2182442Y-37948D01*
X2182132Y-36490D01*
X2181047Y-35448D01*
X2179962Y-35031D01*
X2178567D01*
G01X2179962D02*
X2180892Y-34406D01*
X2181667Y-33365D01*
X2181977Y-32115D01*
X2181667Y-30865D01*
X2180892Y-29823D01*
X2179497Y-29198D01*
X2178102Y-29406D01*
X2176707Y-30240D01*
G01X2188332Y-31281D02*
X2189262Y-30032D01*
X2190347Y-29406D01*
X2191587Y-29198D01*
X2193137Y-29615D01*
X2194222Y-30656D01*
X2194532Y-31906D01*
X2194377Y-33157D01*
X2193757Y-34198D01*
X2190657Y-36281D01*
X2189262Y-37740D01*
X2188332Y-39823D01*
X2188022Y-41698D01*
X2194532D01*
G01X2203677Y-42115D02*
X2203367Y-41906D01*
Y-41490D01*
X2203677Y-41281D01*
X2203987Y-41490D01*
Y-41906D01*
X2203677Y-42115D01*
G01X2216077Y-29198D02*
X2214837Y-29615D01*
X2213907Y-30656D01*
X2213287Y-31906D01*
X2212822Y-33573D01*
X2212667Y-35448D01*
X2212822Y-37323D01*
X2213287Y-38990D01*
X2213907Y-40240D01*
X2214837Y-41281D01*
X2216077Y-41698D01*
X2217317Y-41281D01*
X2218247Y-40240D01*
X2218867Y-38990D01*
X2219332Y-37323D01*
X2219487Y-35448D01*
X2219332Y-33573D01*
X2218867Y-31906D01*
X2218247Y-30656D01*
X2217317Y-29615D01*
X2216077Y-29198D01*
G01X2226152Y-33365D02*
X2230802Y-41698D01*
G01Y-33365D02*
X2226152Y-41698D01*
G01X2237932Y-31281D02*
X2238862Y-30032D01*
X2239947Y-29406D01*
X2241187Y-29198D01*
X2242737Y-29615D01*
X2243822Y-30656D01*
X2244132Y-31906D01*
X2243977Y-33157D01*
X2243357Y-34198D01*
X2240257Y-36281D01*
X2238862Y-37740D01*
X2237932Y-39823D01*
X2237622Y-41698D01*
X2244132D01*
G01X2253277Y-29198D02*
X2252037Y-29615D01*
X2251107Y-30656D01*
X2250487Y-31906D01*
X2250022Y-33573D01*
X2249867Y-35448D01*
X2250022Y-37323D01*
X2250487Y-38990D01*
X2251107Y-40240D01*
X2252037Y-41281D01*
X2253277Y-41698D01*
X2254517Y-41281D01*
X2255447Y-40240D01*
X2256067Y-38990D01*
X2256532Y-37323D01*
X2256687Y-35448D01*
X2256532Y-33573D01*
X2256067Y-31906D01*
X2255447Y-30656D01*
X2254517Y-29615D01*
X2253277Y-29198D01*
G01X2265677Y-42115D02*
X2265367Y-41906D01*
Y-41490D01*
X2265677Y-41281D01*
X2265987Y-41490D01*
Y-41906D01*
X2265677Y-42115D01*
G01X2278077Y-29198D02*
X2276837Y-29615D01*
X2275907Y-30656D01*
X2275287Y-31906D01*
X2274822Y-33573D01*
X2274667Y-35448D01*
X2274822Y-37323D01*
X2275287Y-38990D01*
X2275907Y-40240D01*
X2276837Y-41281D01*
X2278077Y-41698D01*
X2279317Y-41281D01*
X2280247Y-40240D01*
X2280867Y-38990D01*
X2281332Y-37323D01*
X2281487Y-35448D01*
X2281332Y-33573D01*
X2280867Y-31906D01*
X2280247Y-30656D01*
X2279317Y-29615D01*
X2278077Y-29198D01*
G01X2203677Y-8098D02*
Y4402D01*
X2201817Y1902D01*
G01Y-8098D02*
X2205537D01*
G01X2212667Y-6223D02*
X2213597Y-7265D01*
X2214682Y-7890D01*
X2216077Y-8098D01*
X2217472Y-7681D01*
X2218557Y-6848D01*
X2219332Y-5390D01*
X2219487Y-3723D01*
X2219177Y-2056D01*
X2218402Y-1015D01*
X2217317Y-181D01*
X2216232Y27D01*
X2215147Y-181D01*
X2213752Y-1015D01*
X2214217Y4402D01*
X2218402D01*
G01X2228477D02*
X2227237Y3985D01*
X2226307Y2944D01*
X2225687Y1694D01*
X2225222Y27D01*
X2225067Y-1848D01*
X2225222Y-3723D01*
X2225687Y-5390D01*
X2226307Y-6640D01*
X2227237Y-7681D01*
X2228477Y-8098D01*
X2229717Y-7681D01*
X2230647Y-6640D01*
X2231267Y-5390D01*
X2231732Y-3723D01*
X2231887Y-1848D01*
X2231732Y27D01*
X2231267Y1694D01*
X2230647Y2944D01*
X2229717Y3985D01*
X2228477Y4402D01*
G01X2240877Y-8515D02*
X2240567Y-8306D01*
Y-7890D01*
X2240877Y-7681D01*
X2241187Y-7890D01*
Y-8306D01*
X2240877Y-8515D01*
G01X2253277Y4402D02*
X2252037Y3985D01*
X2251107Y2944D01*
X2250487Y1694D01*
X2250022Y27D01*
X2249867Y-1848D01*
X2250022Y-3723D01*
X2250487Y-5390D01*
X2251107Y-6640D01*
X2252037Y-7681D01*
X2253277Y-8098D01*
X2254517Y-7681D01*
X2255447Y-6640D01*
X2256067Y-5390D01*
X2256532Y-3723D01*
X2256687Y-1848D01*
X2256532Y27D01*
X2256067Y1694D01*
X2255447Y2944D01*
X2254517Y3985D01*
X2253277Y4402D01*
G01X2203677Y25502D02*
Y38002D01*
X2201817Y35502D01*
G01Y25502D02*
X2205537D01*
G01X2213132Y35919D02*
X2214062Y37168D01*
X2215147Y37794D01*
X2216387Y38002D01*
X2217937Y37585D01*
X2219022Y36544D01*
X2219332Y35294D01*
X2219177Y34043D01*
X2218557Y33002D01*
X2215457Y30919D01*
X2214062Y29460D01*
X2213132Y27377D01*
X2212822Y25502D01*
X2219332D01*
G01X2225067Y27377D02*
X2225997Y26335D01*
X2227082Y25710D01*
X2228477Y25502D01*
X2229872Y25919D01*
X2230957Y26752D01*
X2231732Y28210D01*
X2231887Y29877D01*
X2231577Y31544D01*
X2230802Y32585D01*
X2229717Y33419D01*
X2228632Y33627D01*
X2227547Y33419D01*
X2226152Y32585D01*
X2226617Y38002D01*
X2230802D01*
G01X2240877Y25085D02*
X2240567Y25294D01*
Y25710D01*
X2240877Y25919D01*
X2241187Y25710D01*
Y25294D01*
X2240877Y25085D01*
G01X2253277Y38002D02*
X2252037Y37585D01*
X2251107Y36544D01*
X2250487Y35294D01*
X2250022Y33627D01*
X2249867Y31752D01*
X2250022Y29877D01*
X2250487Y28210D01*
X2251107Y26960D01*
X2252037Y25919D01*
X2253277Y25502D01*
X2254517Y25919D01*
X2255447Y26960D01*
X2256067Y28210D01*
X2256532Y29877D01*
X2256687Y31752D01*
X2256532Y33627D01*
X2256067Y35294D01*
X2255447Y36544D01*
X2254517Y37585D01*
X2253277Y38002D01*
G01X2209877Y59102D02*
X2210962Y59310D01*
X2212202Y59935D01*
X2212977Y60977D01*
X2213287Y62435D01*
X2212977Y63893D01*
X2212047Y65144D01*
X2210652Y65769D01*
X2209102D01*
X2208172Y66185D01*
X2207397Y67227D01*
X2207087Y68685D01*
X2207552Y70144D01*
X2208637Y71185D01*
X2209877Y71602D01*
X2211117Y71185D01*
X2212202Y70144D01*
X2212667Y68685D01*
X2212357Y67227D01*
X2211582Y66185D01*
X2210652Y65769D01*
X2209102D01*
X2207707Y65144D01*
X2206777Y63893D01*
X2206467Y62435D01*
X2206777Y60977D01*
X2207552Y59935D01*
X2208792Y59310D01*
X2209877Y59102D01*
G01X2221967D02*
X2222277Y61810D01*
X2222742Y64102D01*
X2223362Y66185D01*
X2224137Y68477D01*
X2225377Y71602D01*
X2219177D01*
G01X2234677Y58685D02*
X2234367Y58894D01*
Y59310D01*
X2234677Y59519D01*
X2234987Y59310D01*
Y58894D01*
X2234677Y58685D01*
G01X2247077Y71602D02*
X2245837Y71185D01*
X2244907Y70144D01*
X2244287Y68894D01*
X2243822Y67227D01*
X2243667Y65352D01*
X2243822Y63477D01*
X2244287Y61810D01*
X2244907Y60560D01*
X2245837Y59519D01*
X2247077Y59102D01*
X2248317Y59519D01*
X2249247Y60560D01*
X2249867Y61810D01*
X2250332Y63477D01*
X2250487Y65352D01*
X2250332Y67227D01*
X2249867Y68894D01*
X2249247Y70144D01*
X2248317Y71185D01*
X2247077Y71602D01*
G01X2209877Y92702D02*
X2210962Y92910D01*
X2212202Y93535D01*
X2212977Y94577D01*
X2213287Y96035D01*
X2212977Y97493D01*
X2212047Y98744D01*
X2210652Y99369D01*
X2209102D01*
X2208172Y99785D01*
X2207397Y100827D01*
X2207087Y102285D01*
X2207552Y103744D01*
X2208637Y104785D01*
X2209877Y105202D01*
X2211117Y104785D01*
X2212202Y103744D01*
X2212667Y102285D01*
X2212357Y100827D01*
X2211582Y99785D01*
X2210652Y99369D01*
X2209102D01*
X2207707Y98744D01*
X2206777Y97493D01*
X2206467Y96035D01*
X2206777Y94577D01*
X2207552Y93535D01*
X2208792Y92910D01*
X2209877Y92702D01*
G01X2219332Y97910D02*
X2220417Y99369D01*
X2221347Y100202D01*
X2222587Y100619D01*
X2223672Y100202D01*
X2224447Y99369D01*
X2225067Y98119D01*
X2225222Y96660D01*
X2225067Y95410D01*
X2224447Y94160D01*
X2223517Y93119D01*
X2222432Y92702D01*
X2221192Y93119D01*
X2220107Y94368D01*
X2219487Y96244D01*
X2219332Y98327D01*
X2219642Y101035D01*
X2220107Y102494D01*
X2220882Y103952D01*
X2221967Y104994D01*
X2223052Y105202D01*
X2224137Y104785D01*
X2224912Y103744D01*
G01X2234677Y92285D02*
X2234367Y92494D01*
Y92910D01*
X2234677Y93119D01*
X2234987Y92910D01*
Y92494D01*
X2234677Y92285D01*
G01X2247077Y105202D02*
X2245837Y104785D01*
X2244907Y103744D01*
X2244287Y102494D01*
X2243822Y100827D01*
X2243667Y98952D01*
X2243822Y97077D01*
X2244287Y95410D01*
X2244907Y94160D01*
X2245837Y93119D01*
X2247077Y92702D01*
X2248317Y93119D01*
X2249247Y94160D01*
X2249867Y95410D01*
X2250332Y97077D01*
X2250487Y98952D01*
X2250332Y100827D01*
X2249867Y102494D01*
X2249247Y103744D01*
X2248317Y104785D01*
X2247077Y105202D01*
G01X2209877Y126302D02*
X2210962Y126510D01*
X2212202Y127135D01*
X2212977Y128177D01*
X2213287Y129635D01*
X2212977Y131093D01*
X2212047Y132344D01*
X2210652Y132969D01*
X2209102D01*
X2208172Y133385D01*
X2207397Y134427D01*
X2207087Y135885D01*
X2207552Y137344D01*
X2208637Y138385D01*
X2209877Y138802D01*
X2211117Y138385D01*
X2212202Y137344D01*
X2212667Y135885D01*
X2212357Y134427D01*
X2211582Y133385D01*
X2210652Y132969D01*
X2209102D01*
X2207707Y132344D01*
X2206777Y131093D01*
X2206467Y129635D01*
X2206777Y128177D01*
X2207552Y127135D01*
X2208792Y126510D01*
X2209877Y126302D01*
G01X2224137D02*
Y138802D01*
X2218402Y129844D01*
X2226152D01*
G01X2234677Y125885D02*
X2234367Y126094D01*
Y126510D01*
X2234677Y126719D01*
X2234987Y126510D01*
Y126094D01*
X2234677Y125885D01*
G01X2247077Y138802D02*
X2245837Y138385D01*
X2244907Y137344D01*
X2244287Y136094D01*
X2243822Y134427D01*
X2243667Y132552D01*
X2243822Y130677D01*
X2244287Y129010D01*
X2244907Y127760D01*
X2245837Y126719D01*
X2247077Y126302D01*
X2248317Y126719D01*
X2249247Y127760D01*
X2249867Y129010D01*
X2250332Y130677D01*
X2250487Y132552D01*
X2250332Y134427D01*
X2249867Y136094D01*
X2249247Y137344D01*
X2248317Y138385D01*
X2247077Y138802D01*
G01X2206932Y165110D02*
X2208017Y166569D01*
X2208947Y167402D01*
X2210187Y167819D01*
X2211272Y167402D01*
X2212047Y166569D01*
X2212667Y165319D01*
X2212822Y163860D01*
X2212667Y162610D01*
X2212047Y161360D01*
X2211117Y160319D01*
X2210032Y159902D01*
X2208792Y160319D01*
X2207707Y161568D01*
X2207087Y163444D01*
X2206932Y165527D01*
X2207242Y168235D01*
X2207707Y169694D01*
X2208482Y171152D01*
X2209567Y172194D01*
X2210652Y172402D01*
X2211737Y171985D01*
X2212512Y170944D01*
G01X2218867Y161777D02*
X2219797Y160735D01*
X2220882Y160110D01*
X2222277Y159902D01*
X2223672Y160319D01*
X2224757Y161152D01*
X2225532Y162610D01*
X2225687Y164277D01*
X2225377Y165944D01*
X2224602Y166985D01*
X2223517Y167819D01*
X2222432Y168027D01*
X2221347Y167819D01*
X2219952Y166985D01*
X2220417Y172402D01*
X2224602D01*
G01X2234677Y159485D02*
X2234367Y159694D01*
Y160110D01*
X2234677Y160319D01*
X2234987Y160110D01*
Y159694D01*
X2234677Y159485D01*
G01X2247077Y172402D02*
X2245837Y171985D01*
X2244907Y170944D01*
X2244287Y169694D01*
X2243822Y168027D01*
X2243667Y166152D01*
X2243822Y164277D01*
X2244287Y162610D01*
X2244907Y161360D01*
X2245837Y160319D01*
X2247077Y159902D01*
X2248317Y160319D01*
X2249247Y161360D01*
X2249867Y162610D01*
X2250332Y164277D01*
X2250487Y166152D01*
X2250332Y168027D01*
X2249867Y169694D01*
X2249247Y170944D01*
X2248317Y171985D01*
X2247077Y172402D01*
G01X2206932Y198710D02*
X2208017Y200169D01*
X2208947Y201002D01*
X2210187Y201419D01*
X2211272Y201002D01*
X2212047Y200169D01*
X2212667Y198919D01*
X2212822Y197460D01*
X2212667Y196210D01*
X2212047Y194960D01*
X2211117Y193919D01*
X2210032Y193502D01*
X2208792Y193919D01*
X2207707Y195168D01*
X2207087Y197044D01*
X2206932Y199127D01*
X2207242Y201835D01*
X2207707Y203294D01*
X2208482Y204752D01*
X2209567Y205794D01*
X2210652Y206002D01*
X2211737Y205585D01*
X2212512Y204544D01*
G01X2218867Y196002D02*
X2219797Y194543D01*
X2221037Y193710D01*
X2222432Y193502D01*
X2223672Y193710D01*
X2224912Y194752D01*
X2225687Y196002D01*
X2225842Y197252D01*
X2225532Y198710D01*
X2224447Y199752D01*
X2223362Y200169D01*
X2221967D01*
G01X2223362D02*
X2224292Y200794D01*
X2225067Y201835D01*
X2225377Y203085D01*
X2225067Y204335D01*
X2224292Y205377D01*
X2222897Y206002D01*
X2221502Y205794D01*
X2220107Y204960D01*
G01X2234677Y193085D02*
X2234367Y193294D01*
Y193710D01*
X2234677Y193919D01*
X2234987Y193710D01*
Y193294D01*
X2234677Y193085D01*
G01X2247077Y206002D02*
X2245837Y205585D01*
X2244907Y204544D01*
X2244287Y203294D01*
X2243822Y201627D01*
X2243667Y199752D01*
X2243822Y197877D01*
X2244287Y196210D01*
X2244907Y194960D01*
X2245837Y193919D01*
X2247077Y193502D01*
X2248317Y193919D01*
X2249247Y194960D01*
X2249867Y196210D01*
X2250332Y197877D01*
X2250487Y199752D01*
X2250332Y201627D01*
X2249867Y203294D01*
X2249247Y204544D01*
X2248317Y205585D01*
X2247077Y206002D01*
G01X2206467Y228977D02*
X2207397Y227935D01*
X2208482Y227310D01*
X2209877Y227102D01*
X2211272Y227519D01*
X2212357Y228352D01*
X2213132Y229810D01*
X2213287Y231477D01*
X2212977Y233144D01*
X2212202Y234185D01*
X2211117Y235019D01*
X2210032Y235227D01*
X2208947Y235019D01*
X2207552Y234185D01*
X2208017Y239602D01*
X2212202D01*
G01X2219642Y228560D02*
X2220727Y227519D01*
X2221967Y227102D01*
X2223207Y227519D01*
X2224292Y228768D01*
X2225067Y230644D01*
X2225377Y232519D01*
Y234810D01*
X2225067Y236685D01*
X2224292Y238352D01*
X2223362Y239185D01*
X2222277Y239602D01*
X2221037Y239185D01*
X2220107Y238352D01*
X2219487Y237102D01*
X2219177Y235435D01*
X2219487Y233977D01*
X2220262Y232519D01*
X2221192Y231685D01*
X2222277Y231477D01*
X2223517Y231893D01*
X2224447Y232935D01*
X2225377Y234810D01*
G01X2234677Y226685D02*
X2234367Y226894D01*
Y227310D01*
X2234677Y227519D01*
X2234987Y227310D01*
Y226894D01*
X2234677Y226685D01*
G01X2247077Y239602D02*
X2245837Y239185D01*
X2244907Y238144D01*
X2244287Y236894D01*
X2243822Y235227D01*
X2243667Y233352D01*
X2243822Y231477D01*
X2244287Y229810D01*
X2244907Y228560D01*
X2245837Y227519D01*
X2247077Y227102D01*
X2248317Y227519D01*
X2249247Y228560D01*
X2249867Y229810D01*
X2250332Y231477D01*
X2250487Y233352D01*
X2250332Y235227D01*
X2249867Y236894D01*
X2249247Y238144D01*
X2248317Y239185D01*
X2247077Y239602D01*
G01X2206467Y262577D02*
X2207397Y261535D01*
X2208482Y260910D01*
X2209877Y260702D01*
X2211272Y261119D01*
X2212357Y261952D01*
X2213132Y263410D01*
X2213287Y265077D01*
X2212977Y266744D01*
X2212202Y267785D01*
X2211117Y268619D01*
X2210032Y268827D01*
X2208947Y268619D01*
X2207552Y267785D01*
X2208017Y273202D01*
X2212202D01*
G01X2224137Y260702D02*
Y273202D01*
X2218402Y264244D01*
X2226152D01*
G01X2234677Y260285D02*
X2234367Y260494D01*
Y260910D01*
X2234677Y261119D01*
X2234987Y260910D01*
Y260494D01*
X2234677Y260285D01*
G01X2247077Y273202D02*
X2245837Y272785D01*
X2244907Y271744D01*
X2244287Y270494D01*
X2243822Y268827D01*
X2243667Y266952D01*
X2243822Y265077D01*
X2244287Y263410D01*
X2244907Y262160D01*
X2245837Y261119D01*
X2247077Y260702D01*
X2248317Y261119D01*
X2249247Y262160D01*
X2249867Y263410D01*
X2250332Y265077D01*
X2250487Y266952D01*
X2250332Y268827D01*
X2249867Y270494D01*
X2249247Y271744D01*
X2248317Y272785D01*
X2247077Y273202D01*
G01X2206467Y296177D02*
X2207397Y295135D01*
X2208482Y294510D01*
X2209877Y294302D01*
X2211272Y294719D01*
X2212357Y295552D01*
X2213132Y297010D01*
X2213287Y298677D01*
X2212977Y300344D01*
X2212202Y301385D01*
X2211117Y302219D01*
X2210032Y302427D01*
X2208947Y302219D01*
X2207552Y301385D01*
X2208017Y306802D01*
X2212202D01*
G01X2222277D02*
X2221037Y306385D01*
X2220107Y305344D01*
X2219487Y304094D01*
X2219022Y302427D01*
X2218867Y300552D01*
X2219022Y298677D01*
X2219487Y297010D01*
X2220107Y295760D01*
X2221037Y294719D01*
X2222277Y294302D01*
X2223517Y294719D01*
X2224447Y295760D01*
X2225067Y297010D01*
X2225532Y298677D01*
X2225687Y300552D01*
X2225532Y302427D01*
X2225067Y304094D01*
X2224447Y305344D01*
X2223517Y306385D01*
X2222277Y306802D01*
G01X2234677Y293885D02*
X2234367Y294094D01*
Y294510D01*
X2234677Y294719D01*
X2234987Y294510D01*
Y294094D01*
X2234677Y293885D01*
G01X2247077Y306802D02*
X2245837Y306385D01*
X2244907Y305344D01*
X2244287Y304094D01*
X2243822Y302427D01*
X2243667Y300552D01*
X2243822Y298677D01*
X2244287Y297010D01*
X2244907Y295760D01*
X2245837Y294719D01*
X2247077Y294302D01*
X2248317Y294719D01*
X2249247Y295760D01*
X2249867Y297010D01*
X2250332Y298677D01*
X2250487Y300552D01*
X2250332Y302427D01*
X2249867Y304094D01*
X2249247Y305344D01*
X2248317Y306385D01*
X2247077Y306802D01*
G01X2206467Y329777D02*
X2207397Y328735D01*
X2208482Y328110D01*
X2209877Y327902D01*
X2211272Y328319D01*
X2212357Y329152D01*
X2213132Y330610D01*
X2213287Y332277D01*
X2212977Y333944D01*
X2212202Y334985D01*
X2211117Y335819D01*
X2210032Y336027D01*
X2208947Y335819D01*
X2207552Y334985D01*
X2208017Y340402D01*
X2212202D01*
G01X2222277D02*
X2221037Y339985D01*
X2220107Y338944D01*
X2219487Y337694D01*
X2219022Y336027D01*
X2218867Y334152D01*
X2219022Y332277D01*
X2219487Y330610D01*
X2220107Y329360D01*
X2221037Y328319D01*
X2222277Y327902D01*
X2223517Y328319D01*
X2224447Y329360D01*
X2225067Y330610D01*
X2225532Y332277D01*
X2225687Y334152D01*
X2225532Y336027D01*
X2225067Y337694D01*
X2224447Y338944D01*
X2223517Y339985D01*
X2222277Y340402D01*
G01X2234677Y327485D02*
X2234367Y327694D01*
Y328110D01*
X2234677Y328319D01*
X2234987Y328110D01*
Y327694D01*
X2234677Y327485D01*
G01X2247077Y340402D02*
X2245837Y339985D01*
X2244907Y338944D01*
X2244287Y337694D01*
X2243822Y336027D01*
X2243667Y334152D01*
X2243822Y332277D01*
X2244287Y330610D01*
X2244907Y329360D01*
X2245837Y328319D01*
X2247077Y327902D01*
X2248317Y328319D01*
X2249247Y329360D01*
X2249867Y330610D01*
X2250332Y332277D01*
X2250487Y334152D01*
X2250332Y336027D01*
X2249867Y337694D01*
X2249247Y338944D01*
X2248317Y339985D01*
X2247077Y340402D01*
G01X2211737Y361502D02*
Y374002D01*
X2206002Y365044D01*
X2213752D01*
G01X2221967Y361502D02*
X2222277Y364210D01*
X2222742Y366502D01*
X2223362Y368585D01*
X2224137Y370877D01*
X2225377Y374002D01*
X2219177D01*
G01X2234677Y361085D02*
X2234367Y361294D01*
Y361710D01*
X2234677Y361919D01*
X2234987Y361710D01*
Y361294D01*
X2234677Y361085D01*
G01X2247077Y374002D02*
X2245837Y373585D01*
X2244907Y372544D01*
X2244287Y371294D01*
X2243822Y369627D01*
X2243667Y367752D01*
X2243822Y365877D01*
X2244287Y364210D01*
X2244907Y362960D01*
X2245837Y361919D01*
X2247077Y361502D01*
X2248317Y361919D01*
X2249247Y362960D01*
X2249867Y364210D01*
X2250332Y365877D01*
X2250487Y367752D01*
X2250332Y369627D01*
X2249867Y371294D01*
X2249247Y372544D01*
X2248317Y373585D01*
X2247077Y374002D01*
G01X2211737Y395102D02*
Y407602D01*
X2206002Y398644D01*
X2213752D01*
G01X2219332Y400310D02*
X2220417Y401769D01*
X2221347Y402602D01*
X2222587Y403019D01*
X2223672Y402602D01*
X2224447Y401769D01*
X2225067Y400519D01*
X2225222Y399060D01*
X2225067Y397810D01*
X2224447Y396560D01*
X2223517Y395519D01*
X2222432Y395102D01*
X2221192Y395519D01*
X2220107Y396768D01*
X2219487Y398644D01*
X2219332Y400727D01*
X2219642Y403435D01*
X2220107Y404894D01*
X2220882Y406352D01*
X2221967Y407394D01*
X2223052Y407602D01*
X2224137Y407185D01*
X2224912Y406144D01*
G01X2234677Y394685D02*
X2234367Y394894D01*
Y395310D01*
X2234677Y395519D01*
X2234987Y395310D01*
Y394894D01*
X2234677Y394685D01*
G01X2247077Y407602D02*
X2245837Y407185D01*
X2244907Y406144D01*
X2244287Y404894D01*
X2243822Y403227D01*
X2243667Y401352D01*
X2243822Y399477D01*
X2244287Y397810D01*
X2244907Y396560D01*
X2245837Y395519D01*
X2247077Y395102D01*
X2248317Y395519D01*
X2249247Y396560D01*
X2249867Y397810D01*
X2250332Y399477D01*
X2250487Y401352D01*
X2250332Y403227D01*
X2249867Y404894D01*
X2249247Y406144D01*
X2248317Y407185D01*
X2247077Y407602D01*
G01X2211737Y428702D02*
Y441202D01*
X2206002Y432244D01*
X2213752D01*
G01X2224137Y428702D02*
Y441202D01*
X2218402Y432244D01*
X2226152D01*
G01X2234677Y428285D02*
X2234367Y428494D01*
Y428910D01*
X2234677Y429119D01*
X2234987Y428910D01*
Y428494D01*
X2234677Y428285D01*
G01X2247077Y441202D02*
X2245837Y440785D01*
X2244907Y439744D01*
X2244287Y438494D01*
X2243822Y436827D01*
X2243667Y434952D01*
X2243822Y433077D01*
X2244287Y431410D01*
X2244907Y430160D01*
X2245837Y429119D01*
X2247077Y428702D01*
X2248317Y429119D01*
X2249247Y430160D01*
X2249867Y431410D01*
X2250332Y433077D01*
X2250487Y434952D01*
X2250332Y436827D01*
X2249867Y438494D01*
X2249247Y439744D01*
X2248317Y440785D01*
X2247077Y441202D01*
G01X2211737Y462302D02*
Y474802D01*
X2206002Y465844D01*
X2213752D01*
G01X2222277Y462302D02*
Y474802D01*
X2220417Y472302D01*
G01Y462302D02*
X2224137D01*
G01X2234677Y461885D02*
X2234367Y462094D01*
Y462510D01*
X2234677Y462719D01*
X2234987Y462510D01*
Y462094D01*
X2234677Y461885D01*
G01X2247077Y474802D02*
X2245837Y474385D01*
X2244907Y473344D01*
X2244287Y472094D01*
X2243822Y470427D01*
X2243667Y468552D01*
X2243822Y466677D01*
X2244287Y465010D01*
X2244907Y463760D01*
X2245837Y462719D01*
X2247077Y462302D01*
X2248317Y462719D01*
X2249247Y463760D01*
X2249867Y465010D01*
X2250332Y466677D01*
X2250487Y468552D01*
X2250332Y470427D01*
X2249867Y472094D01*
X2249247Y473344D01*
X2248317Y474385D01*
X2247077Y474802D01*
G01X2211737Y495902D02*
Y508402D01*
X2206002Y499444D01*
X2213752D01*
G01X2222277Y508402D02*
X2221037Y507985D01*
X2220107Y506944D01*
X2219487Y505694D01*
X2219022Y504027D01*
X2218867Y502152D01*
X2219022Y500277D01*
X2219487Y498610D01*
X2220107Y497360D01*
X2221037Y496319D01*
X2222277Y495902D01*
X2223517Y496319D01*
X2224447Y497360D01*
X2225067Y498610D01*
X2225532Y500277D01*
X2225687Y502152D01*
X2225532Y504027D01*
X2225067Y505694D01*
X2224447Y506944D01*
X2223517Y507985D01*
X2222277Y508402D01*
G01X2234677Y495485D02*
X2234367Y495694D01*
Y496110D01*
X2234677Y496319D01*
X2234987Y496110D01*
Y495694D01*
X2234677Y495485D01*
G01X2247077Y508402D02*
X2245837Y507985D01*
X2244907Y506944D01*
X2244287Y505694D01*
X2243822Y504027D01*
X2243667Y502152D01*
X2243822Y500277D01*
X2244287Y498610D01*
X2244907Y497360D01*
X2245837Y496319D01*
X2247077Y495902D01*
X2248317Y496319D01*
X2249247Y497360D01*
X2249867Y498610D01*
X2250332Y500277D01*
X2250487Y502152D01*
X2250332Y504027D01*
X2249867Y505694D01*
X2249247Y506944D01*
X2248317Y507985D01*
X2247077Y508402D01*
G01X2206467Y532002D02*
X2207397Y530543D01*
X2208637Y529710D01*
X2210032Y529502D01*
X2211272Y529710D01*
X2212512Y530752D01*
X2213287Y532002D01*
X2213442Y533252D01*
X2213132Y534710D01*
X2212047Y535752D01*
X2210962Y536169D01*
X2209567D01*
G01X2210962D02*
X2211892Y536794D01*
X2212667Y537835D01*
X2212977Y539085D01*
X2212667Y540335D01*
X2211892Y541377D01*
X2210497Y542002D01*
X2209102Y541794D01*
X2207707Y540960D01*
G01X2219642Y530960D02*
X2220727Y529919D01*
X2221967Y529502D01*
X2223207Y529919D01*
X2224292Y531168D01*
X2225067Y533044D01*
X2225377Y534919D01*
Y537210D01*
X2225067Y539085D01*
X2224292Y540752D01*
X2223362Y541585D01*
X2222277Y542002D01*
X2221037Y541585D01*
X2220107Y540752D01*
X2219487Y539502D01*
X2219177Y537835D01*
X2219487Y536377D01*
X2220262Y534919D01*
X2221192Y534085D01*
X2222277Y533877D01*
X2223517Y534293D01*
X2224447Y535335D01*
X2225377Y537210D01*
G01X2234677Y529085D02*
X2234367Y529294D01*
Y529710D01*
X2234677Y529919D01*
X2234987Y529710D01*
Y529294D01*
X2234677Y529085D01*
G01X2247077Y542002D02*
X2245837Y541585D01*
X2244907Y540544D01*
X2244287Y539294D01*
X2243822Y537627D01*
X2243667Y535752D01*
X2243822Y533877D01*
X2244287Y532210D01*
X2244907Y530960D01*
X2245837Y529919D01*
X2247077Y529502D01*
X2248317Y529919D01*
X2249247Y530960D01*
X2249867Y532210D01*
X2250332Y533877D01*
X2250487Y535752D01*
X2250332Y537627D01*
X2249867Y539294D01*
X2249247Y540544D01*
X2248317Y541585D01*
X2247077Y542002D01*
G01X2206467Y565602D02*
X2207397Y564143D01*
X2208637Y563310D01*
X2210032Y563102D01*
X2211272Y563310D01*
X2212512Y564352D01*
X2213287Y565602D01*
X2213442Y566852D01*
X2213132Y568310D01*
X2212047Y569352D01*
X2210962Y569769D01*
X2209567D01*
G01X2210962D02*
X2211892Y570394D01*
X2212667Y571435D01*
X2212977Y572685D01*
X2212667Y573935D01*
X2211892Y574977D01*
X2210497Y575602D01*
X2209102Y575394D01*
X2207707Y574560D01*
G01X2219332Y568310D02*
X2220417Y569769D01*
X2221347Y570602D01*
X2222587Y571019D01*
X2223672Y570602D01*
X2224447Y569769D01*
X2225067Y568519D01*
X2225222Y567060D01*
X2225067Y565810D01*
X2224447Y564560D01*
X2223517Y563519D01*
X2222432Y563102D01*
X2221192Y563519D01*
X2220107Y564768D01*
X2219487Y566644D01*
X2219332Y568727D01*
X2219642Y571435D01*
X2220107Y572894D01*
X2220882Y574352D01*
X2221967Y575394D01*
X2223052Y575602D01*
X2224137Y575185D01*
X2224912Y574144D01*
G01X2234677Y562685D02*
X2234367Y562894D01*
Y563310D01*
X2234677Y563519D01*
X2234987Y563310D01*
Y562894D01*
X2234677Y562685D01*
G01X2247077Y575602D02*
X2245837Y575185D01*
X2244907Y574144D01*
X2244287Y572894D01*
X2243822Y571227D01*
X2243667Y569352D01*
X2243822Y567477D01*
X2244287Y565810D01*
X2244907Y564560D01*
X2245837Y563519D01*
X2247077Y563102D01*
X2248317Y563519D01*
X2249247Y564560D01*
X2249867Y565810D01*
X2250332Y567477D01*
X2250487Y569352D01*
X2250332Y571227D01*
X2249867Y572894D01*
X2249247Y574144D01*
X2248317Y575185D01*
X2247077Y575602D01*
G01X2206467Y599202D02*
X2207397Y597743D01*
X2208637Y596910D01*
X2210032Y596702D01*
X2211272Y596910D01*
X2212512Y597952D01*
X2213287Y599202D01*
X2213442Y600452D01*
X2213132Y601910D01*
X2212047Y602952D01*
X2210962Y603369D01*
X2209567D01*
G01X2210962D02*
X2211892Y603994D01*
X2212667Y605035D01*
X2212977Y606285D01*
X2212667Y607535D01*
X2211892Y608577D01*
X2210497Y609202D01*
X2209102Y608994D01*
X2207707Y608160D01*
G01X2219332Y607119D02*
X2220262Y608368D01*
X2221347Y608994D01*
X2222587Y609202D01*
X2224137Y608785D01*
X2225222Y607744D01*
X2225532Y606494D01*
X2225377Y605243D01*
X2224757Y604202D01*
X2221657Y602119D01*
X2220262Y600660D01*
X2219332Y598577D01*
X2219022Y596702D01*
X2225532D01*
G01X2234677Y596285D02*
X2234367Y596494D01*
Y596910D01*
X2234677Y597119D01*
X2234987Y596910D01*
Y596494D01*
X2234677Y596285D01*
G01X2247077Y609202D02*
X2245837Y608785D01*
X2244907Y607744D01*
X2244287Y606494D01*
X2243822Y604827D01*
X2243667Y602952D01*
X2243822Y601077D01*
X2244287Y599410D01*
X2244907Y598160D01*
X2245837Y597119D01*
X2247077Y596702D01*
X2248317Y597119D01*
X2249247Y598160D01*
X2249867Y599410D01*
X2250332Y601077D01*
X2250487Y602952D01*
X2250332Y604827D01*
X2249867Y606494D01*
X2249247Y607744D01*
X2248317Y608785D01*
X2247077Y609202D01*
G01X2206467Y632802D02*
X2207397Y631343D01*
X2208637Y630510D01*
X2210032Y630302D01*
X2211272Y630510D01*
X2212512Y631552D01*
X2213287Y632802D01*
X2213442Y634052D01*
X2213132Y635510D01*
X2212047Y636552D01*
X2210962Y636969D01*
X2209567D01*
G01X2210962D02*
X2211892Y637594D01*
X2212667Y638635D01*
X2212977Y639885D01*
X2212667Y641135D01*
X2211892Y642177D01*
X2210497Y642802D01*
X2209102Y642594D01*
X2207707Y641760D01*
G01X2222277Y642802D02*
X2221037Y642385D01*
X2220107Y641344D01*
X2219487Y640094D01*
X2219022Y638427D01*
X2218867Y636552D01*
X2219022Y634677D01*
X2219487Y633010D01*
X2220107Y631760D01*
X2221037Y630719D01*
X2222277Y630302D01*
X2223517Y630719D01*
X2224447Y631760D01*
X2225067Y633010D01*
X2225532Y634677D01*
X2225687Y636552D01*
X2225532Y638427D01*
X2225067Y640094D01*
X2224447Y641344D01*
X2223517Y642385D01*
X2222277Y642802D01*
G01X2234677Y629885D02*
X2234367Y630094D01*
Y630510D01*
X2234677Y630719D01*
X2234987Y630510D01*
Y630094D01*
X2234677Y629885D01*
G01X2247077Y642802D02*
X2245837Y642385D01*
X2244907Y641344D01*
X2244287Y640094D01*
X2243822Y638427D01*
X2243667Y636552D01*
X2243822Y634677D01*
X2244287Y633010D01*
X2244907Y631760D01*
X2245837Y630719D01*
X2247077Y630302D01*
X2248317Y630719D01*
X2249247Y631760D01*
X2249867Y633010D01*
X2250332Y634677D01*
X2250487Y636552D01*
X2250332Y638427D01*
X2249867Y640094D01*
X2249247Y641344D01*
X2248317Y642385D01*
X2247077Y642802D01*
G01X2206467Y666402D02*
X2207397Y664943D01*
X2208637Y664110D01*
X2210032Y663902D01*
X2211272Y664110D01*
X2212512Y665152D01*
X2213287Y666402D01*
X2213442Y667652D01*
X2213132Y669110D01*
X2212047Y670152D01*
X2210962Y670569D01*
X2209567D01*
G01X2210962D02*
X2211892Y671194D01*
X2212667Y672235D01*
X2212977Y673485D01*
X2212667Y674735D01*
X2211892Y675777D01*
X2210497Y676402D01*
X2209102Y676194D01*
X2207707Y675360D01*
G01X2222277Y676402D02*
X2221037Y675985D01*
X2220107Y674944D01*
X2219487Y673694D01*
X2219022Y672027D01*
X2218867Y670152D01*
X2219022Y668277D01*
X2219487Y666610D01*
X2220107Y665360D01*
X2221037Y664319D01*
X2222277Y663902D01*
X2223517Y664319D01*
X2224447Y665360D01*
X2225067Y666610D01*
X2225532Y668277D01*
X2225687Y670152D01*
X2225532Y672027D01*
X2225067Y673694D01*
X2224447Y674944D01*
X2223517Y675985D01*
X2222277Y676402D01*
G01X2234677Y663485D02*
X2234367Y663694D01*
Y664110D01*
X2234677Y664319D01*
X2234987Y664110D01*
Y663694D01*
X2234677Y663485D01*
G01X2247077Y676402D02*
X2245837Y675985D01*
X2244907Y674944D01*
X2244287Y673694D01*
X2243822Y672027D01*
X2243667Y670152D01*
X2243822Y668277D01*
X2244287Y666610D01*
X2244907Y665360D01*
X2245837Y664319D01*
X2247077Y663902D01*
X2248317Y664319D01*
X2249247Y665360D01*
X2249867Y666610D01*
X2250332Y668277D01*
X2250487Y670152D01*
X2250332Y672027D01*
X2249867Y673694D01*
X2249247Y674944D01*
X2248317Y675985D01*
X2247077Y676402D01*
G01X2206932Y707919D02*
X2207862Y709168D01*
X2208947Y709794D01*
X2210187Y710002D01*
X2211737Y709585D01*
X2212822Y708544D01*
X2213132Y707294D01*
X2212977Y706043D01*
X2212357Y705002D01*
X2209257Y702919D01*
X2207862Y701460D01*
X2206932Y699377D01*
X2206622Y697502D01*
X2213132D01*
G01X2219332Y702710D02*
X2220417Y704169D01*
X2221347Y705002D01*
X2222587Y705419D01*
X2223672Y705002D01*
X2224447Y704169D01*
X2225067Y702919D01*
X2225222Y701460D01*
X2225067Y700210D01*
X2224447Y698960D01*
X2223517Y697919D01*
X2222432Y697502D01*
X2221192Y697919D01*
X2220107Y699168D01*
X2219487Y701044D01*
X2219332Y703127D01*
X2219642Y705835D01*
X2220107Y707294D01*
X2220882Y708752D01*
X2221967Y709794D01*
X2223052Y710002D01*
X2224137Y709585D01*
X2224912Y708544D01*
G01X2234677Y697085D02*
X2234367Y697294D01*
Y697710D01*
X2234677Y697919D01*
X2234987Y697710D01*
Y697294D01*
X2234677Y697085D01*
G01X2247077Y710002D02*
X2245837Y709585D01*
X2244907Y708544D01*
X2244287Y707294D01*
X2243822Y705627D01*
X2243667Y703752D01*
X2243822Y701877D01*
X2244287Y700210D01*
X2244907Y698960D01*
X2245837Y697919D01*
X2247077Y697502D01*
X2248317Y697919D01*
X2249247Y698960D01*
X2249867Y700210D01*
X2250332Y701877D01*
X2250487Y703752D01*
X2250332Y705627D01*
X2249867Y707294D01*
X2249247Y708544D01*
X2248317Y709585D01*
X2247077Y710002D01*
G01X2206932Y741519D02*
X2207862Y742768D01*
X2208947Y743394D01*
X2210187Y743602D01*
X2211737Y743185D01*
X2212822Y742144D01*
X2213132Y740894D01*
X2212977Y739643D01*
X2212357Y738602D01*
X2209257Y736519D01*
X2207862Y735060D01*
X2206932Y732977D01*
X2206622Y731102D01*
X2213132D01*
G01X2219332Y741519D02*
X2220262Y742768D01*
X2221347Y743394D01*
X2222587Y743602D01*
X2224137Y743185D01*
X2225222Y742144D01*
X2225532Y740894D01*
X2225377Y739643D01*
X2224757Y738602D01*
X2221657Y736519D01*
X2220262Y735060D01*
X2219332Y732977D01*
X2219022Y731102D01*
X2225532D01*
G01X2234677Y730685D02*
X2234367Y730894D01*
Y731310D01*
X2234677Y731519D01*
X2234987Y731310D01*
Y730894D01*
X2234677Y730685D01*
G01X2247077Y743602D02*
X2245837Y743185D01*
X2244907Y742144D01*
X2244287Y740894D01*
X2243822Y739227D01*
X2243667Y737352D01*
X2243822Y735477D01*
X2244287Y733810D01*
X2244907Y732560D01*
X2245837Y731519D01*
X2247077Y731102D01*
X2248317Y731519D01*
X2249247Y732560D01*
X2249867Y733810D01*
X2250332Y735477D01*
X2250487Y737352D01*
X2250332Y739227D01*
X2249867Y740894D01*
X2249247Y742144D01*
X2248317Y743185D01*
X2247077Y743602D01*
G01X2200732Y775119D02*
X2201662Y776368D01*
X2202747Y776994D01*
X2203987Y777202D01*
X2205537Y776785D01*
X2206622Y775744D01*
X2206932Y774494D01*
X2206777Y773243D01*
X2206157Y772202D01*
X2203057Y770119D01*
X2201662Y768660D01*
X2200732Y766577D01*
X2200422Y764702D01*
X2206932D01*
G01X2213132Y775119D02*
X2214062Y776368D01*
X2215147Y776994D01*
X2216387Y777202D01*
X2217937Y776785D01*
X2219022Y775744D01*
X2219332Y774494D01*
X2219177Y773243D01*
X2218557Y772202D01*
X2215457Y770119D01*
X2214062Y768660D01*
X2213132Y766577D01*
X2212822Y764702D01*
X2219332D01*
G01X2230337D02*
Y777202D01*
X2224602Y768244D01*
X2232352D01*
G01X2240877Y764285D02*
X2240567Y764494D01*
Y764910D01*
X2240877Y765119D01*
X2241187Y764910D01*
Y764494D01*
X2240877Y764285D01*
G01X2253277Y777202D02*
X2252037Y776785D01*
X2251107Y775744D01*
X2250487Y774494D01*
X2250022Y772827D01*
X2249867Y770952D01*
X2250022Y769077D01*
X2250487Y767410D01*
X2251107Y766160D01*
X2252037Y765119D01*
X2253277Y764702D01*
X2254517Y765119D01*
X2255447Y766160D01*
X2256067Y767410D01*
X2256532Y769077D01*
X2256687Y770952D01*
X2256532Y772827D01*
X2256067Y774494D01*
X2255447Y775744D01*
X2254517Y776785D01*
X2253277Y777202D01*
G01X2203677Y798302D02*
Y810802D01*
X2201817Y808302D01*
G01Y798302D02*
X2205537D01*
G01X2215767D02*
X2216077Y801010D01*
X2216542Y803302D01*
X2217162Y805385D01*
X2217937Y807677D01*
X2219177Y810802D01*
X2212977D01*
G01X2228167Y798302D02*
X2228477Y801010D01*
X2228942Y803302D01*
X2229562Y805385D01*
X2230337Y807677D01*
X2231577Y810802D01*
X2225377D01*
G01X2240877Y797885D02*
X2240567Y798094D01*
Y798510D01*
X2240877Y798719D01*
X2241187Y798510D01*
Y798094D01*
X2240877Y797885D01*
G01X2253277Y810802D02*
X2252037Y810385D01*
X2251107Y809344D01*
X2250487Y808094D01*
X2250022Y806427D01*
X2249867Y804552D01*
X2250022Y802677D01*
X2250487Y801010D01*
X2251107Y799760D01*
X2252037Y798719D01*
X2253277Y798302D01*
X2254517Y798719D01*
X2255447Y799760D01*
X2256067Y801010D01*
X2256532Y802677D01*
X2256687Y804552D01*
X2256532Y806427D01*
X2256067Y808094D01*
X2255447Y809344D01*
X2254517Y810385D01*
X2253277Y810802D01*
G01X2203677Y831902D02*
Y844402D01*
X2201817Y841902D01*
G01Y831902D02*
X2205537D01*
G01X2213132Y842319D02*
X2214062Y843568D01*
X2215147Y844194D01*
X2216387Y844402D01*
X2217937Y843985D01*
X2219022Y842944D01*
X2219332Y841694D01*
X2219177Y840443D01*
X2218557Y839402D01*
X2215457Y837319D01*
X2214062Y835860D01*
X2213132Y833777D01*
X2212822Y831902D01*
X2219332D01*
G01X2225067Y833777D02*
X2225997Y832735D01*
X2227082Y832110D01*
X2228477Y831902D01*
X2229872Y832319D01*
X2230957Y833152D01*
X2231732Y834610D01*
X2231887Y836277D01*
X2231577Y837944D01*
X2230802Y838985D01*
X2229717Y839819D01*
X2228632Y840027D01*
X2227547Y839819D01*
X2226152Y838985D01*
X2226617Y844402D01*
X2230802D01*
G01X2240877Y831485D02*
X2240567Y831694D01*
Y832110D01*
X2240877Y832319D01*
X2241187Y832110D01*
Y831694D01*
X2240877Y831485D01*
G01X2253277Y844402D02*
X2252037Y843985D01*
X2251107Y842944D01*
X2250487Y841694D01*
X2250022Y840027D01*
X2249867Y838152D01*
X2250022Y836277D01*
X2250487Y834610D01*
X2251107Y833360D01*
X2252037Y832319D01*
X2253277Y831902D01*
X2254517Y832319D01*
X2255447Y833360D01*
X2256067Y834610D01*
X2256532Y836277D01*
X2256687Y838152D01*
X2256532Y840027D01*
X2256067Y841694D01*
X2255447Y842944D01*
X2254517Y843985D01*
X2253277Y844402D01*
G01X2207242Y866960D02*
X2208327Y865919D01*
X2209567Y865502D01*
X2210807Y865919D01*
X2211892Y867168D01*
X2212667Y869044D01*
X2212977Y870919D01*
Y873210D01*
X2212667Y875085D01*
X2211892Y876752D01*
X2210962Y877585D01*
X2209877Y878002D01*
X2208637Y877585D01*
X2207707Y876752D01*
X2207087Y875502D01*
X2206777Y873835D01*
X2207087Y872377D01*
X2207862Y870919D01*
X2208792Y870085D01*
X2209877Y869877D01*
X2211117Y870293D01*
X2212047Y871335D01*
X2212977Y873210D01*
G01X2219332Y870710D02*
X2220417Y872169D01*
X2221347Y873002D01*
X2222587Y873419D01*
X2223672Y873002D01*
X2224447Y872169D01*
X2225067Y870919D01*
X2225222Y869460D01*
X2225067Y868210D01*
X2224447Y866960D01*
X2223517Y865919D01*
X2222432Y865502D01*
X2221192Y865919D01*
X2220107Y867168D01*
X2219487Y869044D01*
X2219332Y871127D01*
X2219642Y873835D01*
X2220107Y875294D01*
X2220882Y876752D01*
X2221967Y877794D01*
X2223052Y878002D01*
X2224137Y877585D01*
X2224912Y876544D01*
G01X2234677Y865085D02*
X2234367Y865294D01*
Y865710D01*
X2234677Y865919D01*
X2234987Y865710D01*
Y865294D01*
X2234677Y865085D01*
G01X2247077Y878002D02*
X2245837Y877585D01*
X2244907Y876544D01*
X2244287Y875294D01*
X2243822Y873627D01*
X2243667Y871752D01*
X2243822Y869877D01*
X2244287Y868210D01*
X2244907Y866960D01*
X2245837Y865919D01*
X2247077Y865502D01*
X2248317Y865919D01*
X2249247Y866960D01*
X2249867Y868210D01*
X2250332Y869877D01*
X2250487Y871752D01*
X2250332Y873627D01*
X2249867Y875294D01*
X2249247Y876544D01*
X2248317Y877585D01*
X2247077Y878002D01*
G01X2211737Y899102D02*
Y911602D01*
X2206002Y902644D01*
X2213752D01*
G01X2219642Y900560D02*
X2220727Y899519D01*
X2221967Y899102D01*
X2223207Y899519D01*
X2224292Y900768D01*
X2225067Y902644D01*
X2225377Y904519D01*
Y906810D01*
X2225067Y908685D01*
X2224292Y910352D01*
X2223362Y911185D01*
X2222277Y911602D01*
X2221037Y911185D01*
X2220107Y910352D01*
X2219487Y909102D01*
X2219177Y907435D01*
X2219487Y905977D01*
X2220262Y904519D01*
X2221192Y903685D01*
X2222277Y903477D01*
X2223517Y903893D01*
X2224447Y904935D01*
X2225377Y906810D01*
G01X2234677Y898685D02*
X2234367Y898894D01*
Y899310D01*
X2234677Y899519D01*
X2234987Y899310D01*
Y898894D01*
X2234677Y898685D01*
G01X2247077Y911602D02*
X2245837Y911185D01*
X2244907Y910144D01*
X2244287Y908894D01*
X2243822Y907227D01*
X2243667Y905352D01*
X2243822Y903477D01*
X2244287Y901810D01*
X2244907Y900560D01*
X2245837Y899519D01*
X2247077Y899102D01*
X2248317Y899519D01*
X2249247Y900560D01*
X2249867Y901810D01*
X2250332Y903477D01*
X2250487Y905352D01*
X2250332Y907227D01*
X2249867Y908894D01*
X2249247Y910144D01*
X2248317Y911185D01*
X2247077Y911602D01*
G01X2211737Y932702D02*
Y945202D01*
X2206002Y936244D01*
X2213752D01*
G01X2219332Y937910D02*
X2220417Y939369D01*
X2221347Y940202D01*
X2222587Y940619D01*
X2223672Y940202D01*
X2224447Y939369D01*
X2225067Y938119D01*
X2225222Y936660D01*
X2225067Y935410D01*
X2224447Y934160D01*
X2223517Y933119D01*
X2222432Y932702D01*
X2221192Y933119D01*
X2220107Y934368D01*
X2219487Y936244D01*
X2219332Y938327D01*
X2219642Y941035D01*
X2220107Y942494D01*
X2220882Y943952D01*
X2221967Y944994D01*
X2223052Y945202D01*
X2224137Y944785D01*
X2224912Y943744D01*
G01X2234677Y932285D02*
X2234367Y932494D01*
Y932910D01*
X2234677Y933119D01*
X2234987Y932910D01*
Y932494D01*
X2234677Y932285D01*
G01X2247077Y945202D02*
X2245837Y944785D01*
X2244907Y943744D01*
X2244287Y942494D01*
X2243822Y940827D01*
X2243667Y938952D01*
X2243822Y937077D01*
X2244287Y935410D01*
X2244907Y934160D01*
X2245837Y933119D01*
X2247077Y932702D01*
X2248317Y933119D01*
X2249247Y934160D01*
X2249867Y935410D01*
X2250332Y937077D01*
X2250487Y938952D01*
X2250332Y940827D01*
X2249867Y942494D01*
X2249247Y943744D01*
X2248317Y944785D01*
X2247077Y945202D01*
G01X2211737Y966302D02*
Y978802D01*
X2206002Y969844D01*
X2213752D01*
G01X2218867Y968177D02*
X2219797Y967135D01*
X2220882Y966510D01*
X2222277Y966302D01*
X2223672Y966719D01*
X2224757Y967552D01*
X2225532Y969010D01*
X2225687Y970677D01*
X2225377Y972344D01*
X2224602Y973385D01*
X2223517Y974219D01*
X2222432Y974427D01*
X2221347Y974219D01*
X2219952Y973385D01*
X2220417Y978802D01*
X2224602D01*
G01X2234677Y965885D02*
X2234367Y966094D01*
Y966510D01*
X2234677Y966719D01*
X2234987Y966510D01*
Y966094D01*
X2234677Y965885D01*
G01X2247077Y978802D02*
X2245837Y978385D01*
X2244907Y977344D01*
X2244287Y976094D01*
X2243822Y974427D01*
X2243667Y972552D01*
X2243822Y970677D01*
X2244287Y969010D01*
X2244907Y967760D01*
X2245837Y966719D01*
X2247077Y966302D01*
X2248317Y966719D01*
X2249247Y967760D01*
X2249867Y969010D01*
X2250332Y970677D01*
X2250487Y972552D01*
X2250332Y974427D01*
X2249867Y976094D01*
X2249247Y977344D01*
X2248317Y978385D01*
X2247077Y978802D01*
G01X2211737Y999902D02*
Y1012402D01*
X2206002Y1003444D01*
X2213752D01*
G01X2222277Y999902D02*
Y1012402D01*
X2220417Y1009902D01*
G01Y999902D02*
X2224137D01*
G01X2234677Y999485D02*
X2234367Y999694D01*
Y1000110D01*
X2234677Y1000319D01*
X2234987Y1000110D01*
Y999694D01*
X2234677Y999485D01*
G01X2247077Y1012402D02*
X2245837Y1011985D01*
X2244907Y1010944D01*
X2244287Y1009694D01*
X2243822Y1008027D01*
X2243667Y1006152D01*
X2243822Y1004277D01*
X2244287Y1002610D01*
X2244907Y1001360D01*
X2245837Y1000319D01*
X2247077Y999902D01*
X2248317Y1000319D01*
X2249247Y1001360D01*
X2249867Y1002610D01*
X2250332Y1004277D01*
X2250487Y1006152D01*
X2250332Y1008027D01*
X2249867Y1009694D01*
X2249247Y1010944D01*
X2248317Y1011985D01*
X2247077Y1012402D01*
G01X2211737Y1033502D02*
Y1046002D01*
X2206002Y1037044D01*
X2213752D01*
G01X2222277Y1033502D02*
Y1046002D01*
X2220417Y1043502D01*
G01Y1033502D02*
X2224137D01*
G01X2234677Y1033085D02*
X2234367Y1033294D01*
Y1033710D01*
X2234677Y1033919D01*
X2234987Y1033710D01*
Y1033294D01*
X2234677Y1033085D01*
G01X2247077Y1046002D02*
X2245837Y1045585D01*
X2244907Y1044544D01*
X2244287Y1043294D01*
X2243822Y1041627D01*
X2243667Y1039752D01*
X2243822Y1037877D01*
X2244287Y1036210D01*
X2244907Y1034960D01*
X2245837Y1033919D01*
X2247077Y1033502D01*
X2248317Y1033919D01*
X2249247Y1034960D01*
X2249867Y1036210D01*
X2250332Y1037877D01*
X2250487Y1039752D01*
X2250332Y1041627D01*
X2249867Y1043294D01*
X2249247Y1044544D01*
X2248317Y1045585D01*
X2247077Y1046002D01*
G01X2211737Y1067102D02*
Y1079602D01*
X2206002Y1070644D01*
X2213752D01*
G01X2222277Y1079602D02*
X2221037Y1079185D01*
X2220107Y1078144D01*
X2219487Y1076894D01*
X2219022Y1075227D01*
X2218867Y1073352D01*
X2219022Y1071477D01*
X2219487Y1069810D01*
X2220107Y1068560D01*
X2221037Y1067519D01*
X2222277Y1067102D01*
X2223517Y1067519D01*
X2224447Y1068560D01*
X2225067Y1069810D01*
X2225532Y1071477D01*
X2225687Y1073352D01*
X2225532Y1075227D01*
X2225067Y1076894D01*
X2224447Y1078144D01*
X2223517Y1079185D01*
X2222277Y1079602D01*
G01X2234677Y1066685D02*
X2234367Y1066894D01*
Y1067310D01*
X2234677Y1067519D01*
X2234987Y1067310D01*
Y1066894D01*
X2234677Y1066685D01*
G01X2247077Y1079602D02*
X2245837Y1079185D01*
X2244907Y1078144D01*
X2244287Y1076894D01*
X2243822Y1075227D01*
X2243667Y1073352D01*
X2243822Y1071477D01*
X2244287Y1069810D01*
X2244907Y1068560D01*
X2245837Y1067519D01*
X2247077Y1067102D01*
X2248317Y1067519D01*
X2249247Y1068560D01*
X2249867Y1069810D01*
X2250332Y1071477D01*
X2250487Y1073352D01*
X2250332Y1075227D01*
X2249867Y1076894D01*
X2249247Y1078144D01*
X2248317Y1079185D01*
X2247077Y1079602D01*
G01X2211737Y1100702D02*
Y1113202D01*
X2206002Y1104244D01*
X2213752D01*
G01X2222277Y1113202D02*
X2221037Y1112785D01*
X2220107Y1111744D01*
X2219487Y1110494D01*
X2219022Y1108827D01*
X2218867Y1106952D01*
X2219022Y1105077D01*
X2219487Y1103410D01*
X2220107Y1102160D01*
X2221037Y1101119D01*
X2222277Y1100702D01*
X2223517Y1101119D01*
X2224447Y1102160D01*
X2225067Y1103410D01*
X2225532Y1105077D01*
X2225687Y1106952D01*
X2225532Y1108827D01*
X2225067Y1110494D01*
X2224447Y1111744D01*
X2223517Y1112785D01*
X2222277Y1113202D01*
G01X2234677Y1100285D02*
X2234367Y1100494D01*
Y1100910D01*
X2234677Y1101119D01*
X2234987Y1100910D01*
Y1100494D01*
X2234677Y1100285D01*
G01X2247077Y1113202D02*
X2245837Y1112785D01*
X2244907Y1111744D01*
X2244287Y1110494D01*
X2243822Y1108827D01*
X2243667Y1106952D01*
X2243822Y1105077D01*
X2244287Y1103410D01*
X2244907Y1102160D01*
X2245837Y1101119D01*
X2247077Y1100702D01*
X2248317Y1101119D01*
X2249247Y1102160D01*
X2249867Y1103410D01*
X2250332Y1105077D01*
X2250487Y1106952D01*
X2250332Y1108827D01*
X2249867Y1110494D01*
X2249247Y1111744D01*
X2248317Y1112785D01*
X2247077Y1113202D01*
G01X2206467Y1136802D02*
X2207397Y1135343D01*
X2208637Y1134510D01*
X2210032Y1134302D01*
X2211272Y1134510D01*
X2212512Y1135552D01*
X2213287Y1136802D01*
X2213442Y1138052D01*
X2213132Y1139510D01*
X2212047Y1140552D01*
X2210962Y1140969D01*
X2209567D01*
G01X2210962D02*
X2211892Y1141594D01*
X2212667Y1142635D01*
X2212977Y1143885D01*
X2212667Y1145135D01*
X2211892Y1146177D01*
X2210497Y1146802D01*
X2209102Y1146594D01*
X2207707Y1145760D01*
G01X2219642Y1135760D02*
X2220727Y1134719D01*
X2221967Y1134302D01*
X2223207Y1134719D01*
X2224292Y1135968D01*
X2225067Y1137844D01*
X2225377Y1139719D01*
Y1142010D01*
X2225067Y1143885D01*
X2224292Y1145552D01*
X2223362Y1146385D01*
X2222277Y1146802D01*
X2221037Y1146385D01*
X2220107Y1145552D01*
X2219487Y1144302D01*
X2219177Y1142635D01*
X2219487Y1141177D01*
X2220262Y1139719D01*
X2221192Y1138885D01*
X2222277Y1138677D01*
X2223517Y1139093D01*
X2224447Y1140135D01*
X2225377Y1142010D01*
G01X2234677Y1133885D02*
X2234367Y1134094D01*
Y1134510D01*
X2234677Y1134719D01*
X2234987Y1134510D01*
Y1134094D01*
X2234677Y1133885D01*
G01X2247077Y1146802D02*
X2245837Y1146385D01*
X2244907Y1145344D01*
X2244287Y1144094D01*
X2243822Y1142427D01*
X2243667Y1140552D01*
X2243822Y1138677D01*
X2244287Y1137010D01*
X2244907Y1135760D01*
X2245837Y1134719D01*
X2247077Y1134302D01*
X2248317Y1134719D01*
X2249247Y1135760D01*
X2249867Y1137010D01*
X2250332Y1138677D01*
X2250487Y1140552D01*
X2250332Y1142427D01*
X2249867Y1144094D01*
X2249247Y1145344D01*
X2248317Y1146385D01*
X2247077Y1146802D01*
G01X2206467Y1170402D02*
X2207397Y1168943D01*
X2208637Y1168110D01*
X2210032Y1167902D01*
X2211272Y1168110D01*
X2212512Y1169152D01*
X2213287Y1170402D01*
X2213442Y1171652D01*
X2213132Y1173110D01*
X2212047Y1174152D01*
X2210962Y1174569D01*
X2209567D01*
G01X2210962D02*
X2211892Y1175194D01*
X2212667Y1176235D01*
X2212977Y1177485D01*
X2212667Y1178735D01*
X2211892Y1179777D01*
X2210497Y1180402D01*
X2209102Y1180194D01*
X2207707Y1179360D01*
G01X2219332Y1173110D02*
X2220417Y1174569D01*
X2221347Y1175402D01*
X2222587Y1175819D01*
X2223672Y1175402D01*
X2224447Y1174569D01*
X2225067Y1173319D01*
X2225222Y1171860D01*
X2225067Y1170610D01*
X2224447Y1169360D01*
X2223517Y1168319D01*
X2222432Y1167902D01*
X2221192Y1168319D01*
X2220107Y1169568D01*
X2219487Y1171444D01*
X2219332Y1173527D01*
X2219642Y1176235D01*
X2220107Y1177694D01*
X2220882Y1179152D01*
X2221967Y1180194D01*
X2223052Y1180402D01*
X2224137Y1179985D01*
X2224912Y1178944D01*
G01X2234677Y1167485D02*
X2234367Y1167694D01*
Y1168110D01*
X2234677Y1168319D01*
X2234987Y1168110D01*
Y1167694D01*
X2234677Y1167485D01*
G01X2247077Y1180402D02*
X2245837Y1179985D01*
X2244907Y1178944D01*
X2244287Y1177694D01*
X2243822Y1176027D01*
X2243667Y1174152D01*
X2243822Y1172277D01*
X2244287Y1170610D01*
X2244907Y1169360D01*
X2245837Y1168319D01*
X2247077Y1167902D01*
X2248317Y1168319D01*
X2249247Y1169360D01*
X2249867Y1170610D01*
X2250332Y1172277D01*
X2250487Y1174152D01*
X2250332Y1176027D01*
X2249867Y1177694D01*
X2249247Y1178944D01*
X2248317Y1179985D01*
X2247077Y1180402D01*
G01X2206467Y1204002D02*
X2207397Y1202543D01*
X2208637Y1201710D01*
X2210032Y1201502D01*
X2211272Y1201710D01*
X2212512Y1202752D01*
X2213287Y1204002D01*
X2213442Y1205252D01*
X2213132Y1206710D01*
X2212047Y1207752D01*
X2210962Y1208169D01*
X2209567D01*
G01X2210962D02*
X2211892Y1208794D01*
X2212667Y1209835D01*
X2212977Y1211085D01*
X2212667Y1212335D01*
X2211892Y1213377D01*
X2210497Y1214002D01*
X2209102Y1213794D01*
X2207707Y1212960D01*
G01X2224137Y1201502D02*
Y1214002D01*
X2218402Y1205044D01*
X2226152D01*
G01X2234677Y1201085D02*
X2234367Y1201294D01*
Y1201710D01*
X2234677Y1201919D01*
X2234987Y1201710D01*
Y1201294D01*
X2234677Y1201085D01*
G01X2247077Y1214002D02*
X2245837Y1213585D01*
X2244907Y1212544D01*
X2244287Y1211294D01*
X2243822Y1209627D01*
X2243667Y1207752D01*
X2243822Y1205877D01*
X2244287Y1204210D01*
X2244907Y1202960D01*
X2245837Y1201919D01*
X2247077Y1201502D01*
X2248317Y1201919D01*
X2249247Y1202960D01*
X2249867Y1204210D01*
X2250332Y1205877D01*
X2250487Y1207752D01*
X2250332Y1209627D01*
X2249867Y1211294D01*
X2249247Y1212544D01*
X2248317Y1213585D01*
X2247077Y1214002D01*
G01X2206467Y1237602D02*
X2207397Y1236143D01*
X2208637Y1235310D01*
X2210032Y1235102D01*
X2211272Y1235310D01*
X2212512Y1236352D01*
X2213287Y1237602D01*
X2213442Y1238852D01*
X2213132Y1240310D01*
X2212047Y1241352D01*
X2210962Y1241769D01*
X2209567D01*
G01X2210962D02*
X2211892Y1242394D01*
X2212667Y1243435D01*
X2212977Y1244685D01*
X2212667Y1245935D01*
X2211892Y1246977D01*
X2210497Y1247602D01*
X2209102Y1247394D01*
X2207707Y1246560D01*
G01X2219332Y1245519D02*
X2220262Y1246768D01*
X2221347Y1247394D01*
X2222587Y1247602D01*
X2224137Y1247185D01*
X2225222Y1246144D01*
X2225532Y1244894D01*
X2225377Y1243643D01*
X2224757Y1242602D01*
X2221657Y1240519D01*
X2220262Y1239060D01*
X2219332Y1236977D01*
X2219022Y1235102D01*
X2225532D01*
G01X2234677Y1234685D02*
X2234367Y1234894D01*
Y1235310D01*
X2234677Y1235519D01*
X2234987Y1235310D01*
Y1234894D01*
X2234677Y1234685D01*
G01X2247077Y1247602D02*
X2245837Y1247185D01*
X2244907Y1246144D01*
X2244287Y1244894D01*
X2243822Y1243227D01*
X2243667Y1241352D01*
X2243822Y1239477D01*
X2244287Y1237810D01*
X2244907Y1236560D01*
X2245837Y1235519D01*
X2247077Y1235102D01*
X2248317Y1235519D01*
X2249247Y1236560D01*
X2249867Y1237810D01*
X2250332Y1239477D01*
X2250487Y1241352D01*
X2250332Y1243227D01*
X2249867Y1244894D01*
X2249247Y1246144D01*
X2248317Y1247185D01*
X2247077Y1247602D01*
G01X2206467Y1271202D02*
X2207397Y1269743D01*
X2208637Y1268910D01*
X2210032Y1268702D01*
X2211272Y1268910D01*
X2212512Y1269952D01*
X2213287Y1271202D01*
X2213442Y1272452D01*
X2213132Y1273910D01*
X2212047Y1274952D01*
X2210962Y1275369D01*
X2209567D01*
G01X2210962D02*
X2211892Y1275994D01*
X2212667Y1277035D01*
X2212977Y1278285D01*
X2212667Y1279535D01*
X2211892Y1280577D01*
X2210497Y1281202D01*
X2209102Y1280994D01*
X2207707Y1280160D01*
G01X2222277Y1268702D02*
Y1281202D01*
X2220417Y1278702D01*
G01Y1268702D02*
X2224137D01*
G01X2234677Y1268285D02*
X2234367Y1268494D01*
Y1268910D01*
X2234677Y1269119D01*
X2234987Y1268910D01*
Y1268494D01*
X2234677Y1268285D01*
G01X2247077Y1281202D02*
X2245837Y1280785D01*
X2244907Y1279744D01*
X2244287Y1278494D01*
X2243822Y1276827D01*
X2243667Y1274952D01*
X2243822Y1273077D01*
X2244287Y1271410D01*
X2244907Y1270160D01*
X2245837Y1269119D01*
X2247077Y1268702D01*
X2248317Y1269119D01*
X2249247Y1270160D01*
X2249867Y1271410D01*
X2250332Y1273077D01*
X2250487Y1274952D01*
X2250332Y1276827D01*
X2249867Y1278494D01*
X2249247Y1279744D01*
X2248317Y1280785D01*
X2247077Y1281202D01*
G01X2206467Y1304802D02*
X2207397Y1303343D01*
X2208637Y1302510D01*
X2210032Y1302302D01*
X2211272Y1302510D01*
X2212512Y1303552D01*
X2213287Y1304802D01*
X2213442Y1306052D01*
X2213132Y1307510D01*
X2212047Y1308552D01*
X2210962Y1308969D01*
X2209567D01*
G01X2210962D02*
X2211892Y1309594D01*
X2212667Y1310635D01*
X2212977Y1311885D01*
X2212667Y1313135D01*
X2211892Y1314177D01*
X2210497Y1314802D01*
X2209102Y1314594D01*
X2207707Y1313760D01*
G01X2222277Y1314802D02*
X2221037Y1314385D01*
X2220107Y1313344D01*
X2219487Y1312094D01*
X2219022Y1310427D01*
X2218867Y1308552D01*
X2219022Y1306677D01*
X2219487Y1305010D01*
X2220107Y1303760D01*
X2221037Y1302719D01*
X2222277Y1302302D01*
X2223517Y1302719D01*
X2224447Y1303760D01*
X2225067Y1305010D01*
X2225532Y1306677D01*
X2225687Y1308552D01*
X2225532Y1310427D01*
X2225067Y1312094D01*
X2224447Y1313344D01*
X2223517Y1314385D01*
X2222277Y1314802D01*
G01X2234677Y1301885D02*
X2234367Y1302094D01*
Y1302510D01*
X2234677Y1302719D01*
X2234987Y1302510D01*
Y1302094D01*
X2234677Y1301885D01*
G01X2247077Y1314802D02*
X2245837Y1314385D01*
X2244907Y1313344D01*
X2244287Y1312094D01*
X2243822Y1310427D01*
X2243667Y1308552D01*
X2243822Y1306677D01*
X2244287Y1305010D01*
X2244907Y1303760D01*
X2245837Y1302719D01*
X2247077Y1302302D01*
X2248317Y1302719D01*
X2249247Y1303760D01*
X2249867Y1305010D01*
X2250332Y1306677D01*
X2250487Y1308552D01*
X2250332Y1310427D01*
X2249867Y1312094D01*
X2249247Y1313344D01*
X2248317Y1314385D01*
X2247077Y1314802D01*
G01X2206467Y1338402D02*
X2207397Y1336943D01*
X2208637Y1336110D01*
X2210032Y1335902D01*
X2211272Y1336110D01*
X2212512Y1337152D01*
X2213287Y1338402D01*
X2213442Y1339652D01*
X2213132Y1341110D01*
X2212047Y1342152D01*
X2210962Y1342569D01*
X2209567D01*
G01X2210962D02*
X2211892Y1343194D01*
X2212667Y1344235D01*
X2212977Y1345485D01*
X2212667Y1346735D01*
X2211892Y1347777D01*
X2210497Y1348402D01*
X2209102Y1348194D01*
X2207707Y1347360D01*
G01X2222277Y1348402D02*
X2221037Y1347985D01*
X2220107Y1346944D01*
X2219487Y1345694D01*
X2219022Y1344027D01*
X2218867Y1342152D01*
X2219022Y1340277D01*
X2219487Y1338610D01*
X2220107Y1337360D01*
X2221037Y1336319D01*
X2222277Y1335902D01*
X2223517Y1336319D01*
X2224447Y1337360D01*
X2225067Y1338610D01*
X2225532Y1340277D01*
X2225687Y1342152D01*
X2225532Y1344027D01*
X2225067Y1345694D01*
X2224447Y1346944D01*
X2223517Y1347985D01*
X2222277Y1348402D01*
G01X2234677Y1335485D02*
X2234367Y1335694D01*
Y1336110D01*
X2234677Y1336319D01*
X2234987Y1336110D01*
Y1335694D01*
X2234677Y1335485D01*
G01X2247077Y1348402D02*
X2245837Y1347985D01*
X2244907Y1346944D01*
X2244287Y1345694D01*
X2243822Y1344027D01*
X2243667Y1342152D01*
X2243822Y1340277D01*
X2244287Y1338610D01*
X2244907Y1337360D01*
X2245837Y1336319D01*
X2247077Y1335902D01*
X2248317Y1336319D01*
X2249247Y1337360D01*
X2249867Y1338610D01*
X2250332Y1340277D01*
X2250487Y1342152D01*
X2250332Y1344027D01*
X2249867Y1345694D01*
X2249247Y1346944D01*
X2248317Y1347985D01*
X2247077Y1348402D01*
G01X2200732Y1379919D02*
X2201662Y1381168D01*
X2202747Y1381794D01*
X2203987Y1382002D01*
X2205537Y1381585D01*
X2206622Y1380544D01*
X2206932Y1379294D01*
X2206777Y1378043D01*
X2206157Y1377002D01*
X2203057Y1374919D01*
X2201662Y1373460D01*
X2200732Y1371377D01*
X2200422Y1369502D01*
X2206932D01*
G01X2213442Y1370960D02*
X2214527Y1369919D01*
X2215767Y1369502D01*
X2217007Y1369919D01*
X2218092Y1371168D01*
X2218867Y1373044D01*
X2219177Y1374919D01*
Y1377210D01*
X2218867Y1379085D01*
X2218092Y1380752D01*
X2217162Y1381585D01*
X2216077Y1382002D01*
X2214837Y1381585D01*
X2213907Y1380752D01*
X2213287Y1379502D01*
X2212977Y1377835D01*
X2213287Y1376377D01*
X2214062Y1374919D01*
X2214992Y1374085D01*
X2216077Y1373877D01*
X2217317Y1374293D01*
X2218247Y1375335D01*
X2219177Y1377210D01*
G01X2228477Y1369085D02*
X2228167Y1369294D01*
Y1369710D01*
X2228477Y1369919D01*
X2228787Y1369710D01*
Y1369294D01*
X2228477Y1369085D01*
G01X2237467Y1371377D02*
X2238397Y1370335D01*
X2239482Y1369710D01*
X2240877Y1369502D01*
X2242272Y1369919D01*
X2243357Y1370752D01*
X2244132Y1372210D01*
X2244287Y1373877D01*
X2243977Y1375544D01*
X2243202Y1376585D01*
X2242117Y1377419D01*
X2241032Y1377627D01*
X2239947Y1377419D01*
X2238552Y1376585D01*
X2239017Y1382002D01*
X2243202D01*
G01X2250332Y1379919D02*
X2251262Y1381168D01*
X2252347Y1381794D01*
X2253587Y1382002D01*
X2255137Y1381585D01*
X2256222Y1380544D01*
X2256532Y1379294D01*
X2256377Y1378043D01*
X2255757Y1377002D01*
X2252657Y1374919D01*
X2251262Y1373460D01*
X2250332Y1371377D01*
X2250022Y1369502D01*
X2256532D01*
G01X2206932Y1413519D02*
X2207862Y1414768D01*
X2208947Y1415394D01*
X2210187Y1415602D01*
X2211737Y1415185D01*
X2212822Y1414144D01*
X2213132Y1412894D01*
X2212977Y1411643D01*
X2212357Y1410602D01*
X2209257Y1408519D01*
X2207862Y1407060D01*
X2206932Y1404977D01*
X2206622Y1403102D01*
X2213132D01*
G01X2219332Y1408310D02*
X2220417Y1409769D01*
X2221347Y1410602D01*
X2222587Y1411019D01*
X2223672Y1410602D01*
X2224447Y1409769D01*
X2225067Y1408519D01*
X2225222Y1407060D01*
X2225067Y1405810D01*
X2224447Y1404560D01*
X2223517Y1403519D01*
X2222432Y1403102D01*
X2221192Y1403519D01*
X2220107Y1404768D01*
X2219487Y1406644D01*
X2219332Y1408727D01*
X2219642Y1411435D01*
X2220107Y1412894D01*
X2220882Y1414352D01*
X2221967Y1415394D01*
X2223052Y1415602D01*
X2224137Y1415185D01*
X2224912Y1414144D01*
G01X2234677Y1402685D02*
X2234367Y1402894D01*
Y1403310D01*
X2234677Y1403519D01*
X2234987Y1403310D01*
Y1402894D01*
X2234677Y1402685D01*
G01X2247077Y1415602D02*
X2245837Y1415185D01*
X2244907Y1414144D01*
X2244287Y1412894D01*
X2243822Y1411227D01*
X2243667Y1409352D01*
X2243822Y1407477D01*
X2244287Y1405810D01*
X2244907Y1404560D01*
X2245837Y1403519D01*
X2247077Y1403102D01*
X2248317Y1403519D01*
X2249247Y1404560D01*
X2249867Y1405810D01*
X2250332Y1407477D01*
X2250487Y1409352D01*
X2250332Y1411227D01*
X2249867Y1412894D01*
X2249247Y1414144D01*
X2248317Y1415185D01*
X2247077Y1415602D01*
G01X2206932Y1447119D02*
X2207862Y1448368D01*
X2208947Y1448994D01*
X2210187Y1449202D01*
X2211737Y1448785D01*
X2212822Y1447744D01*
X2213132Y1446494D01*
X2212977Y1445243D01*
X2212357Y1444202D01*
X2209257Y1442119D01*
X2207862Y1440660D01*
X2206932Y1438577D01*
X2206622Y1436702D01*
X2213132D01*
G01X2224137D02*
Y1449202D01*
X2218402Y1440244D01*
X2226152D01*
G01X2234677Y1436285D02*
X2234367Y1436494D01*
Y1436910D01*
X2234677Y1437119D01*
X2234987Y1436910D01*
Y1436494D01*
X2234677Y1436285D01*
G01X2247077Y1449202D02*
X2245837Y1448785D01*
X2244907Y1447744D01*
X2244287Y1446494D01*
X2243822Y1444827D01*
X2243667Y1442952D01*
X2243822Y1441077D01*
X2244287Y1439410D01*
X2244907Y1438160D01*
X2245837Y1437119D01*
X2247077Y1436702D01*
X2248317Y1437119D01*
X2249247Y1438160D01*
X2249867Y1439410D01*
X2250332Y1441077D01*
X2250487Y1442952D01*
X2250332Y1444827D01*
X2249867Y1446494D01*
X2249247Y1447744D01*
X2248317Y1448785D01*
X2247077Y1449202D01*
G01X2206932Y1480719D02*
X2207862Y1481968D01*
X2208947Y1482594D01*
X2210187Y1482802D01*
X2211737Y1482385D01*
X2212822Y1481344D01*
X2213132Y1480094D01*
X2212977Y1478843D01*
X2212357Y1477802D01*
X2209257Y1475719D01*
X2207862Y1474260D01*
X2206932Y1472177D01*
X2206622Y1470302D01*
X2213132D01*
G01X2219332Y1480719D02*
X2220262Y1481968D01*
X2221347Y1482594D01*
X2222587Y1482802D01*
X2224137Y1482385D01*
X2225222Y1481344D01*
X2225532Y1480094D01*
X2225377Y1478843D01*
X2224757Y1477802D01*
X2221657Y1475719D01*
X2220262Y1474260D01*
X2219332Y1472177D01*
X2219022Y1470302D01*
X2225532D01*
G01X2234677Y1469885D02*
X2234367Y1470094D01*
Y1470510D01*
X2234677Y1470719D01*
X2234987Y1470510D01*
Y1470094D01*
X2234677Y1469885D01*
G01X2247077Y1482802D02*
X2245837Y1482385D01*
X2244907Y1481344D01*
X2244287Y1480094D01*
X2243822Y1478427D01*
X2243667Y1476552D01*
X2243822Y1474677D01*
X2244287Y1473010D01*
X2244907Y1471760D01*
X2245837Y1470719D01*
X2247077Y1470302D01*
X2248317Y1470719D01*
X2249247Y1471760D01*
X2249867Y1473010D01*
X2250332Y1474677D01*
X2250487Y1476552D01*
X2250332Y1478427D01*
X2249867Y1480094D01*
X2249247Y1481344D01*
X2248317Y1482385D01*
X2247077Y1482802D01*
G01X2203677Y1503902D02*
Y1516402D01*
X2201817Y1513902D01*
G01Y1503902D02*
X2205537D01*
G01X2213442Y1505360D02*
X2214527Y1504319D01*
X2215767Y1503902D01*
X2217007Y1504319D01*
X2218092Y1505568D01*
X2218867Y1507444D01*
X2219177Y1509319D01*
Y1511610D01*
X2218867Y1513485D01*
X2218092Y1515152D01*
X2217162Y1515985D01*
X2216077Y1516402D01*
X2214837Y1515985D01*
X2213907Y1515152D01*
X2213287Y1513902D01*
X2212977Y1512235D01*
X2213287Y1510777D01*
X2214062Y1509319D01*
X2214992Y1508485D01*
X2216077Y1508277D01*
X2217317Y1508693D01*
X2218247Y1509735D01*
X2219177Y1511610D01*
G01X2228477Y1503485D02*
X2228167Y1503694D01*
Y1504110D01*
X2228477Y1504319D01*
X2228787Y1504110D01*
Y1503694D01*
X2228477Y1503485D01*
G01X2237932Y1509110D02*
X2239017Y1510569D01*
X2239947Y1511402D01*
X2241187Y1511819D01*
X2242272Y1511402D01*
X2243047Y1510569D01*
X2243667Y1509319D01*
X2243822Y1507860D01*
X2243667Y1506610D01*
X2243047Y1505360D01*
X2242117Y1504319D01*
X2241032Y1503902D01*
X2239792Y1504319D01*
X2238707Y1505568D01*
X2238087Y1507444D01*
X2237932Y1509527D01*
X2238242Y1512235D01*
X2238707Y1513694D01*
X2239482Y1515152D01*
X2240567Y1516194D01*
X2241652Y1516402D01*
X2242737Y1515985D01*
X2243512Y1514944D01*
G01X2253277Y1503902D02*
X2254362Y1504110D01*
X2255602Y1504735D01*
X2256377Y1505777D01*
X2256687Y1507235D01*
X2256377Y1508693D01*
X2255447Y1509944D01*
X2254052Y1510569D01*
X2252502D01*
X2251572Y1510985D01*
X2250797Y1512027D01*
X2250487Y1513485D01*
X2250952Y1514944D01*
X2252037Y1515985D01*
X2253277Y1516402D01*
X2254517Y1515985D01*
X2255602Y1514944D01*
X2256067Y1513485D01*
X2255757Y1512027D01*
X2254982Y1510985D01*
X2254052Y1510569D01*
X2252502D01*
X2251107Y1509944D01*
X2250177Y1508693D01*
X2249867Y1507235D01*
X2250177Y1505777D01*
X2250952Y1504735D01*
X2252192Y1504110D01*
X2253277Y1503902D01*
G01X2209877Y1537502D02*
Y1550002D01*
X2208017Y1547502D01*
G01Y1537502D02*
X2211737D01*
G01X2222277D02*
X2223362Y1537710D01*
X2224602Y1538335D01*
X2225377Y1539377D01*
X2225687Y1540835D01*
X2225377Y1542293D01*
X2224447Y1543544D01*
X2223052Y1544169D01*
X2221502D01*
X2220572Y1544585D01*
X2219797Y1545627D01*
X2219487Y1547085D01*
X2219952Y1548544D01*
X2221037Y1549585D01*
X2222277Y1550002D01*
X2223517Y1549585D01*
X2224602Y1548544D01*
X2225067Y1547085D01*
X2224757Y1545627D01*
X2223982Y1544585D01*
X2223052Y1544169D01*
X2221502D01*
X2220107Y1543544D01*
X2219177Y1542293D01*
X2218867Y1540835D01*
X2219177Y1539377D01*
X2219952Y1538335D01*
X2221192Y1537710D01*
X2222277Y1537502D01*
G01X2234677Y1537085D02*
X2234367Y1537294D01*
Y1537710D01*
X2234677Y1537919D01*
X2234987Y1537710D01*
Y1537294D01*
X2234677Y1537085D01*
G01X2247077Y1550002D02*
X2245837Y1549585D01*
X2244907Y1548544D01*
X2244287Y1547294D01*
X2243822Y1545627D01*
X2243667Y1543752D01*
X2243822Y1541877D01*
X2244287Y1540210D01*
X2244907Y1538960D01*
X2245837Y1537919D01*
X2247077Y1537502D01*
X2248317Y1537919D01*
X2249247Y1538960D01*
X2249867Y1540210D01*
X2250332Y1541877D01*
X2250487Y1543752D01*
X2250332Y1545627D01*
X2249867Y1547294D01*
X2249247Y1548544D01*
X2248317Y1549585D01*
X2247077Y1550002D01*
G01X2209877Y1571102D02*
Y1583602D01*
X2208017Y1581102D01*
G01Y1571102D02*
X2211737D01*
G01X2219332Y1576310D02*
X2220417Y1577769D01*
X2221347Y1578602D01*
X2222587Y1579019D01*
X2223672Y1578602D01*
X2224447Y1577769D01*
X2225067Y1576519D01*
X2225222Y1575060D01*
X2225067Y1573810D01*
X2224447Y1572560D01*
X2223517Y1571519D01*
X2222432Y1571102D01*
X2221192Y1571519D01*
X2220107Y1572768D01*
X2219487Y1574644D01*
X2219332Y1576727D01*
X2219642Y1579435D01*
X2220107Y1580894D01*
X2220882Y1582352D01*
X2221967Y1583394D01*
X2223052Y1583602D01*
X2224137Y1583185D01*
X2224912Y1582144D01*
G01X2234677Y1570685D02*
X2234367Y1570894D01*
Y1571310D01*
X2234677Y1571519D01*
X2234987Y1571310D01*
Y1570894D01*
X2234677Y1570685D01*
G01X2247077Y1583602D02*
X2245837Y1583185D01*
X2244907Y1582144D01*
X2244287Y1580894D01*
X2243822Y1579227D01*
X2243667Y1577352D01*
X2243822Y1575477D01*
X2244287Y1573810D01*
X2244907Y1572560D01*
X2245837Y1571519D01*
X2247077Y1571102D01*
X2248317Y1571519D01*
X2249247Y1572560D01*
X2249867Y1573810D01*
X2250332Y1575477D01*
X2250487Y1577352D01*
X2250332Y1579227D01*
X2249867Y1580894D01*
X2249247Y1582144D01*
X2248317Y1583185D01*
X2247077Y1583602D01*
G01X2203677Y1604702D02*
Y1617202D01*
X2201817Y1614702D01*
G01Y1604702D02*
X2205537D01*
G01X2212667Y1606577D02*
X2213597Y1605535D01*
X2214682Y1604910D01*
X2216077Y1604702D01*
X2217472Y1605119D01*
X2218557Y1605952D01*
X2219332Y1607410D01*
X2219487Y1609077D01*
X2219177Y1610744D01*
X2218402Y1611785D01*
X2217317Y1612619D01*
X2216232Y1612827D01*
X2215147Y1612619D01*
X2213752Y1611785D01*
X2214217Y1617202D01*
X2218402D01*
G01X2228477Y1604285D02*
X2228167Y1604494D01*
Y1604910D01*
X2228477Y1605119D01*
X2228787Y1604910D01*
Y1604494D01*
X2228477Y1604285D01*
G01X2240567Y1604702D02*
X2240877Y1607410D01*
X2241342Y1609702D01*
X2241962Y1611785D01*
X2242737Y1614077D01*
X2243977Y1617202D01*
X2237777D01*
G01X2255137Y1604702D02*
Y1617202D01*
X2249402Y1608244D01*
X2257152D01*
G01X2209877Y1638302D02*
Y1650802D01*
X2208017Y1648302D01*
G01Y1638302D02*
X2211737D01*
G01X2218867Y1640177D02*
X2219797Y1639135D01*
X2220882Y1638510D01*
X2222277Y1638302D01*
X2223672Y1638719D01*
X2224757Y1639552D01*
X2225532Y1641010D01*
X2225687Y1642677D01*
X2225377Y1644344D01*
X2224602Y1645385D01*
X2223517Y1646219D01*
X2222432Y1646427D01*
X2221347Y1646219D01*
X2219952Y1645385D01*
X2220417Y1650802D01*
X2224602D01*
G01X2234677Y1637885D02*
X2234367Y1638094D01*
Y1638510D01*
X2234677Y1638719D01*
X2234987Y1638510D01*
Y1638094D01*
X2234677Y1637885D01*
G01X2247077Y1650802D02*
X2245837Y1650385D01*
X2244907Y1649344D01*
X2244287Y1648094D01*
X2243822Y1646427D01*
X2243667Y1644552D01*
X2243822Y1642677D01*
X2244287Y1641010D01*
X2244907Y1639760D01*
X2245837Y1638719D01*
X2247077Y1638302D01*
X2248317Y1638719D01*
X2249247Y1639760D01*
X2249867Y1641010D01*
X2250332Y1642677D01*
X2250487Y1644552D01*
X2250332Y1646427D01*
X2249867Y1648094D01*
X2249247Y1649344D01*
X2248317Y1650385D01*
X2247077Y1650802D01*
G01X2209877Y1671902D02*
Y1684402D01*
X2208017Y1681902D01*
G01Y1671902D02*
X2211737D01*
G01X2219332Y1682319D02*
X2220262Y1683568D01*
X2221347Y1684194D01*
X2222587Y1684402D01*
X2224137Y1683985D01*
X2225222Y1682944D01*
X2225532Y1681694D01*
X2225377Y1680443D01*
X2224757Y1679402D01*
X2221657Y1677319D01*
X2220262Y1675860D01*
X2219332Y1673777D01*
X2219022Y1671902D01*
X2225532D01*
G01X2234677Y1671485D02*
X2234367Y1671694D01*
Y1672110D01*
X2234677Y1672319D01*
X2234987Y1672110D01*
Y1671694D01*
X2234677Y1671485D01*
G01X2247077Y1684402D02*
X2245837Y1683985D01*
X2244907Y1682944D01*
X2244287Y1681694D01*
X2243822Y1680027D01*
X2243667Y1678152D01*
X2243822Y1676277D01*
X2244287Y1674610D01*
X2244907Y1673360D01*
X2245837Y1672319D01*
X2247077Y1671902D01*
X2248317Y1672319D01*
X2249247Y1673360D01*
X2249867Y1674610D01*
X2250332Y1676277D01*
X2250487Y1678152D01*
X2250332Y1680027D01*
X2249867Y1681694D01*
X2249247Y1682944D01*
X2248317Y1683985D01*
X2247077Y1684402D01*
G01X2209877Y1705502D02*
Y1718002D01*
X2208017Y1715502D01*
G01Y1705502D02*
X2211737D01*
G01X2219332Y1715919D02*
X2220262Y1717168D01*
X2221347Y1717794D01*
X2222587Y1718002D01*
X2224137Y1717585D01*
X2225222Y1716544D01*
X2225532Y1715294D01*
X2225377Y1714043D01*
X2224757Y1713002D01*
X2221657Y1710919D01*
X2220262Y1709460D01*
X2219332Y1707377D01*
X2219022Y1705502D01*
X2225532D01*
G01X2234677Y1705085D02*
X2234367Y1705294D01*
Y1705710D01*
X2234677Y1705919D01*
X2234987Y1705710D01*
Y1705294D01*
X2234677Y1705085D01*
G01X2247077Y1718002D02*
X2245837Y1717585D01*
X2244907Y1716544D01*
X2244287Y1715294D01*
X2243822Y1713627D01*
X2243667Y1711752D01*
X2243822Y1709877D01*
X2244287Y1708210D01*
X2244907Y1706960D01*
X2245837Y1705919D01*
X2247077Y1705502D01*
X2248317Y1705919D01*
X2249247Y1706960D01*
X2249867Y1708210D01*
X2250332Y1709877D01*
X2250487Y1711752D01*
X2250332Y1713627D01*
X2249867Y1715294D01*
X2249247Y1716544D01*
X2248317Y1717585D01*
X2247077Y1718002D01*
G01X2209877Y1739102D02*
Y1751602D01*
X2208017Y1749102D01*
G01Y1739102D02*
X2211737D01*
G01X2222277Y1751602D02*
X2221037Y1751185D01*
X2220107Y1750144D01*
X2219487Y1748894D01*
X2219022Y1747227D01*
X2218867Y1745352D01*
X2219022Y1743477D01*
X2219487Y1741810D01*
X2220107Y1740560D01*
X2221037Y1739519D01*
X2222277Y1739102D01*
X2223517Y1739519D01*
X2224447Y1740560D01*
X2225067Y1741810D01*
X2225532Y1743477D01*
X2225687Y1745352D01*
X2225532Y1747227D01*
X2225067Y1748894D01*
X2224447Y1750144D01*
X2223517Y1751185D01*
X2222277Y1751602D01*
G01X2234677Y1738685D02*
X2234367Y1738894D01*
Y1739310D01*
X2234677Y1739519D01*
X2234987Y1739310D01*
Y1738894D01*
X2234677Y1738685D01*
G01X2247077Y1751602D02*
X2245837Y1751185D01*
X2244907Y1750144D01*
X2244287Y1748894D01*
X2243822Y1747227D01*
X2243667Y1745352D01*
X2243822Y1743477D01*
X2244287Y1741810D01*
X2244907Y1740560D01*
X2245837Y1739519D01*
X2247077Y1739102D01*
X2248317Y1739519D01*
X2249247Y1740560D01*
X2249867Y1741810D01*
X2250332Y1743477D01*
X2250487Y1745352D01*
X2250332Y1747227D01*
X2249867Y1748894D01*
X2249247Y1750144D01*
X2248317Y1751185D01*
X2247077Y1751602D01*
G01X2209877Y1772702D02*
Y1785202D01*
X2208017Y1782702D01*
G01Y1772702D02*
X2211737D01*
G01X2222277Y1785202D02*
X2221037Y1784785D01*
X2220107Y1783744D01*
X2219487Y1782494D01*
X2219022Y1780827D01*
X2218867Y1778952D01*
X2219022Y1777077D01*
X2219487Y1775410D01*
X2220107Y1774160D01*
X2221037Y1773119D01*
X2222277Y1772702D01*
X2223517Y1773119D01*
X2224447Y1774160D01*
X2225067Y1775410D01*
X2225532Y1777077D01*
X2225687Y1778952D01*
X2225532Y1780827D01*
X2225067Y1782494D01*
X2224447Y1783744D01*
X2223517Y1784785D01*
X2222277Y1785202D01*
G01X2234677Y1772285D02*
X2234367Y1772494D01*
Y1772910D01*
X2234677Y1773119D01*
X2234987Y1772910D01*
Y1772494D01*
X2234677Y1772285D01*
G01X2247077Y1785202D02*
X2245837Y1784785D01*
X2244907Y1783744D01*
X2244287Y1782494D01*
X2243822Y1780827D01*
X2243667Y1778952D01*
X2243822Y1777077D01*
X2244287Y1775410D01*
X2244907Y1774160D01*
X2245837Y1773119D01*
X2247077Y1772702D01*
X2248317Y1773119D01*
X2249247Y1774160D01*
X2249867Y1775410D01*
X2250332Y1777077D01*
X2250487Y1778952D01*
X2250332Y1780827D01*
X2249867Y1782494D01*
X2249247Y1783744D01*
X2248317Y1784785D01*
X2247077Y1785202D01*
G01X2194377Y1839902D02*
X2188177D01*
Y1852402D01*
X2194377D01*
G01X2191897Y1846360D02*
X2188177D01*
G01X2200577Y1852402D02*
Y1839902D01*
X2206777D01*
G01X2212977Y1852402D02*
Y1839902D01*
X2219177D01*
G01X2226617Y1852402D02*
X2230337D01*
G01X2228477D02*
Y1839902D01*
G01X2226617D02*
X2230337D01*
G01X2237777D02*
Y1852402D01*
X2241497D01*
X2242737Y1851777D01*
X2243667Y1850319D01*
X2243977Y1848652D01*
X2243667Y1846985D01*
X2242892Y1845735D01*
X2241497Y1845110D01*
X2237777D01*
G01X2250022Y1841568D02*
X2251262Y1840527D01*
X2252657Y1839902D01*
X2253897D01*
X2255137Y1840527D01*
X2256067Y1841568D01*
X2256532Y1843027D01*
X2256222Y1844485D01*
X2255447Y1845735D01*
X2254052Y1846569D01*
X2252192Y1846985D01*
X2251107Y1847819D01*
X2250642Y1849277D01*
X2250952Y1850735D01*
X2251727Y1851777D01*
X2252812Y1852402D01*
X2253897D01*
X2254982Y1851985D01*
X2255912Y1850944D01*
G01X2268777Y1839902D02*
X2262577D01*
Y1852402D01*
X2268777D01*
G01X2266297Y1846360D02*
X2262577D01*
G01X2206622Y1870868D02*
X2207862Y1869827D01*
X2209257Y1869202D01*
X2210497D01*
X2211737Y1869827D01*
X2212667Y1870868D01*
X2213132Y1872327D01*
X2212822Y1873785D01*
X2212047Y1875035D01*
X2210652Y1875869D01*
X2208792Y1876285D01*
X2207707Y1877119D01*
X2207242Y1878577D01*
X2207552Y1880035D01*
X2208327Y1881077D01*
X2209412Y1881702D01*
X2210497D01*
X2211582Y1881285D01*
X2212512Y1880244D01*
G01X2220417Y1881702D02*
X2224137D01*
G01X2222277D02*
Y1869202D01*
G01X2220417D02*
X2224137D01*
G01X2231732Y1881702D02*
X2237622D01*
X2231732Y1869202D01*
X2237622D01*
G01X2250177D02*
X2243977D01*
Y1881702D01*
X2250177D01*
G01X2247697Y1875660D02*
X2243977D01*
G01X2216077Y1806302D02*
X2217162Y1806510D01*
X2218402Y1807135D01*
X2219177Y1808177D01*
X2219487Y1809635D01*
X2219177Y1811093D01*
X2218247Y1812344D01*
X2216852Y1812969D01*
X2215302D01*
X2214372Y1813385D01*
X2213597Y1814427D01*
X2213287Y1815885D01*
X2213752Y1817344D01*
X2214837Y1818385D01*
X2216077Y1818802D01*
X2217317Y1818385D01*
X2218402Y1817344D01*
X2218867Y1815885D01*
X2218557Y1814427D01*
X2217782Y1813385D01*
X2216852Y1812969D01*
X2215302D01*
X2213907Y1812344D01*
X2212977Y1811093D01*
X2212667Y1809635D01*
X2212977Y1808177D01*
X2213752Y1807135D01*
X2214992Y1806510D01*
X2216077Y1806302D01*
G01X2228477Y1805885D02*
X2228167Y1806094D01*
Y1806510D01*
X2228477Y1806719D01*
X2228787Y1806510D01*
Y1806094D01*
X2228477Y1805885D01*
G01X2240877Y1818802D02*
X2239637Y1818385D01*
X2238707Y1817344D01*
X2238087Y1816094D01*
X2237622Y1814427D01*
X2237467Y1812552D01*
X2237622Y1810677D01*
X2238087Y1809010D01*
X2238707Y1807760D01*
X2239637Y1806719D01*
X2240877Y1806302D01*
X2242117Y1806719D01*
X2243047Y1807760D01*
X2243667Y1809010D01*
X2244132Y1810677D01*
X2244287Y1812552D01*
X2244132Y1814427D01*
X2243667Y1816094D01*
X2243047Y1817344D01*
X2242117Y1818385D01*
X2240877Y1818802D01*
G01X2252502Y1894202D02*
X2256377Y1906702D01*
X2260252Y1894202D01*
G01X2258857Y1898577D02*
X2253897D01*
G01X2265677Y1906702D02*
Y1894202D01*
X2271877D01*
G01X2278077Y1906702D02*
Y1894202D01*
X2284277D01*
G01X2302567Y1906702D02*
Y1897744D01*
X2303187Y1895868D01*
X2304427Y1894619D01*
X2305977Y1894202D01*
X2307527Y1894619D01*
X2308767Y1895868D01*
X2309387Y1897744D01*
Y1906702D01*
G01X2314812Y1894202D02*
Y1906702D01*
X2321942Y1894202D01*
Y1906702D01*
G01X2328917D02*
X2332637D01*
G01X2330777D02*
Y1894202D01*
G01X2328917D02*
X2332637D01*
G01X2343177Y1906702D02*
Y1894202D01*
G01X2339612Y1906702D02*
X2346742D01*
G01X2352322Y1895868D02*
X2353562Y1894827D01*
X2354957Y1894202D01*
X2356197D01*
X2357437Y1894827D01*
X2358367Y1895868D01*
X2358832Y1897327D01*
X2358522Y1898785D01*
X2357747Y1900035D01*
X2356352Y1900869D01*
X2354492Y1901285D01*
X2353407Y1902119D01*
X2352942Y1903577D01*
X2353252Y1905035D01*
X2354027Y1906077D01*
X2355112Y1906702D01*
X2356197D01*
X2357282Y1906285D01*
X2358212Y1905244D01*
G01X2376502Y1894202D02*
X2380377Y1906702D01*
X2384252Y1894202D01*
G01X2382857Y1898577D02*
X2377897D01*
G01X2389677Y1894202D02*
Y1906702D01*
X2393552D01*
X2394792Y1906077D01*
X2395567Y1905244D01*
X2395877Y1903577D01*
X2395567Y1901910D01*
X2394637Y1900869D01*
X2393552Y1900244D01*
X2389677D01*
G01X2393552D02*
X2395877Y1894202D01*
G01X2408277D02*
X2402077D01*
Y1906702D01*
X2408277D01*
G01X2405797Y1900660D02*
X2402077D01*
G01X2428117Y1906702D02*
X2431837D01*
G01X2429977D02*
Y1894202D01*
G01X2428117D02*
X2431837D01*
G01X2438812D02*
Y1906702D01*
X2445942Y1894202D01*
Y1906702D01*
G01X2463147Y1894202D02*
Y1906702D01*
X2467177Y1896285D01*
X2471207Y1906702D01*
Y1894202D01*
G01X2477717Y1906702D02*
X2481437D01*
G01X2479577D02*
Y1894202D01*
G01X2477717D02*
X2481437D01*
G01X2488877Y1906702D02*
Y1894202D01*
X2495077D01*
G01X2501122Y1895868D02*
X2502362Y1894827D01*
X2503757Y1894202D01*
X2504997D01*
X2506237Y1894827D01*
X2507167Y1895868D01*
X2507632Y1897327D01*
X2507322Y1898785D01*
X2506547Y1900035D01*
X2505152Y1900869D01*
X2503292Y1901285D01*
X2502207Y1902119D01*
X2501742Y1903577D01*
X2502052Y1905035D01*
X2502827Y1906077D01*
X2503912Y1906702D01*
X2504997D01*
X2506082Y1906285D01*
X2507012Y1905244D01*
G01X2221967Y1919202D02*
Y1931702D01*
X2225067D01*
X2226307Y1931077D01*
X2227237Y1930244D01*
X2228012Y1928994D01*
X2228632Y1927535D01*
X2228787Y1925452D01*
X2228632Y1923369D01*
X2228012Y1921910D01*
X2227237Y1920660D01*
X2226307Y1919827D01*
X2225067Y1919202D01*
X2221967D01*
G01X2234677D02*
Y1931702D01*
X2238552D01*
X2239792Y1931077D01*
X2240567Y1930244D01*
X2240877Y1928577D01*
X2240567Y1926910D01*
X2239637Y1925869D01*
X2238552Y1925244D01*
X2234677D01*
G01X2238552D02*
X2240877Y1919202D01*
G01X2248317Y1931702D02*
X2252037D01*
G01X2250177D02*
Y1919202D01*
G01X2248317D02*
X2252037D01*
G01X2259477Y1931702D02*
Y1919202D01*
X2265677D01*
G01X2271877Y1931702D02*
Y1919202D01*
X2278077D01*
G01X2303187Y1930660D02*
X2302257Y1931285D01*
X2301172Y1931702D01*
X2299932D01*
X2298537Y1931077D01*
X2297452Y1930035D01*
X2296677Y1928785D01*
X2296057Y1926702D01*
X2295902Y1924827D01*
X2296212Y1922952D01*
X2296677Y1921702D01*
X2297607Y1920452D01*
X2298692Y1919619D01*
X2299777Y1919202D01*
X2300862D01*
X2301947Y1919619D01*
X2302877Y1920243D01*
X2303652Y1921077D01*
G01X2308922Y1919202D02*
Y1931702D01*
G01X2315432D02*
Y1919202D01*
G01Y1925452D02*
X2308922D01*
G01X2320702Y1919202D02*
X2324577Y1931702D01*
X2328452Y1919202D01*
G01X2327057Y1923577D02*
X2322097D01*
G01X2333877Y1919202D02*
Y1931702D01*
X2337752D01*
X2338992Y1931077D01*
X2339767Y1930244D01*
X2340077Y1928577D01*
X2339767Y1926910D01*
X2338837Y1925869D01*
X2337752Y1925244D01*
X2333877D01*
G01X2337752D02*
X2340077Y1919202D01*
G01X2349377Y1931702D02*
Y1919202D01*
G01X2345812Y1931702D02*
X2352942D01*
G01X2361777Y1918785D02*
X2361467Y1918994D01*
Y1919410D01*
X2361777Y1919619D01*
X2362087Y1919410D01*
Y1918994D01*
X2361777Y1918785D01*
G01Y1924410D02*
X2361467Y1924619D01*
Y1925035D01*
X2361777Y1925244D01*
X2362087Y1925035D01*
Y1924619D01*
X2361777Y1924410D01*
G01X2386577Y1931702D02*
Y1919202D01*
G01X2383012Y1931702D02*
X2390142D01*
G01X2398977Y1919202D02*
X2397737Y1919410D01*
X2396652Y1920243D01*
X2395722Y1921494D01*
X2395102Y1922952D01*
X2394792Y1924619D01*
Y1926285D01*
X2395102Y1927952D01*
X2395722Y1929410D01*
X2396652Y1930660D01*
X2397737Y1931494D01*
X2398977Y1931702D01*
X2400217Y1931494D01*
X2401302Y1930660D01*
X2402232Y1929410D01*
X2402852Y1927952D01*
X2403162Y1926285D01*
Y1924619D01*
X2402852Y1922952D01*
X2402232Y1921494D01*
X2401302Y1920243D01*
X2400217Y1919410D01*
X2398977Y1919202D01*
G01X2408277D02*
Y1931702D01*
X2411997D01*
X2413237Y1931077D01*
X2414167Y1929619D01*
X2414477Y1927952D01*
X2414167Y1926285D01*
X2413392Y1925035D01*
X2411997Y1924410D01*
X2408277D01*
G01X2436177Y1931702D02*
Y1919202D01*
G01X2434007Y1927535D02*
X2438347D01*
G01X2448577Y1919202D02*
X2447647Y1919410D01*
X2446717Y1920243D01*
X2446097Y1921702D01*
X2445787Y1923369D01*
X2446097Y1925035D01*
X2446717Y1926494D01*
X2447647Y1927327D01*
X2448577Y1927535D01*
X2449507Y1927327D01*
X2450437Y1926494D01*
X2451057Y1925035D01*
X2451212Y1923369D01*
X2451057Y1921702D01*
X2450437Y1920243D01*
X2449507Y1919410D01*
X2448577Y1919202D01*
G01X2474617Y1925869D02*
X2475237Y1926494D01*
X2475702Y1927535D01*
X2476012Y1928994D01*
X2475702Y1930244D01*
X2475082Y1931077D01*
X2473997Y1931702D01*
X2469812D01*
Y1919202D01*
X2474927D01*
X2476012Y1920035D01*
X2476632Y1921285D01*
X2476942Y1922744D01*
X2476632Y1924202D01*
X2475702Y1925452D01*
X2474617Y1925869D01*
X2469812D01*
G01X2485777Y1919202D02*
X2484537Y1919410D01*
X2483452Y1920243D01*
X2482522Y1921494D01*
X2481902Y1922952D01*
X2481592Y1924619D01*
Y1926285D01*
X2481902Y1927952D01*
X2482522Y1929410D01*
X2483452Y1930660D01*
X2484537Y1931494D01*
X2485777Y1931702D01*
X2487017Y1931494D01*
X2488102Y1930660D01*
X2489032Y1929410D01*
X2489652Y1927952D01*
X2489962Y1926285D01*
Y1924619D01*
X2489652Y1922952D01*
X2489032Y1921494D01*
X2488102Y1920243D01*
X2487017Y1919410D01*
X2485777Y1919202D01*
G01X2498177Y1931702D02*
Y1919202D01*
G01X2494612Y1931702D02*
X2501742D01*
G01X2510577D02*
Y1919202D01*
G01X2507012Y1931702D02*
X2514142D01*
G01X2522977Y1919202D02*
X2521737Y1919410D01*
X2520652Y1920243D01*
X2519722Y1921494D01*
X2519102Y1922952D01*
X2518792Y1924619D01*
Y1926285D01*
X2519102Y1927952D01*
X2519722Y1929410D01*
X2520652Y1930660D01*
X2521737Y1931494D01*
X2522977Y1931702D01*
X2524217Y1931494D01*
X2525302Y1930660D01*
X2526232Y1929410D01*
X2526852Y1927952D01*
X2527162Y1926285D01*
Y1924619D01*
X2526852Y1922952D01*
X2526232Y1921494D01*
X2525302Y1920243D01*
X2524217Y1919410D01*
X2522977Y1919202D01*
G01X2531347D02*
Y1931702D01*
X2535377Y1921285D01*
X2539407Y1931702D01*
Y1919202D01*
G01X2323027Y1887952D02*
Y-287448D01*
G01X2366272Y-272731D02*
X2369992D01*
G01X2367977Y-270023D02*
Y-275440D01*
G01X2380377Y-264398D02*
X2379137Y-264815D01*
X2378207Y-265856D01*
X2377587Y-267106D01*
X2377122Y-268773D01*
X2376967Y-270648D01*
X2377122Y-272523D01*
X2377587Y-274190D01*
X2378207Y-275440D01*
X2379137Y-276481D01*
X2380377Y-276898D01*
X2381617Y-276481D01*
X2382547Y-275440D01*
X2383167Y-274190D01*
X2383632Y-272523D01*
X2383787Y-270648D01*
X2383632Y-268773D01*
X2383167Y-267106D01*
X2382547Y-265856D01*
X2381617Y-264815D01*
X2380377Y-264398D01*
G01X2392777Y-277315D02*
X2392467Y-277106D01*
Y-276690D01*
X2392777Y-276481D01*
X2393087Y-276690D01*
Y-277106D01*
X2392777Y-277315D01*
G01X2405177Y-264398D02*
X2403937Y-264815D01*
X2403007Y-265856D01*
X2402387Y-267106D01*
X2401922Y-268773D01*
X2401767Y-270648D01*
X2401922Y-272523D01*
X2402387Y-274190D01*
X2403007Y-275440D01*
X2403937Y-276481D01*
X2405177Y-276898D01*
X2406417Y-276481D01*
X2407347Y-275440D01*
X2407967Y-274190D01*
X2408432Y-272523D01*
X2408587Y-270648D01*
X2408432Y-268773D01*
X2407967Y-267106D01*
X2407347Y-265856D01*
X2406417Y-264815D01*
X2405177Y-264398D01*
G01X2414787Y-277315D02*
X2420367Y-264398D01*
G01X2427962Y-272731D02*
X2431992D01*
G01X2442377Y-264398D02*
X2441137Y-264815D01*
X2440207Y-265856D01*
X2439587Y-267106D01*
X2439122Y-268773D01*
X2438967Y-270648D01*
X2439122Y-272523D01*
X2439587Y-274190D01*
X2440207Y-275440D01*
X2441137Y-276481D01*
X2442377Y-276898D01*
X2443617Y-276481D01*
X2444547Y-275440D01*
X2445167Y-274190D01*
X2445632Y-272523D01*
X2445787Y-270648D01*
X2445632Y-268773D01*
X2445167Y-267106D01*
X2444547Y-265856D01*
X2443617Y-264815D01*
X2442377Y-264398D01*
G01X2454777Y-277315D02*
X2454467Y-277106D01*
Y-276690D01*
X2454777Y-276481D01*
X2455087Y-276690D01*
Y-277106D01*
X2454777Y-277315D01*
G01X2467177Y-264398D02*
X2465937Y-264815D01*
X2465007Y-265856D01*
X2464387Y-267106D01*
X2463922Y-268773D01*
X2463767Y-270648D01*
X2463922Y-272523D01*
X2464387Y-274190D01*
X2465007Y-275440D01*
X2465937Y-276481D01*
X2467177Y-276898D01*
X2468417Y-276481D01*
X2469347Y-275440D01*
X2469967Y-274190D01*
X2470432Y-272523D01*
X2470587Y-270648D01*
X2470432Y-268773D01*
X2469967Y-267106D01*
X2469347Y-265856D01*
X2468417Y-264815D01*
X2467177Y-264398D01*
G01X2366272Y-239131D02*
X2369992D01*
G01X2367977Y-236423D02*
Y-241840D01*
G01X2380377Y-230798D02*
X2379137Y-231215D01*
X2378207Y-232256D01*
X2377587Y-233506D01*
X2377122Y-235173D01*
X2376967Y-237048D01*
X2377122Y-238923D01*
X2377587Y-240590D01*
X2378207Y-241840D01*
X2379137Y-242881D01*
X2380377Y-243298D01*
X2381617Y-242881D01*
X2382547Y-241840D01*
X2383167Y-240590D01*
X2383632Y-238923D01*
X2383787Y-237048D01*
X2383632Y-235173D01*
X2383167Y-233506D01*
X2382547Y-232256D01*
X2381617Y-231215D01*
X2380377Y-230798D01*
G01X2392777Y-243715D02*
X2392467Y-243506D01*
Y-243090D01*
X2392777Y-242881D01*
X2393087Y-243090D01*
Y-243506D01*
X2392777Y-243715D01*
G01X2405177Y-230798D02*
X2403937Y-231215D01*
X2403007Y-232256D01*
X2402387Y-233506D01*
X2401922Y-235173D01*
X2401767Y-237048D01*
X2401922Y-238923D01*
X2402387Y-240590D01*
X2403007Y-241840D01*
X2403937Y-242881D01*
X2405177Y-243298D01*
X2406417Y-242881D01*
X2407347Y-241840D01*
X2407967Y-240590D01*
X2408432Y-238923D01*
X2408587Y-237048D01*
X2408432Y-235173D01*
X2407967Y-233506D01*
X2407347Y-232256D01*
X2406417Y-231215D01*
X2405177Y-230798D01*
G01X2414787Y-243715D02*
X2420367Y-230798D01*
G01X2427962Y-239131D02*
X2431992D01*
G01X2442377Y-230798D02*
X2441137Y-231215D01*
X2440207Y-232256D01*
X2439587Y-233506D01*
X2439122Y-235173D01*
X2438967Y-237048D01*
X2439122Y-238923D01*
X2439587Y-240590D01*
X2440207Y-241840D01*
X2441137Y-242881D01*
X2442377Y-243298D01*
X2443617Y-242881D01*
X2444547Y-241840D01*
X2445167Y-240590D01*
X2445632Y-238923D01*
X2445787Y-237048D01*
X2445632Y-235173D01*
X2445167Y-233506D01*
X2444547Y-232256D01*
X2443617Y-231215D01*
X2442377Y-230798D01*
G01X2454777Y-243715D02*
X2454467Y-243506D01*
Y-243090D01*
X2454777Y-242881D01*
X2455087Y-243090D01*
Y-243506D01*
X2454777Y-243715D01*
G01X2467177Y-230798D02*
X2465937Y-231215D01*
X2465007Y-232256D01*
X2464387Y-233506D01*
X2463922Y-235173D01*
X2463767Y-237048D01*
X2463922Y-238923D01*
X2464387Y-240590D01*
X2465007Y-241840D01*
X2465937Y-242881D01*
X2467177Y-243298D01*
X2468417Y-242881D01*
X2469347Y-241840D01*
X2469967Y-240590D01*
X2470432Y-238923D01*
X2470587Y-237048D01*
X2470432Y-235173D01*
X2469967Y-233506D01*
X2469347Y-232256D01*
X2468417Y-231215D01*
X2467177Y-230798D01*
G01X2366272Y-205531D02*
X2369992D01*
G01X2367977Y-202823D02*
Y-208240D01*
G01X2376967Y-207823D02*
X2377897Y-208865D01*
X2378982Y-209490D01*
X2380377Y-209698D01*
X2381772Y-209281D01*
X2382857Y-208448D01*
X2383632Y-206990D01*
X2383787Y-205323D01*
X2383477Y-203656D01*
X2382702Y-202615D01*
X2381617Y-201781D01*
X2380532Y-201573D01*
X2379447Y-201781D01*
X2378052Y-202615D01*
X2378517Y-197198D01*
X2382702D01*
G01X2392777Y-210115D02*
X2392467Y-209906D01*
Y-209490D01*
X2392777Y-209281D01*
X2393087Y-209490D01*
Y-209906D01*
X2392777Y-210115D01*
G01X2405177Y-197198D02*
X2403937Y-197615D01*
X2403007Y-198656D01*
X2402387Y-199906D01*
X2401922Y-201573D01*
X2401767Y-203448D01*
X2401922Y-205323D01*
X2402387Y-206990D01*
X2403007Y-208240D01*
X2403937Y-209281D01*
X2405177Y-209698D01*
X2406417Y-209281D01*
X2407347Y-208240D01*
X2407967Y-206990D01*
X2408432Y-205323D01*
X2408587Y-203448D01*
X2408432Y-201573D01*
X2407967Y-199906D01*
X2407347Y-198656D01*
X2406417Y-197615D01*
X2405177Y-197198D01*
G01X2414787Y-210115D02*
X2420367Y-197198D01*
G01X2427962Y-205531D02*
X2431992D01*
G01X2438967Y-207823D02*
X2439897Y-208865D01*
X2440982Y-209490D01*
X2442377Y-209698D01*
X2443772Y-209281D01*
X2444857Y-208448D01*
X2445632Y-206990D01*
X2445787Y-205323D01*
X2445477Y-203656D01*
X2444702Y-202615D01*
X2443617Y-201781D01*
X2442532Y-201573D01*
X2441447Y-201781D01*
X2440052Y-202615D01*
X2440517Y-197198D01*
X2444702D01*
G01X2454777Y-210115D02*
X2454467Y-209906D01*
Y-209490D01*
X2454777Y-209281D01*
X2455087Y-209490D01*
Y-209906D01*
X2454777Y-210115D01*
G01X2467177Y-197198D02*
X2465937Y-197615D01*
X2465007Y-198656D01*
X2464387Y-199906D01*
X2463922Y-201573D01*
X2463767Y-203448D01*
X2463922Y-205323D01*
X2464387Y-206990D01*
X2465007Y-208240D01*
X2465937Y-209281D01*
X2467177Y-209698D01*
X2468417Y-209281D01*
X2469347Y-208240D01*
X2469967Y-206990D01*
X2470432Y-205323D01*
X2470587Y-203448D01*
X2470432Y-201573D01*
X2469967Y-199906D01*
X2469347Y-198656D01*
X2468417Y-197615D01*
X2467177Y-197198D01*
G01X2366272Y-171931D02*
X2369992D01*
G01X2367977Y-169223D02*
Y-174640D01*
G01X2376967Y-173598D02*
X2377897Y-175057D01*
X2379137Y-175890D01*
X2380532Y-176098D01*
X2381772Y-175890D01*
X2383012Y-174848D01*
X2383787Y-173598D01*
X2383942Y-172348D01*
X2383632Y-170890D01*
X2382547Y-169848D01*
X2381462Y-169431D01*
X2380067D01*
G01X2381462D02*
X2382392Y-168806D01*
X2383167Y-167765D01*
X2383477Y-166515D01*
X2383167Y-165265D01*
X2382392Y-164223D01*
X2380997Y-163598D01*
X2379602Y-163806D01*
X2378207Y-164640D01*
G01X2392777Y-176515D02*
X2392467Y-176306D01*
Y-175890D01*
X2392777Y-175681D01*
X2393087Y-175890D01*
Y-176306D01*
X2392777Y-176515D01*
G01X2405177Y-163598D02*
X2403937Y-164015D01*
X2403007Y-165056D01*
X2402387Y-166306D01*
X2401922Y-167973D01*
X2401767Y-169848D01*
X2401922Y-171723D01*
X2402387Y-173390D01*
X2403007Y-174640D01*
X2403937Y-175681D01*
X2405177Y-176098D01*
X2406417Y-175681D01*
X2407347Y-174640D01*
X2407967Y-173390D01*
X2408432Y-171723D01*
X2408587Y-169848D01*
X2408432Y-167973D01*
X2407967Y-166306D01*
X2407347Y-165056D01*
X2406417Y-164015D01*
X2405177Y-163598D01*
G01X2414787Y-176515D02*
X2420367Y-163598D01*
G01X2427962Y-171931D02*
X2431992D01*
G01X2438967Y-173598D02*
X2439897Y-175057D01*
X2441137Y-175890D01*
X2442532Y-176098D01*
X2443772Y-175890D01*
X2445012Y-174848D01*
X2445787Y-173598D01*
X2445942Y-172348D01*
X2445632Y-170890D01*
X2444547Y-169848D01*
X2443462Y-169431D01*
X2442067D01*
G01X2443462D02*
X2444392Y-168806D01*
X2445167Y-167765D01*
X2445477Y-166515D01*
X2445167Y-165265D01*
X2444392Y-164223D01*
X2442997Y-163598D01*
X2441602Y-163806D01*
X2440207Y-164640D01*
G01X2454777Y-176515D02*
X2454467Y-176306D01*
Y-175890D01*
X2454777Y-175681D01*
X2455087Y-175890D01*
Y-176306D01*
X2454777Y-176515D01*
G01X2467177Y-163598D02*
X2465937Y-164015D01*
X2465007Y-165056D01*
X2464387Y-166306D01*
X2463922Y-167973D01*
X2463767Y-169848D01*
X2463922Y-171723D01*
X2464387Y-173390D01*
X2465007Y-174640D01*
X2465937Y-175681D01*
X2467177Y-176098D01*
X2468417Y-175681D01*
X2469347Y-174640D01*
X2469967Y-173390D01*
X2470432Y-171723D01*
X2470587Y-169848D01*
X2470432Y-167973D01*
X2469967Y-166306D01*
X2469347Y-165056D01*
X2468417Y-164015D01*
X2467177Y-163598D01*
G01X2366272Y-138331D02*
X2369992D01*
G01X2367977Y-135623D02*
Y-141040D01*
G01X2380377Y-129998D02*
X2379137Y-130415D01*
X2378207Y-131456D01*
X2377587Y-132706D01*
X2377122Y-134373D01*
X2376967Y-136248D01*
X2377122Y-138123D01*
X2377587Y-139790D01*
X2378207Y-141040D01*
X2379137Y-142081D01*
X2380377Y-142498D01*
X2381617Y-142081D01*
X2382547Y-141040D01*
X2383167Y-139790D01*
X2383632Y-138123D01*
X2383787Y-136248D01*
X2383632Y-134373D01*
X2383167Y-132706D01*
X2382547Y-131456D01*
X2381617Y-130415D01*
X2380377Y-129998D01*
G01X2392777Y-142915D02*
X2392467Y-142706D01*
Y-142290D01*
X2392777Y-142081D01*
X2393087Y-142290D01*
Y-142706D01*
X2392777Y-142915D01*
G01X2405177Y-129998D02*
X2403937Y-130415D01*
X2403007Y-131456D01*
X2402387Y-132706D01*
X2401922Y-134373D01*
X2401767Y-136248D01*
X2401922Y-138123D01*
X2402387Y-139790D01*
X2403007Y-141040D01*
X2403937Y-142081D01*
X2405177Y-142498D01*
X2406417Y-142081D01*
X2407347Y-141040D01*
X2407967Y-139790D01*
X2408432Y-138123D01*
X2408587Y-136248D01*
X2408432Y-134373D01*
X2407967Y-132706D01*
X2407347Y-131456D01*
X2406417Y-130415D01*
X2405177Y-129998D01*
G01X2414787Y-142915D02*
X2420367Y-129998D01*
G01X2427962Y-138331D02*
X2431992D01*
G01X2442377Y-129998D02*
X2441137Y-130415D01*
X2440207Y-131456D01*
X2439587Y-132706D01*
X2439122Y-134373D01*
X2438967Y-136248D01*
X2439122Y-138123D01*
X2439587Y-139790D01*
X2440207Y-141040D01*
X2441137Y-142081D01*
X2442377Y-142498D01*
X2443617Y-142081D01*
X2444547Y-141040D01*
X2445167Y-139790D01*
X2445632Y-138123D01*
X2445787Y-136248D01*
X2445632Y-134373D01*
X2445167Y-132706D01*
X2444547Y-131456D01*
X2443617Y-130415D01*
X2442377Y-129998D01*
G01X2454777Y-142915D02*
X2454467Y-142706D01*
Y-142290D01*
X2454777Y-142081D01*
X2455087Y-142290D01*
Y-142706D01*
X2454777Y-142915D01*
G01X2467177Y-129998D02*
X2465937Y-130415D01*
X2465007Y-131456D01*
X2464387Y-132706D01*
X2463922Y-134373D01*
X2463767Y-136248D01*
X2463922Y-138123D01*
X2464387Y-139790D01*
X2465007Y-141040D01*
X2465937Y-142081D01*
X2467177Y-142498D01*
X2468417Y-142081D01*
X2469347Y-141040D01*
X2469967Y-139790D01*
X2470432Y-138123D01*
X2470587Y-136248D01*
X2470432Y-134373D01*
X2469967Y-132706D01*
X2469347Y-131456D01*
X2468417Y-130415D01*
X2467177Y-129998D01*
G01X2366272Y-104731D02*
X2369992D01*
G01X2367977Y-102023D02*
Y-107440D01*
G01X2380377Y-96398D02*
X2379137Y-96815D01*
X2378207Y-97856D01*
X2377587Y-99106D01*
X2377122Y-100773D01*
X2376967Y-102648D01*
X2377122Y-104523D01*
X2377587Y-106190D01*
X2378207Y-107440D01*
X2379137Y-108481D01*
X2380377Y-108898D01*
X2381617Y-108481D01*
X2382547Y-107440D01*
X2383167Y-106190D01*
X2383632Y-104523D01*
X2383787Y-102648D01*
X2383632Y-100773D01*
X2383167Y-99106D01*
X2382547Y-97856D01*
X2381617Y-96815D01*
X2380377Y-96398D01*
G01X2392777Y-109315D02*
X2392467Y-109106D01*
Y-108690D01*
X2392777Y-108481D01*
X2393087Y-108690D01*
Y-109106D01*
X2392777Y-109315D01*
G01X2405177Y-96398D02*
X2403937Y-96815D01*
X2403007Y-97856D01*
X2402387Y-99106D01*
X2401922Y-100773D01*
X2401767Y-102648D01*
X2401922Y-104523D01*
X2402387Y-106190D01*
X2403007Y-107440D01*
X2403937Y-108481D01*
X2405177Y-108898D01*
X2406417Y-108481D01*
X2407347Y-107440D01*
X2407967Y-106190D01*
X2408432Y-104523D01*
X2408587Y-102648D01*
X2408432Y-100773D01*
X2407967Y-99106D01*
X2407347Y-97856D01*
X2406417Y-96815D01*
X2405177Y-96398D01*
G01X2414787Y-109315D02*
X2420367Y-96398D01*
G01X2427962Y-104731D02*
X2431992D01*
G01X2442377Y-96398D02*
X2441137Y-96815D01*
X2440207Y-97856D01*
X2439587Y-99106D01*
X2439122Y-100773D01*
X2438967Y-102648D01*
X2439122Y-104523D01*
X2439587Y-106190D01*
X2440207Y-107440D01*
X2441137Y-108481D01*
X2442377Y-108898D01*
X2443617Y-108481D01*
X2444547Y-107440D01*
X2445167Y-106190D01*
X2445632Y-104523D01*
X2445787Y-102648D01*
X2445632Y-100773D01*
X2445167Y-99106D01*
X2444547Y-97856D01*
X2443617Y-96815D01*
X2442377Y-96398D01*
G01X2454777Y-109315D02*
X2454467Y-109106D01*
Y-108690D01*
X2454777Y-108481D01*
X2455087Y-108690D01*
Y-109106D01*
X2454777Y-109315D01*
G01X2467177Y-96398D02*
X2465937Y-96815D01*
X2465007Y-97856D01*
X2464387Y-99106D01*
X2463922Y-100773D01*
X2463767Y-102648D01*
X2463922Y-104523D01*
X2464387Y-106190D01*
X2465007Y-107440D01*
X2465937Y-108481D01*
X2467177Y-108898D01*
X2468417Y-108481D01*
X2469347Y-107440D01*
X2469967Y-106190D01*
X2470432Y-104523D01*
X2470587Y-102648D01*
X2470432Y-100773D01*
X2469967Y-99106D01*
X2469347Y-97856D01*
X2468417Y-96815D01*
X2467177Y-96398D01*
G01X2366272Y-71131D02*
X2369992D01*
G01X2367977Y-68423D02*
Y-73840D01*
G01X2376967Y-72798D02*
X2377897Y-74257D01*
X2379137Y-75090D01*
X2380532Y-75298D01*
X2381772Y-75090D01*
X2383012Y-74048D01*
X2383787Y-72798D01*
X2383942Y-71548D01*
X2383632Y-70090D01*
X2382547Y-69048D01*
X2381462Y-68631D01*
X2380067D01*
G01X2381462D02*
X2382392Y-68006D01*
X2383167Y-66965D01*
X2383477Y-65715D01*
X2383167Y-64465D01*
X2382392Y-63423D01*
X2380997Y-62798D01*
X2379602Y-63006D01*
X2378207Y-63840D01*
G01X2392777Y-75715D02*
X2392467Y-75506D01*
Y-75090D01*
X2392777Y-74881D01*
X2393087Y-75090D01*
Y-75506D01*
X2392777Y-75715D01*
G01X2405177Y-62798D02*
X2403937Y-63215D01*
X2403007Y-64256D01*
X2402387Y-65506D01*
X2401922Y-67173D01*
X2401767Y-69048D01*
X2401922Y-70923D01*
X2402387Y-72590D01*
X2403007Y-73840D01*
X2403937Y-74881D01*
X2405177Y-75298D01*
X2406417Y-74881D01*
X2407347Y-73840D01*
X2407967Y-72590D01*
X2408432Y-70923D01*
X2408587Y-69048D01*
X2408432Y-67173D01*
X2407967Y-65506D01*
X2407347Y-64256D01*
X2406417Y-63215D01*
X2405177Y-62798D01*
G01X2414787Y-75715D02*
X2420367Y-62798D01*
G01X2427962Y-71131D02*
X2431992D01*
G01X2438967Y-72798D02*
X2439897Y-74257D01*
X2441137Y-75090D01*
X2442532Y-75298D01*
X2443772Y-75090D01*
X2445012Y-74048D01*
X2445787Y-72798D01*
X2445942Y-71548D01*
X2445632Y-70090D01*
X2444547Y-69048D01*
X2443462Y-68631D01*
X2442067D01*
G01X2443462D02*
X2444392Y-68006D01*
X2445167Y-66965D01*
X2445477Y-65715D01*
X2445167Y-64465D01*
X2444392Y-63423D01*
X2442997Y-62798D01*
X2441602Y-63006D01*
X2440207Y-63840D01*
G01X2454777Y-75715D02*
X2454467Y-75506D01*
Y-75090D01*
X2454777Y-74881D01*
X2455087Y-75090D01*
Y-75506D01*
X2454777Y-75715D01*
G01X2467177Y-62798D02*
X2465937Y-63215D01*
X2465007Y-64256D01*
X2464387Y-65506D01*
X2463922Y-67173D01*
X2463767Y-69048D01*
X2463922Y-70923D01*
X2464387Y-72590D01*
X2465007Y-73840D01*
X2465937Y-74881D01*
X2467177Y-75298D01*
X2468417Y-74881D01*
X2469347Y-73840D01*
X2469967Y-72590D01*
X2470432Y-70923D01*
X2470587Y-69048D01*
X2470432Y-67173D01*
X2469967Y-65506D01*
X2469347Y-64256D01*
X2468417Y-63215D01*
X2467177Y-62798D01*
G01X2366272Y-37531D02*
X2369992D01*
G01X2367977Y-34823D02*
Y-40240D01*
G01X2380377Y-29198D02*
X2379137Y-29615D01*
X2378207Y-30656D01*
X2377587Y-31906D01*
X2377122Y-33573D01*
X2376967Y-35448D01*
X2377122Y-37323D01*
X2377587Y-38990D01*
X2378207Y-40240D01*
X2379137Y-41281D01*
X2380377Y-41698D01*
X2381617Y-41281D01*
X2382547Y-40240D01*
X2383167Y-38990D01*
X2383632Y-37323D01*
X2383787Y-35448D01*
X2383632Y-33573D01*
X2383167Y-31906D01*
X2382547Y-30656D01*
X2381617Y-29615D01*
X2380377Y-29198D01*
G01X2392777Y-42115D02*
X2392467Y-41906D01*
Y-41490D01*
X2392777Y-41281D01*
X2393087Y-41490D01*
Y-41906D01*
X2392777Y-42115D01*
G01X2405177Y-29198D02*
X2403937Y-29615D01*
X2403007Y-30656D01*
X2402387Y-31906D01*
X2401922Y-33573D01*
X2401767Y-35448D01*
X2401922Y-37323D01*
X2402387Y-38990D01*
X2403007Y-40240D01*
X2403937Y-41281D01*
X2405177Y-41698D01*
X2406417Y-41281D01*
X2407347Y-40240D01*
X2407967Y-38990D01*
X2408432Y-37323D01*
X2408587Y-35448D01*
X2408432Y-33573D01*
X2407967Y-31906D01*
X2407347Y-30656D01*
X2406417Y-29615D01*
X2405177Y-29198D01*
G01X2414787Y-42115D02*
X2420367Y-29198D01*
G01X2427962Y-37531D02*
X2431992D01*
G01X2442377Y-29198D02*
X2441137Y-29615D01*
X2440207Y-30656D01*
X2439587Y-31906D01*
X2439122Y-33573D01*
X2438967Y-35448D01*
X2439122Y-37323D01*
X2439587Y-38990D01*
X2440207Y-40240D01*
X2441137Y-41281D01*
X2442377Y-41698D01*
X2443617Y-41281D01*
X2444547Y-40240D01*
X2445167Y-38990D01*
X2445632Y-37323D01*
X2445787Y-35448D01*
X2445632Y-33573D01*
X2445167Y-31906D01*
X2444547Y-30656D01*
X2443617Y-29615D01*
X2442377Y-29198D01*
G01X2454777Y-42115D02*
X2454467Y-41906D01*
Y-41490D01*
X2454777Y-41281D01*
X2455087Y-41490D01*
Y-41906D01*
X2454777Y-42115D01*
G01X2467177Y-29198D02*
X2465937Y-29615D01*
X2465007Y-30656D01*
X2464387Y-31906D01*
X2463922Y-33573D01*
X2463767Y-35448D01*
X2463922Y-37323D01*
X2464387Y-38990D01*
X2465007Y-40240D01*
X2465937Y-41281D01*
X2467177Y-41698D01*
X2468417Y-41281D01*
X2469347Y-40240D01*
X2469967Y-38990D01*
X2470432Y-37323D01*
X2470587Y-35448D01*
X2470432Y-33573D01*
X2469967Y-31906D01*
X2469347Y-30656D01*
X2468417Y-29615D01*
X2467177Y-29198D01*
G01X2366272Y-3931D02*
X2369992D01*
G01X2367977Y-1223D02*
Y-6640D01*
G01X2380377Y4402D02*
X2379137Y3985D01*
X2378207Y2944D01*
X2377587Y1694D01*
X2377122Y27D01*
X2376967Y-1848D01*
X2377122Y-3723D01*
X2377587Y-5390D01*
X2378207Y-6640D01*
X2379137Y-7681D01*
X2380377Y-8098D01*
X2381617Y-7681D01*
X2382547Y-6640D01*
X2383167Y-5390D01*
X2383632Y-3723D01*
X2383787Y-1848D01*
X2383632Y27D01*
X2383167Y1694D01*
X2382547Y2944D01*
X2381617Y3985D01*
X2380377Y4402D01*
G01X2392777Y-8515D02*
X2392467Y-8306D01*
Y-7890D01*
X2392777Y-7681D01*
X2393087Y-7890D01*
Y-8306D01*
X2392777Y-8515D01*
G01X2405177Y4402D02*
X2403937Y3985D01*
X2403007Y2944D01*
X2402387Y1694D01*
X2401922Y27D01*
X2401767Y-1848D01*
X2401922Y-3723D01*
X2402387Y-5390D01*
X2403007Y-6640D01*
X2403937Y-7681D01*
X2405177Y-8098D01*
X2406417Y-7681D01*
X2407347Y-6640D01*
X2407967Y-5390D01*
X2408432Y-3723D01*
X2408587Y-1848D01*
X2408432Y27D01*
X2407967Y1694D01*
X2407347Y2944D01*
X2406417Y3985D01*
X2405177Y4402D01*
G01X2414787Y-8515D02*
X2420367Y4402D01*
G01X2427962Y-3931D02*
X2431992D01*
G01X2442377Y4402D02*
X2441137Y3985D01*
X2440207Y2944D01*
X2439587Y1694D01*
X2439122Y27D01*
X2438967Y-1848D01*
X2439122Y-3723D01*
X2439587Y-5390D01*
X2440207Y-6640D01*
X2441137Y-7681D01*
X2442377Y-8098D01*
X2443617Y-7681D01*
X2444547Y-6640D01*
X2445167Y-5390D01*
X2445632Y-3723D01*
X2445787Y-1848D01*
X2445632Y27D01*
X2445167Y1694D01*
X2444547Y2944D01*
X2443617Y3985D01*
X2442377Y4402D01*
G01X2454777Y-8515D02*
X2454467Y-8306D01*
Y-7890D01*
X2454777Y-7681D01*
X2455087Y-7890D01*
Y-8306D01*
X2454777Y-8515D01*
G01X2467177Y4402D02*
X2465937Y3985D01*
X2465007Y2944D01*
X2464387Y1694D01*
X2463922Y27D01*
X2463767Y-1848D01*
X2463922Y-3723D01*
X2464387Y-5390D01*
X2465007Y-6640D01*
X2465937Y-7681D01*
X2467177Y-8098D01*
X2468417Y-7681D01*
X2469347Y-6640D01*
X2469967Y-5390D01*
X2470432Y-3723D01*
X2470587Y-1848D01*
X2470432Y27D01*
X2469967Y1694D01*
X2469347Y2944D01*
X2468417Y3985D01*
X2467177Y4402D01*
G01X2366272Y29669D02*
X2369992D01*
G01X2367977Y32377D02*
Y26960D01*
G01X2377432Y35919D02*
X2378362Y37168D01*
X2379447Y37794D01*
X2380687Y38002D01*
X2382237Y37585D01*
X2383322Y36544D01*
X2383632Y35294D01*
X2383477Y34043D01*
X2382857Y33002D01*
X2379757Y30919D01*
X2378362Y29460D01*
X2377432Y27377D01*
X2377122Y25502D01*
X2383632D01*
G01X2392777Y25085D02*
X2392467Y25294D01*
Y25710D01*
X2392777Y25919D01*
X2393087Y25710D01*
Y25294D01*
X2392777Y25085D01*
G01X2405177Y38002D02*
X2403937Y37585D01*
X2403007Y36544D01*
X2402387Y35294D01*
X2401922Y33627D01*
X2401767Y31752D01*
X2401922Y29877D01*
X2402387Y28210D01*
X2403007Y26960D01*
X2403937Y25919D01*
X2405177Y25502D01*
X2406417Y25919D01*
X2407347Y26960D01*
X2407967Y28210D01*
X2408432Y29877D01*
X2408587Y31752D01*
X2408432Y33627D01*
X2407967Y35294D01*
X2407347Y36544D01*
X2406417Y37585D01*
X2405177Y38002D01*
G01X2414787Y25085D02*
X2420367Y38002D01*
G01X2427962Y29669D02*
X2431992D01*
G01X2439432Y35919D02*
X2440362Y37168D01*
X2441447Y37794D01*
X2442687Y38002D01*
X2444237Y37585D01*
X2445322Y36544D01*
X2445632Y35294D01*
X2445477Y34043D01*
X2444857Y33002D01*
X2441757Y30919D01*
X2440362Y29460D01*
X2439432Y27377D01*
X2439122Y25502D01*
X2445632D01*
G01X2454777Y25085D02*
X2454467Y25294D01*
Y25710D01*
X2454777Y25919D01*
X2455087Y25710D01*
Y25294D01*
X2454777Y25085D01*
G01X2467177Y38002D02*
X2465937Y37585D01*
X2465007Y36544D01*
X2464387Y35294D01*
X2463922Y33627D01*
X2463767Y31752D01*
X2463922Y29877D01*
X2464387Y28210D01*
X2465007Y26960D01*
X2465937Y25919D01*
X2467177Y25502D01*
X2468417Y25919D01*
X2469347Y26960D01*
X2469967Y28210D01*
X2470432Y29877D01*
X2470587Y31752D01*
X2470432Y33627D01*
X2469967Y35294D01*
X2469347Y36544D01*
X2468417Y37585D01*
X2467177Y38002D01*
G01X2366272Y63269D02*
X2369992D01*
G01X2367977Y65977D02*
Y60560D01*
G01X2376967Y61602D02*
X2377897Y60143D01*
X2379137Y59310D01*
X2380532Y59102D01*
X2381772Y59310D01*
X2383012Y60352D01*
X2383787Y61602D01*
X2383942Y62852D01*
X2383632Y64310D01*
X2382547Y65352D01*
X2381462Y65769D01*
X2380067D01*
G01X2381462D02*
X2382392Y66394D01*
X2383167Y67435D01*
X2383477Y68685D01*
X2383167Y69935D01*
X2382392Y70977D01*
X2380997Y71602D01*
X2379602Y71394D01*
X2378207Y70560D01*
G01X2392777Y58685D02*
X2392467Y58894D01*
Y59310D01*
X2392777Y59519D01*
X2393087Y59310D01*
Y58894D01*
X2392777Y58685D01*
G01X2405177Y71602D02*
X2403937Y71185D01*
X2403007Y70144D01*
X2402387Y68894D01*
X2401922Y67227D01*
X2401767Y65352D01*
X2401922Y63477D01*
X2402387Y61810D01*
X2403007Y60560D01*
X2403937Y59519D01*
X2405177Y59102D01*
X2406417Y59519D01*
X2407347Y60560D01*
X2407967Y61810D01*
X2408432Y63477D01*
X2408587Y65352D01*
X2408432Y67227D01*
X2407967Y68894D01*
X2407347Y70144D01*
X2406417Y71185D01*
X2405177Y71602D01*
G01X2414787Y58685D02*
X2420367Y71602D01*
G01X2427962Y63269D02*
X2431992D01*
G01X2438967Y61602D02*
X2439897Y60143D01*
X2441137Y59310D01*
X2442532Y59102D01*
X2443772Y59310D01*
X2445012Y60352D01*
X2445787Y61602D01*
X2445942Y62852D01*
X2445632Y64310D01*
X2444547Y65352D01*
X2443462Y65769D01*
X2442067D01*
G01X2443462D02*
X2444392Y66394D01*
X2445167Y67435D01*
X2445477Y68685D01*
X2445167Y69935D01*
X2444392Y70977D01*
X2442997Y71602D01*
X2441602Y71394D01*
X2440207Y70560D01*
G01X2454777Y58685D02*
X2454467Y58894D01*
Y59310D01*
X2454777Y59519D01*
X2455087Y59310D01*
Y58894D01*
X2454777Y58685D01*
G01X2467177Y71602D02*
X2465937Y71185D01*
X2465007Y70144D01*
X2464387Y68894D01*
X2463922Y67227D01*
X2463767Y65352D01*
X2463922Y63477D01*
X2464387Y61810D01*
X2465007Y60560D01*
X2465937Y59519D01*
X2467177Y59102D01*
X2468417Y59519D01*
X2469347Y60560D01*
X2469967Y61810D01*
X2470432Y63477D01*
X2470587Y65352D01*
X2470432Y67227D01*
X2469967Y68894D01*
X2469347Y70144D01*
X2468417Y71185D01*
X2467177Y71602D01*
G01X2366272Y96869D02*
X2369992D01*
G01X2367977Y99577D02*
Y94160D01*
G01X2380377Y105202D02*
X2379137Y104785D01*
X2378207Y103744D01*
X2377587Y102494D01*
X2377122Y100827D01*
X2376967Y98952D01*
X2377122Y97077D01*
X2377587Y95410D01*
X2378207Y94160D01*
X2379137Y93119D01*
X2380377Y92702D01*
X2381617Y93119D01*
X2382547Y94160D01*
X2383167Y95410D01*
X2383632Y97077D01*
X2383787Y98952D01*
X2383632Y100827D01*
X2383167Y102494D01*
X2382547Y103744D01*
X2381617Y104785D01*
X2380377Y105202D01*
G01X2392777Y92285D02*
X2392467Y92494D01*
Y92910D01*
X2392777Y93119D01*
X2393087Y92910D01*
Y92494D01*
X2392777Y92285D01*
G01X2405177Y105202D02*
X2403937Y104785D01*
X2403007Y103744D01*
X2402387Y102494D01*
X2401922Y100827D01*
X2401767Y98952D01*
X2401922Y97077D01*
X2402387Y95410D01*
X2403007Y94160D01*
X2403937Y93119D01*
X2405177Y92702D01*
X2406417Y93119D01*
X2407347Y94160D01*
X2407967Y95410D01*
X2408432Y97077D01*
X2408587Y98952D01*
X2408432Y100827D01*
X2407967Y102494D01*
X2407347Y103744D01*
X2406417Y104785D01*
X2405177Y105202D01*
G01X2414787Y92285D02*
X2420367Y105202D01*
G01X2427962Y96869D02*
X2431992D01*
G01X2442377Y105202D02*
X2441137Y104785D01*
X2440207Y103744D01*
X2439587Y102494D01*
X2439122Y100827D01*
X2438967Y98952D01*
X2439122Y97077D01*
X2439587Y95410D01*
X2440207Y94160D01*
X2441137Y93119D01*
X2442377Y92702D01*
X2443617Y93119D01*
X2444547Y94160D01*
X2445167Y95410D01*
X2445632Y97077D01*
X2445787Y98952D01*
X2445632Y100827D01*
X2445167Y102494D01*
X2444547Y103744D01*
X2443617Y104785D01*
X2442377Y105202D01*
G01X2454777Y92285D02*
X2454467Y92494D01*
Y92910D01*
X2454777Y93119D01*
X2455087Y92910D01*
Y92494D01*
X2454777Y92285D01*
G01X2467177Y105202D02*
X2465937Y104785D01*
X2465007Y103744D01*
X2464387Y102494D01*
X2463922Y100827D01*
X2463767Y98952D01*
X2463922Y97077D01*
X2464387Y95410D01*
X2465007Y94160D01*
X2465937Y93119D01*
X2467177Y92702D01*
X2468417Y93119D01*
X2469347Y94160D01*
X2469967Y95410D01*
X2470432Y97077D01*
X2470587Y98952D01*
X2470432Y100827D01*
X2469967Y102494D01*
X2469347Y103744D01*
X2468417Y104785D01*
X2467177Y105202D01*
G01X2366272Y130469D02*
X2369992D01*
G01X2367977Y133177D02*
Y127760D01*
G01X2380377Y138802D02*
X2379137Y138385D01*
X2378207Y137344D01*
X2377587Y136094D01*
X2377122Y134427D01*
X2376967Y132552D01*
X2377122Y130677D01*
X2377587Y129010D01*
X2378207Y127760D01*
X2379137Y126719D01*
X2380377Y126302D01*
X2381617Y126719D01*
X2382547Y127760D01*
X2383167Y129010D01*
X2383632Y130677D01*
X2383787Y132552D01*
X2383632Y134427D01*
X2383167Y136094D01*
X2382547Y137344D01*
X2381617Y138385D01*
X2380377Y138802D01*
G01X2392777Y125885D02*
X2392467Y126094D01*
Y126510D01*
X2392777Y126719D01*
X2393087Y126510D01*
Y126094D01*
X2392777Y125885D01*
G01X2405177Y138802D02*
X2403937Y138385D01*
X2403007Y137344D01*
X2402387Y136094D01*
X2401922Y134427D01*
X2401767Y132552D01*
X2401922Y130677D01*
X2402387Y129010D01*
X2403007Y127760D01*
X2403937Y126719D01*
X2405177Y126302D01*
X2406417Y126719D01*
X2407347Y127760D01*
X2407967Y129010D01*
X2408432Y130677D01*
X2408587Y132552D01*
X2408432Y134427D01*
X2407967Y136094D01*
X2407347Y137344D01*
X2406417Y138385D01*
X2405177Y138802D01*
G01X2414787Y125885D02*
X2420367Y138802D01*
G01X2427962Y130469D02*
X2431992D01*
G01X2442377Y138802D02*
X2441137Y138385D01*
X2440207Y137344D01*
X2439587Y136094D01*
X2439122Y134427D01*
X2438967Y132552D01*
X2439122Y130677D01*
X2439587Y129010D01*
X2440207Y127760D01*
X2441137Y126719D01*
X2442377Y126302D01*
X2443617Y126719D01*
X2444547Y127760D01*
X2445167Y129010D01*
X2445632Y130677D01*
X2445787Y132552D01*
X2445632Y134427D01*
X2445167Y136094D01*
X2444547Y137344D01*
X2443617Y138385D01*
X2442377Y138802D01*
G01X2454777Y125885D02*
X2454467Y126094D01*
Y126510D01*
X2454777Y126719D01*
X2455087Y126510D01*
Y126094D01*
X2454777Y125885D01*
G01X2467177Y138802D02*
X2465937Y138385D01*
X2465007Y137344D01*
X2464387Y136094D01*
X2463922Y134427D01*
X2463767Y132552D01*
X2463922Y130677D01*
X2464387Y129010D01*
X2465007Y127760D01*
X2465937Y126719D01*
X2467177Y126302D01*
X2468417Y126719D01*
X2469347Y127760D01*
X2469967Y129010D01*
X2470432Y130677D01*
X2470587Y132552D01*
X2470432Y134427D01*
X2469967Y136094D01*
X2469347Y137344D01*
X2468417Y138385D01*
X2467177Y138802D01*
G01X2366272Y164069D02*
X2369992D01*
G01X2367977Y166777D02*
Y161360D01*
G01X2380377Y172402D02*
X2379137Y171985D01*
X2378207Y170944D01*
X2377587Y169694D01*
X2377122Y168027D01*
X2376967Y166152D01*
X2377122Y164277D01*
X2377587Y162610D01*
X2378207Y161360D01*
X2379137Y160319D01*
X2380377Y159902D01*
X2381617Y160319D01*
X2382547Y161360D01*
X2383167Y162610D01*
X2383632Y164277D01*
X2383787Y166152D01*
X2383632Y168027D01*
X2383167Y169694D01*
X2382547Y170944D01*
X2381617Y171985D01*
X2380377Y172402D01*
G01X2392777Y159485D02*
X2392467Y159694D01*
Y160110D01*
X2392777Y160319D01*
X2393087Y160110D01*
Y159694D01*
X2392777Y159485D01*
G01X2405177Y172402D02*
X2403937Y171985D01*
X2403007Y170944D01*
X2402387Y169694D01*
X2401922Y168027D01*
X2401767Y166152D01*
X2401922Y164277D01*
X2402387Y162610D01*
X2403007Y161360D01*
X2403937Y160319D01*
X2405177Y159902D01*
X2406417Y160319D01*
X2407347Y161360D01*
X2407967Y162610D01*
X2408432Y164277D01*
X2408587Y166152D01*
X2408432Y168027D01*
X2407967Y169694D01*
X2407347Y170944D01*
X2406417Y171985D01*
X2405177Y172402D01*
G01X2414787Y159485D02*
X2420367Y172402D01*
G01X2427962Y164069D02*
X2431992D01*
G01X2442377Y172402D02*
X2441137Y171985D01*
X2440207Y170944D01*
X2439587Y169694D01*
X2439122Y168027D01*
X2438967Y166152D01*
X2439122Y164277D01*
X2439587Y162610D01*
X2440207Y161360D01*
X2441137Y160319D01*
X2442377Y159902D01*
X2443617Y160319D01*
X2444547Y161360D01*
X2445167Y162610D01*
X2445632Y164277D01*
X2445787Y166152D01*
X2445632Y168027D01*
X2445167Y169694D01*
X2444547Y170944D01*
X2443617Y171985D01*
X2442377Y172402D01*
G01X2454777Y159485D02*
X2454467Y159694D01*
Y160110D01*
X2454777Y160319D01*
X2455087Y160110D01*
Y159694D01*
X2454777Y159485D01*
G01X2467177Y172402D02*
X2465937Y171985D01*
X2465007Y170944D01*
X2464387Y169694D01*
X2463922Y168027D01*
X2463767Y166152D01*
X2463922Y164277D01*
X2464387Y162610D01*
X2465007Y161360D01*
X2465937Y160319D01*
X2467177Y159902D01*
X2468417Y160319D01*
X2469347Y161360D01*
X2469967Y162610D01*
X2470432Y164277D01*
X2470587Y166152D01*
X2470432Y168027D01*
X2469967Y169694D01*
X2469347Y170944D01*
X2468417Y171985D01*
X2467177Y172402D01*
G01X2366272Y197669D02*
X2369992D01*
G01X2367977Y200377D02*
Y194960D01*
G01X2380377Y206002D02*
X2379137Y205585D01*
X2378207Y204544D01*
X2377587Y203294D01*
X2377122Y201627D01*
X2376967Y199752D01*
X2377122Y197877D01*
X2377587Y196210D01*
X2378207Y194960D01*
X2379137Y193919D01*
X2380377Y193502D01*
X2381617Y193919D01*
X2382547Y194960D01*
X2383167Y196210D01*
X2383632Y197877D01*
X2383787Y199752D01*
X2383632Y201627D01*
X2383167Y203294D01*
X2382547Y204544D01*
X2381617Y205585D01*
X2380377Y206002D01*
G01X2392777Y193085D02*
X2392467Y193294D01*
Y193710D01*
X2392777Y193919D01*
X2393087Y193710D01*
Y193294D01*
X2392777Y193085D01*
G01X2405177Y206002D02*
X2403937Y205585D01*
X2403007Y204544D01*
X2402387Y203294D01*
X2401922Y201627D01*
X2401767Y199752D01*
X2401922Y197877D01*
X2402387Y196210D01*
X2403007Y194960D01*
X2403937Y193919D01*
X2405177Y193502D01*
X2406417Y193919D01*
X2407347Y194960D01*
X2407967Y196210D01*
X2408432Y197877D01*
X2408587Y199752D01*
X2408432Y201627D01*
X2407967Y203294D01*
X2407347Y204544D01*
X2406417Y205585D01*
X2405177Y206002D01*
G01X2414787Y193085D02*
X2420367Y206002D01*
G01X2427962Y197669D02*
X2431992D01*
G01X2442377Y206002D02*
X2441137Y205585D01*
X2440207Y204544D01*
X2439587Y203294D01*
X2439122Y201627D01*
X2438967Y199752D01*
X2439122Y197877D01*
X2439587Y196210D01*
X2440207Y194960D01*
X2441137Y193919D01*
X2442377Y193502D01*
X2443617Y193919D01*
X2444547Y194960D01*
X2445167Y196210D01*
X2445632Y197877D01*
X2445787Y199752D01*
X2445632Y201627D01*
X2445167Y203294D01*
X2444547Y204544D01*
X2443617Y205585D01*
X2442377Y206002D01*
G01X2454777Y193085D02*
X2454467Y193294D01*
Y193710D01*
X2454777Y193919D01*
X2455087Y193710D01*
Y193294D01*
X2454777Y193085D01*
G01X2467177Y206002D02*
X2465937Y205585D01*
X2465007Y204544D01*
X2464387Y203294D01*
X2463922Y201627D01*
X2463767Y199752D01*
X2463922Y197877D01*
X2464387Y196210D01*
X2465007Y194960D01*
X2465937Y193919D01*
X2467177Y193502D01*
X2468417Y193919D01*
X2469347Y194960D01*
X2469967Y196210D01*
X2470432Y197877D01*
X2470587Y199752D01*
X2470432Y201627D01*
X2469967Y203294D01*
X2469347Y204544D01*
X2468417Y205585D01*
X2467177Y206002D01*
G01X2366272Y231269D02*
X2369992D01*
G01X2367977Y233977D02*
Y228560D01*
G01X2376967Y229602D02*
X2377897Y228143D01*
X2379137Y227310D01*
X2380532Y227102D01*
X2381772Y227310D01*
X2383012Y228352D01*
X2383787Y229602D01*
X2383942Y230852D01*
X2383632Y232310D01*
X2382547Y233352D01*
X2381462Y233769D01*
X2380067D01*
G01X2381462D02*
X2382392Y234394D01*
X2383167Y235435D01*
X2383477Y236685D01*
X2383167Y237935D01*
X2382392Y238977D01*
X2380997Y239602D01*
X2379602Y239394D01*
X2378207Y238560D01*
G01X2392777Y226685D02*
X2392467Y226894D01*
Y227310D01*
X2392777Y227519D01*
X2393087Y227310D01*
Y226894D01*
X2392777Y226685D01*
G01X2405177Y239602D02*
X2403937Y239185D01*
X2403007Y238144D01*
X2402387Y236894D01*
X2401922Y235227D01*
X2401767Y233352D01*
X2401922Y231477D01*
X2402387Y229810D01*
X2403007Y228560D01*
X2403937Y227519D01*
X2405177Y227102D01*
X2406417Y227519D01*
X2407347Y228560D01*
X2407967Y229810D01*
X2408432Y231477D01*
X2408587Y233352D01*
X2408432Y235227D01*
X2407967Y236894D01*
X2407347Y238144D01*
X2406417Y239185D01*
X2405177Y239602D01*
G01X2414787Y226685D02*
X2420367Y239602D01*
G01X2427962Y231269D02*
X2431992D01*
G01X2438967Y229602D02*
X2439897Y228143D01*
X2441137Y227310D01*
X2442532Y227102D01*
X2443772Y227310D01*
X2445012Y228352D01*
X2445787Y229602D01*
X2445942Y230852D01*
X2445632Y232310D01*
X2444547Y233352D01*
X2443462Y233769D01*
X2442067D01*
G01X2443462D02*
X2444392Y234394D01*
X2445167Y235435D01*
X2445477Y236685D01*
X2445167Y237935D01*
X2444392Y238977D01*
X2442997Y239602D01*
X2441602Y239394D01*
X2440207Y238560D01*
G01X2454777Y226685D02*
X2454467Y226894D01*
Y227310D01*
X2454777Y227519D01*
X2455087Y227310D01*
Y226894D01*
X2454777Y226685D01*
G01X2467177Y239602D02*
X2465937Y239185D01*
X2465007Y238144D01*
X2464387Y236894D01*
X2463922Y235227D01*
X2463767Y233352D01*
X2463922Y231477D01*
X2464387Y229810D01*
X2465007Y228560D01*
X2465937Y227519D01*
X2467177Y227102D01*
X2468417Y227519D01*
X2469347Y228560D01*
X2469967Y229810D01*
X2470432Y231477D01*
X2470587Y233352D01*
X2470432Y235227D01*
X2469967Y236894D01*
X2469347Y238144D01*
X2468417Y239185D01*
X2467177Y239602D01*
G01X2366272Y264869D02*
X2369992D01*
G01X2367977Y267577D02*
Y262160D01*
G01X2376967Y263202D02*
X2377897Y261743D01*
X2379137Y260910D01*
X2380532Y260702D01*
X2381772Y260910D01*
X2383012Y261952D01*
X2383787Y263202D01*
X2383942Y264452D01*
X2383632Y265910D01*
X2382547Y266952D01*
X2381462Y267369D01*
X2380067D01*
G01X2381462D02*
X2382392Y267994D01*
X2383167Y269035D01*
X2383477Y270285D01*
X2383167Y271535D01*
X2382392Y272577D01*
X2380997Y273202D01*
X2379602Y272994D01*
X2378207Y272160D01*
G01X2392777Y260285D02*
X2392467Y260494D01*
Y260910D01*
X2392777Y261119D01*
X2393087Y260910D01*
Y260494D01*
X2392777Y260285D01*
G01X2405177Y273202D02*
X2403937Y272785D01*
X2403007Y271744D01*
X2402387Y270494D01*
X2401922Y268827D01*
X2401767Y266952D01*
X2401922Y265077D01*
X2402387Y263410D01*
X2403007Y262160D01*
X2403937Y261119D01*
X2405177Y260702D01*
X2406417Y261119D01*
X2407347Y262160D01*
X2407967Y263410D01*
X2408432Y265077D01*
X2408587Y266952D01*
X2408432Y268827D01*
X2407967Y270494D01*
X2407347Y271744D01*
X2406417Y272785D01*
X2405177Y273202D01*
G01X2414787Y260285D02*
X2420367Y273202D01*
G01X2427962Y264869D02*
X2431992D01*
G01X2438967Y263202D02*
X2439897Y261743D01*
X2441137Y260910D01*
X2442532Y260702D01*
X2443772Y260910D01*
X2445012Y261952D01*
X2445787Y263202D01*
X2445942Y264452D01*
X2445632Y265910D01*
X2444547Y266952D01*
X2443462Y267369D01*
X2442067D01*
G01X2443462D02*
X2444392Y267994D01*
X2445167Y269035D01*
X2445477Y270285D01*
X2445167Y271535D01*
X2444392Y272577D01*
X2442997Y273202D01*
X2441602Y272994D01*
X2440207Y272160D01*
G01X2454777Y260285D02*
X2454467Y260494D01*
Y260910D01*
X2454777Y261119D01*
X2455087Y260910D01*
Y260494D01*
X2454777Y260285D01*
G01X2467177Y273202D02*
X2465937Y272785D01*
X2465007Y271744D01*
X2464387Y270494D01*
X2463922Y268827D01*
X2463767Y266952D01*
X2463922Y265077D01*
X2464387Y263410D01*
X2465007Y262160D01*
X2465937Y261119D01*
X2467177Y260702D01*
X2468417Y261119D01*
X2469347Y262160D01*
X2469967Y263410D01*
X2470432Y265077D01*
X2470587Y266952D01*
X2470432Y268827D01*
X2469967Y270494D01*
X2469347Y271744D01*
X2468417Y272785D01*
X2467177Y273202D01*
G01X2366272Y298469D02*
X2369992D01*
G01X2367977Y301177D02*
Y295760D01*
G01X2376967Y296802D02*
X2377897Y295343D01*
X2379137Y294510D01*
X2380532Y294302D01*
X2381772Y294510D01*
X2383012Y295552D01*
X2383787Y296802D01*
X2383942Y298052D01*
X2383632Y299510D01*
X2382547Y300552D01*
X2381462Y300969D01*
X2380067D01*
G01X2381462D02*
X2382392Y301594D01*
X2383167Y302635D01*
X2383477Y303885D01*
X2383167Y305135D01*
X2382392Y306177D01*
X2380997Y306802D01*
X2379602Y306594D01*
X2378207Y305760D01*
G01X2392777Y293885D02*
X2392467Y294094D01*
Y294510D01*
X2392777Y294719D01*
X2393087Y294510D01*
Y294094D01*
X2392777Y293885D01*
G01X2405177Y306802D02*
X2403937Y306385D01*
X2403007Y305344D01*
X2402387Y304094D01*
X2401922Y302427D01*
X2401767Y300552D01*
X2401922Y298677D01*
X2402387Y297010D01*
X2403007Y295760D01*
X2403937Y294719D01*
X2405177Y294302D01*
X2406417Y294719D01*
X2407347Y295760D01*
X2407967Y297010D01*
X2408432Y298677D01*
X2408587Y300552D01*
X2408432Y302427D01*
X2407967Y304094D01*
X2407347Y305344D01*
X2406417Y306385D01*
X2405177Y306802D01*
G01X2414787Y293885D02*
X2420367Y306802D01*
G01X2427962Y298469D02*
X2431992D01*
G01X2438967Y296802D02*
X2439897Y295343D01*
X2441137Y294510D01*
X2442532Y294302D01*
X2443772Y294510D01*
X2445012Y295552D01*
X2445787Y296802D01*
X2445942Y298052D01*
X2445632Y299510D01*
X2444547Y300552D01*
X2443462Y300969D01*
X2442067D01*
G01X2443462D02*
X2444392Y301594D01*
X2445167Y302635D01*
X2445477Y303885D01*
X2445167Y305135D01*
X2444392Y306177D01*
X2442997Y306802D01*
X2441602Y306594D01*
X2440207Y305760D01*
G01X2454777Y293885D02*
X2454467Y294094D01*
Y294510D01*
X2454777Y294719D01*
X2455087Y294510D01*
Y294094D01*
X2454777Y293885D01*
G01X2467177Y306802D02*
X2465937Y306385D01*
X2465007Y305344D01*
X2464387Y304094D01*
X2463922Y302427D01*
X2463767Y300552D01*
X2463922Y298677D01*
X2464387Y297010D01*
X2465007Y295760D01*
X2465937Y294719D01*
X2467177Y294302D01*
X2468417Y294719D01*
X2469347Y295760D01*
X2469967Y297010D01*
X2470432Y298677D01*
X2470587Y300552D01*
X2470432Y302427D01*
X2469967Y304094D01*
X2469347Y305344D01*
X2468417Y306385D01*
X2467177Y306802D01*
G01X2366272Y332069D02*
X2369992D01*
G01X2367977Y334777D02*
Y329360D01*
G01X2380377Y340402D02*
X2379137Y339985D01*
X2378207Y338944D01*
X2377587Y337694D01*
X2377122Y336027D01*
X2376967Y334152D01*
X2377122Y332277D01*
X2377587Y330610D01*
X2378207Y329360D01*
X2379137Y328319D01*
X2380377Y327902D01*
X2381617Y328319D01*
X2382547Y329360D01*
X2383167Y330610D01*
X2383632Y332277D01*
X2383787Y334152D01*
X2383632Y336027D01*
X2383167Y337694D01*
X2382547Y338944D01*
X2381617Y339985D01*
X2380377Y340402D01*
G01X2392777Y327485D02*
X2392467Y327694D01*
Y328110D01*
X2392777Y328319D01*
X2393087Y328110D01*
Y327694D01*
X2392777Y327485D01*
G01X2405177Y340402D02*
X2403937Y339985D01*
X2403007Y338944D01*
X2402387Y337694D01*
X2401922Y336027D01*
X2401767Y334152D01*
X2401922Y332277D01*
X2402387Y330610D01*
X2403007Y329360D01*
X2403937Y328319D01*
X2405177Y327902D01*
X2406417Y328319D01*
X2407347Y329360D01*
X2407967Y330610D01*
X2408432Y332277D01*
X2408587Y334152D01*
X2408432Y336027D01*
X2407967Y337694D01*
X2407347Y338944D01*
X2406417Y339985D01*
X2405177Y340402D01*
G01X2414787Y327485D02*
X2420367Y340402D01*
G01X2427962Y332069D02*
X2431992D01*
G01X2442377Y340402D02*
X2441137Y339985D01*
X2440207Y338944D01*
X2439587Y337694D01*
X2439122Y336027D01*
X2438967Y334152D01*
X2439122Y332277D01*
X2439587Y330610D01*
X2440207Y329360D01*
X2441137Y328319D01*
X2442377Y327902D01*
X2443617Y328319D01*
X2444547Y329360D01*
X2445167Y330610D01*
X2445632Y332277D01*
X2445787Y334152D01*
X2445632Y336027D01*
X2445167Y337694D01*
X2444547Y338944D01*
X2443617Y339985D01*
X2442377Y340402D01*
G01X2454777Y327485D02*
X2454467Y327694D01*
Y328110D01*
X2454777Y328319D01*
X2455087Y328110D01*
Y327694D01*
X2454777Y327485D01*
G01X2467177Y340402D02*
X2465937Y339985D01*
X2465007Y338944D01*
X2464387Y337694D01*
X2463922Y336027D01*
X2463767Y334152D01*
X2463922Y332277D01*
X2464387Y330610D01*
X2465007Y329360D01*
X2465937Y328319D01*
X2467177Y327902D01*
X2468417Y328319D01*
X2469347Y329360D01*
X2469967Y330610D01*
X2470432Y332277D01*
X2470587Y334152D01*
X2470432Y336027D01*
X2469967Y337694D01*
X2469347Y338944D01*
X2468417Y339985D01*
X2467177Y340402D01*
G01X2366272Y365669D02*
X2369992D01*
G01X2367977Y368377D02*
Y362960D01*
G01X2376967Y364002D02*
X2377897Y362543D01*
X2379137Y361710D01*
X2380532Y361502D01*
X2381772Y361710D01*
X2383012Y362752D01*
X2383787Y364002D01*
X2383942Y365252D01*
X2383632Y366710D01*
X2382547Y367752D01*
X2381462Y368169D01*
X2380067D01*
G01X2381462D02*
X2382392Y368794D01*
X2383167Y369835D01*
X2383477Y371085D01*
X2383167Y372335D01*
X2382392Y373377D01*
X2380997Y374002D01*
X2379602Y373794D01*
X2378207Y372960D01*
G01X2392777Y361085D02*
X2392467Y361294D01*
Y361710D01*
X2392777Y361919D01*
X2393087Y361710D01*
Y361294D01*
X2392777Y361085D01*
G01X2405177Y374002D02*
X2403937Y373585D01*
X2403007Y372544D01*
X2402387Y371294D01*
X2401922Y369627D01*
X2401767Y367752D01*
X2401922Y365877D01*
X2402387Y364210D01*
X2403007Y362960D01*
X2403937Y361919D01*
X2405177Y361502D01*
X2406417Y361919D01*
X2407347Y362960D01*
X2407967Y364210D01*
X2408432Y365877D01*
X2408587Y367752D01*
X2408432Y369627D01*
X2407967Y371294D01*
X2407347Y372544D01*
X2406417Y373585D01*
X2405177Y374002D01*
G01X2414787Y361085D02*
X2420367Y374002D01*
G01X2427962Y365669D02*
X2431992D01*
G01X2438967Y364002D02*
X2439897Y362543D01*
X2441137Y361710D01*
X2442532Y361502D01*
X2443772Y361710D01*
X2445012Y362752D01*
X2445787Y364002D01*
X2445942Y365252D01*
X2445632Y366710D01*
X2444547Y367752D01*
X2443462Y368169D01*
X2442067D01*
G01X2443462D02*
X2444392Y368794D01*
X2445167Y369835D01*
X2445477Y371085D01*
X2445167Y372335D01*
X2444392Y373377D01*
X2442997Y374002D01*
X2441602Y373794D01*
X2440207Y372960D01*
G01X2454777Y361085D02*
X2454467Y361294D01*
Y361710D01*
X2454777Y361919D01*
X2455087Y361710D01*
Y361294D01*
X2454777Y361085D01*
G01X2467177Y374002D02*
X2465937Y373585D01*
X2465007Y372544D01*
X2464387Y371294D01*
X2463922Y369627D01*
X2463767Y367752D01*
X2463922Y365877D01*
X2464387Y364210D01*
X2465007Y362960D01*
X2465937Y361919D01*
X2467177Y361502D01*
X2468417Y361919D01*
X2469347Y362960D01*
X2469967Y364210D01*
X2470432Y365877D01*
X2470587Y367752D01*
X2470432Y369627D01*
X2469967Y371294D01*
X2469347Y372544D01*
X2468417Y373585D01*
X2467177Y374002D01*
G01X2366272Y399269D02*
X2369992D01*
G01X2367977Y401977D02*
Y396560D01*
G01X2380377Y407602D02*
X2379137Y407185D01*
X2378207Y406144D01*
X2377587Y404894D01*
X2377122Y403227D01*
X2376967Y401352D01*
X2377122Y399477D01*
X2377587Y397810D01*
X2378207Y396560D01*
X2379137Y395519D01*
X2380377Y395102D01*
X2381617Y395519D01*
X2382547Y396560D01*
X2383167Y397810D01*
X2383632Y399477D01*
X2383787Y401352D01*
X2383632Y403227D01*
X2383167Y404894D01*
X2382547Y406144D01*
X2381617Y407185D01*
X2380377Y407602D01*
G01X2392777Y394685D02*
X2392467Y394894D01*
Y395310D01*
X2392777Y395519D01*
X2393087Y395310D01*
Y394894D01*
X2392777Y394685D01*
G01X2405177Y407602D02*
X2403937Y407185D01*
X2403007Y406144D01*
X2402387Y404894D01*
X2401922Y403227D01*
X2401767Y401352D01*
X2401922Y399477D01*
X2402387Y397810D01*
X2403007Y396560D01*
X2403937Y395519D01*
X2405177Y395102D01*
X2406417Y395519D01*
X2407347Y396560D01*
X2407967Y397810D01*
X2408432Y399477D01*
X2408587Y401352D01*
X2408432Y403227D01*
X2407967Y404894D01*
X2407347Y406144D01*
X2406417Y407185D01*
X2405177Y407602D01*
G01X2414787Y394685D02*
X2420367Y407602D01*
G01X2427962Y399269D02*
X2431992D01*
G01X2442377Y407602D02*
X2441137Y407185D01*
X2440207Y406144D01*
X2439587Y404894D01*
X2439122Y403227D01*
X2438967Y401352D01*
X2439122Y399477D01*
X2439587Y397810D01*
X2440207Y396560D01*
X2441137Y395519D01*
X2442377Y395102D01*
X2443617Y395519D01*
X2444547Y396560D01*
X2445167Y397810D01*
X2445632Y399477D01*
X2445787Y401352D01*
X2445632Y403227D01*
X2445167Y404894D01*
X2444547Y406144D01*
X2443617Y407185D01*
X2442377Y407602D01*
G01X2454777Y394685D02*
X2454467Y394894D01*
Y395310D01*
X2454777Y395519D01*
X2455087Y395310D01*
Y394894D01*
X2454777Y394685D01*
G01X2467177Y407602D02*
X2465937Y407185D01*
X2465007Y406144D01*
X2464387Y404894D01*
X2463922Y403227D01*
X2463767Y401352D01*
X2463922Y399477D01*
X2464387Y397810D01*
X2465007Y396560D01*
X2465937Y395519D01*
X2467177Y395102D01*
X2468417Y395519D01*
X2469347Y396560D01*
X2469967Y397810D01*
X2470432Y399477D01*
X2470587Y401352D01*
X2470432Y403227D01*
X2469967Y404894D01*
X2469347Y406144D01*
X2468417Y407185D01*
X2467177Y407602D01*
G01X2366272Y432869D02*
X2369992D01*
G01X2367977Y435577D02*
Y430160D01*
G01X2380377Y441202D02*
X2379137Y440785D01*
X2378207Y439744D01*
X2377587Y438494D01*
X2377122Y436827D01*
X2376967Y434952D01*
X2377122Y433077D01*
X2377587Y431410D01*
X2378207Y430160D01*
X2379137Y429119D01*
X2380377Y428702D01*
X2381617Y429119D01*
X2382547Y430160D01*
X2383167Y431410D01*
X2383632Y433077D01*
X2383787Y434952D01*
X2383632Y436827D01*
X2383167Y438494D01*
X2382547Y439744D01*
X2381617Y440785D01*
X2380377Y441202D01*
G01X2392777Y428285D02*
X2392467Y428494D01*
Y428910D01*
X2392777Y429119D01*
X2393087Y428910D01*
Y428494D01*
X2392777Y428285D01*
G01X2405177Y441202D02*
X2403937Y440785D01*
X2403007Y439744D01*
X2402387Y438494D01*
X2401922Y436827D01*
X2401767Y434952D01*
X2401922Y433077D01*
X2402387Y431410D01*
X2403007Y430160D01*
X2403937Y429119D01*
X2405177Y428702D01*
X2406417Y429119D01*
X2407347Y430160D01*
X2407967Y431410D01*
X2408432Y433077D01*
X2408587Y434952D01*
X2408432Y436827D01*
X2407967Y438494D01*
X2407347Y439744D01*
X2406417Y440785D01*
X2405177Y441202D01*
G01X2414787Y428285D02*
X2420367Y441202D01*
G01X2427962Y432869D02*
X2431992D01*
G01X2442377Y441202D02*
X2441137Y440785D01*
X2440207Y439744D01*
X2439587Y438494D01*
X2439122Y436827D01*
X2438967Y434952D01*
X2439122Y433077D01*
X2439587Y431410D01*
X2440207Y430160D01*
X2441137Y429119D01*
X2442377Y428702D01*
X2443617Y429119D01*
X2444547Y430160D01*
X2445167Y431410D01*
X2445632Y433077D01*
X2445787Y434952D01*
X2445632Y436827D01*
X2445167Y438494D01*
X2444547Y439744D01*
X2443617Y440785D01*
X2442377Y441202D01*
G01X2454777Y428285D02*
X2454467Y428494D01*
Y428910D01*
X2454777Y429119D01*
X2455087Y428910D01*
Y428494D01*
X2454777Y428285D01*
G01X2467177Y441202D02*
X2465937Y440785D01*
X2465007Y439744D01*
X2464387Y438494D01*
X2463922Y436827D01*
X2463767Y434952D01*
X2463922Y433077D01*
X2464387Y431410D01*
X2465007Y430160D01*
X2465937Y429119D01*
X2467177Y428702D01*
X2468417Y429119D01*
X2469347Y430160D01*
X2469967Y431410D01*
X2470432Y433077D01*
X2470587Y434952D01*
X2470432Y436827D01*
X2469967Y438494D01*
X2469347Y439744D01*
X2468417Y440785D01*
X2467177Y441202D01*
G01X2366272Y466469D02*
X2369992D01*
G01X2367977Y469177D02*
Y463760D01*
G01X2376967Y464802D02*
X2377897Y463343D01*
X2379137Y462510D01*
X2380532Y462302D01*
X2381772Y462510D01*
X2383012Y463552D01*
X2383787Y464802D01*
X2383942Y466052D01*
X2383632Y467510D01*
X2382547Y468552D01*
X2381462Y468969D01*
X2380067D01*
G01X2381462D02*
X2382392Y469594D01*
X2383167Y470635D01*
X2383477Y471885D01*
X2383167Y473135D01*
X2382392Y474177D01*
X2380997Y474802D01*
X2379602Y474594D01*
X2378207Y473760D01*
G01X2392777Y461885D02*
X2392467Y462094D01*
Y462510D01*
X2392777Y462719D01*
X2393087Y462510D01*
Y462094D01*
X2392777Y461885D01*
G01X2405177Y474802D02*
X2403937Y474385D01*
X2403007Y473344D01*
X2402387Y472094D01*
X2401922Y470427D01*
X2401767Y468552D01*
X2401922Y466677D01*
X2402387Y465010D01*
X2403007Y463760D01*
X2403937Y462719D01*
X2405177Y462302D01*
X2406417Y462719D01*
X2407347Y463760D01*
X2407967Y465010D01*
X2408432Y466677D01*
X2408587Y468552D01*
X2408432Y470427D01*
X2407967Y472094D01*
X2407347Y473344D01*
X2406417Y474385D01*
X2405177Y474802D01*
G01X2414787Y461885D02*
X2420367Y474802D01*
G01X2427962Y466469D02*
X2431992D01*
G01X2438967Y464802D02*
X2439897Y463343D01*
X2441137Y462510D01*
X2442532Y462302D01*
X2443772Y462510D01*
X2445012Y463552D01*
X2445787Y464802D01*
X2445942Y466052D01*
X2445632Y467510D01*
X2444547Y468552D01*
X2443462Y468969D01*
X2442067D01*
G01X2443462D02*
X2444392Y469594D01*
X2445167Y470635D01*
X2445477Y471885D01*
X2445167Y473135D01*
X2444392Y474177D01*
X2442997Y474802D01*
X2441602Y474594D01*
X2440207Y473760D01*
G01X2454777Y461885D02*
X2454467Y462094D01*
Y462510D01*
X2454777Y462719D01*
X2455087Y462510D01*
Y462094D01*
X2454777Y461885D01*
G01X2467177Y474802D02*
X2465937Y474385D01*
X2465007Y473344D01*
X2464387Y472094D01*
X2463922Y470427D01*
X2463767Y468552D01*
X2463922Y466677D01*
X2464387Y465010D01*
X2465007Y463760D01*
X2465937Y462719D01*
X2467177Y462302D01*
X2468417Y462719D01*
X2469347Y463760D01*
X2469967Y465010D01*
X2470432Y466677D01*
X2470587Y468552D01*
X2470432Y470427D01*
X2469967Y472094D01*
X2469347Y473344D01*
X2468417Y474385D01*
X2467177Y474802D01*
G01X2366272Y500069D02*
X2369992D01*
G01X2367977Y502777D02*
Y497360D01*
G01X2376967Y498402D02*
X2377897Y496943D01*
X2379137Y496110D01*
X2380532Y495902D01*
X2381772Y496110D01*
X2383012Y497152D01*
X2383787Y498402D01*
X2383942Y499652D01*
X2383632Y501110D01*
X2382547Y502152D01*
X2381462Y502569D01*
X2380067D01*
G01X2381462D02*
X2382392Y503194D01*
X2383167Y504235D01*
X2383477Y505485D01*
X2383167Y506735D01*
X2382392Y507777D01*
X2380997Y508402D01*
X2379602Y508194D01*
X2378207Y507360D01*
G01X2392777Y495485D02*
X2392467Y495694D01*
Y496110D01*
X2392777Y496319D01*
X2393087Y496110D01*
Y495694D01*
X2392777Y495485D01*
G01X2405177Y508402D02*
X2403937Y507985D01*
X2403007Y506944D01*
X2402387Y505694D01*
X2401922Y504027D01*
X2401767Y502152D01*
X2401922Y500277D01*
X2402387Y498610D01*
X2403007Y497360D01*
X2403937Y496319D01*
X2405177Y495902D01*
X2406417Y496319D01*
X2407347Y497360D01*
X2407967Y498610D01*
X2408432Y500277D01*
X2408587Y502152D01*
X2408432Y504027D01*
X2407967Y505694D01*
X2407347Y506944D01*
X2406417Y507985D01*
X2405177Y508402D01*
G01X2414787Y495485D02*
X2420367Y508402D01*
G01X2427962Y500069D02*
X2431992D01*
G01X2438967Y498402D02*
X2439897Y496943D01*
X2441137Y496110D01*
X2442532Y495902D01*
X2443772Y496110D01*
X2445012Y497152D01*
X2445787Y498402D01*
X2445942Y499652D01*
X2445632Y501110D01*
X2444547Y502152D01*
X2443462Y502569D01*
X2442067D01*
G01X2443462D02*
X2444392Y503194D01*
X2445167Y504235D01*
X2445477Y505485D01*
X2445167Y506735D01*
X2444392Y507777D01*
X2442997Y508402D01*
X2441602Y508194D01*
X2440207Y507360D01*
G01X2454777Y495485D02*
X2454467Y495694D01*
Y496110D01*
X2454777Y496319D01*
X2455087Y496110D01*
Y495694D01*
X2454777Y495485D01*
G01X2467177Y508402D02*
X2465937Y507985D01*
X2465007Y506944D01*
X2464387Y505694D01*
X2463922Y504027D01*
X2463767Y502152D01*
X2463922Y500277D01*
X2464387Y498610D01*
X2465007Y497360D01*
X2465937Y496319D01*
X2467177Y495902D01*
X2468417Y496319D01*
X2469347Y497360D01*
X2469967Y498610D01*
X2470432Y500277D01*
X2470587Y502152D01*
X2470432Y504027D01*
X2469967Y505694D01*
X2469347Y506944D01*
X2468417Y507985D01*
X2467177Y508402D01*
G01X2366272Y533669D02*
X2369992D01*
G01X2367977Y536377D02*
Y530960D01*
G01X2380377Y529502D02*
Y542002D01*
X2378517Y539502D01*
G01Y529502D02*
X2382237D01*
G01X2392777Y529085D02*
X2392467Y529294D01*
Y529710D01*
X2392777Y529919D01*
X2393087Y529710D01*
Y529294D01*
X2392777Y529085D01*
G01X2405177Y542002D02*
X2403937Y541585D01*
X2403007Y540544D01*
X2402387Y539294D01*
X2401922Y537627D01*
X2401767Y535752D01*
X2401922Y533877D01*
X2402387Y532210D01*
X2403007Y530960D01*
X2403937Y529919D01*
X2405177Y529502D01*
X2406417Y529919D01*
X2407347Y530960D01*
X2407967Y532210D01*
X2408432Y533877D01*
X2408587Y535752D01*
X2408432Y537627D01*
X2407967Y539294D01*
X2407347Y540544D01*
X2406417Y541585D01*
X2405177Y542002D01*
G01X2414787Y529085D02*
X2420367Y542002D01*
G01X2427962Y533669D02*
X2431992D01*
G01X2442377Y529502D02*
Y542002D01*
X2440517Y539502D01*
G01Y529502D02*
X2444237D01*
G01X2454777Y529085D02*
X2454467Y529294D01*
Y529710D01*
X2454777Y529919D01*
X2455087Y529710D01*
Y529294D01*
X2454777Y529085D01*
G01X2467177Y542002D02*
X2465937Y541585D01*
X2465007Y540544D01*
X2464387Y539294D01*
X2463922Y537627D01*
X2463767Y535752D01*
X2463922Y533877D01*
X2464387Y532210D01*
X2465007Y530960D01*
X2465937Y529919D01*
X2467177Y529502D01*
X2468417Y529919D01*
X2469347Y530960D01*
X2469967Y532210D01*
X2470432Y533877D01*
X2470587Y535752D01*
X2470432Y537627D01*
X2469967Y539294D01*
X2469347Y540544D01*
X2468417Y541585D01*
X2467177Y542002D01*
G01X2366272Y567269D02*
X2369992D01*
G01X2367977Y569977D02*
Y564560D01*
G01X2380377Y575602D02*
X2379137Y575185D01*
X2378207Y574144D01*
X2377587Y572894D01*
X2377122Y571227D01*
X2376967Y569352D01*
X2377122Y567477D01*
X2377587Y565810D01*
X2378207Y564560D01*
X2379137Y563519D01*
X2380377Y563102D01*
X2381617Y563519D01*
X2382547Y564560D01*
X2383167Y565810D01*
X2383632Y567477D01*
X2383787Y569352D01*
X2383632Y571227D01*
X2383167Y572894D01*
X2382547Y574144D01*
X2381617Y575185D01*
X2380377Y575602D01*
G01X2392777Y562685D02*
X2392467Y562894D01*
Y563310D01*
X2392777Y563519D01*
X2393087Y563310D01*
Y562894D01*
X2392777Y562685D01*
G01X2405177Y575602D02*
X2403937Y575185D01*
X2403007Y574144D01*
X2402387Y572894D01*
X2401922Y571227D01*
X2401767Y569352D01*
X2401922Y567477D01*
X2402387Y565810D01*
X2403007Y564560D01*
X2403937Y563519D01*
X2405177Y563102D01*
X2406417Y563519D01*
X2407347Y564560D01*
X2407967Y565810D01*
X2408432Y567477D01*
X2408587Y569352D01*
X2408432Y571227D01*
X2407967Y572894D01*
X2407347Y574144D01*
X2406417Y575185D01*
X2405177Y575602D01*
G01X2414787Y562685D02*
X2420367Y575602D01*
G01X2427962Y567269D02*
X2431992D01*
G01X2442377Y575602D02*
X2441137Y575185D01*
X2440207Y574144D01*
X2439587Y572894D01*
X2439122Y571227D01*
X2438967Y569352D01*
X2439122Y567477D01*
X2439587Y565810D01*
X2440207Y564560D01*
X2441137Y563519D01*
X2442377Y563102D01*
X2443617Y563519D01*
X2444547Y564560D01*
X2445167Y565810D01*
X2445632Y567477D01*
X2445787Y569352D01*
X2445632Y571227D01*
X2445167Y572894D01*
X2444547Y574144D01*
X2443617Y575185D01*
X2442377Y575602D01*
G01X2454777Y562685D02*
X2454467Y562894D01*
Y563310D01*
X2454777Y563519D01*
X2455087Y563310D01*
Y562894D01*
X2454777Y562685D01*
G01X2467177Y575602D02*
X2465937Y575185D01*
X2465007Y574144D01*
X2464387Y572894D01*
X2463922Y571227D01*
X2463767Y569352D01*
X2463922Y567477D01*
X2464387Y565810D01*
X2465007Y564560D01*
X2465937Y563519D01*
X2467177Y563102D01*
X2468417Y563519D01*
X2469347Y564560D01*
X2469967Y565810D01*
X2470432Y567477D01*
X2470587Y569352D01*
X2470432Y571227D01*
X2469967Y572894D01*
X2469347Y574144D01*
X2468417Y575185D01*
X2467177Y575602D01*
G01X2366272Y600869D02*
X2369992D01*
G01X2367977Y603577D02*
Y598160D01*
G01X2376967Y599202D02*
X2377897Y597743D01*
X2379137Y596910D01*
X2380532Y596702D01*
X2381772Y596910D01*
X2383012Y597952D01*
X2383787Y599202D01*
X2383942Y600452D01*
X2383632Y601910D01*
X2382547Y602952D01*
X2381462Y603369D01*
X2380067D01*
G01X2381462D02*
X2382392Y603994D01*
X2383167Y605035D01*
X2383477Y606285D01*
X2383167Y607535D01*
X2382392Y608577D01*
X2380997Y609202D01*
X2379602Y608994D01*
X2378207Y608160D01*
G01X2392777Y596285D02*
X2392467Y596494D01*
Y596910D01*
X2392777Y597119D01*
X2393087Y596910D01*
Y596494D01*
X2392777Y596285D01*
G01X2405177Y609202D02*
X2403937Y608785D01*
X2403007Y607744D01*
X2402387Y606494D01*
X2401922Y604827D01*
X2401767Y602952D01*
X2401922Y601077D01*
X2402387Y599410D01*
X2403007Y598160D01*
X2403937Y597119D01*
X2405177Y596702D01*
X2406417Y597119D01*
X2407347Y598160D01*
X2407967Y599410D01*
X2408432Y601077D01*
X2408587Y602952D01*
X2408432Y604827D01*
X2407967Y606494D01*
X2407347Y607744D01*
X2406417Y608785D01*
X2405177Y609202D01*
G01X2414787Y596285D02*
X2420367Y609202D01*
G01X2427962Y600869D02*
X2431992D01*
G01X2438967Y599202D02*
X2439897Y597743D01*
X2441137Y596910D01*
X2442532Y596702D01*
X2443772Y596910D01*
X2445012Y597952D01*
X2445787Y599202D01*
X2445942Y600452D01*
X2445632Y601910D01*
X2444547Y602952D01*
X2443462Y603369D01*
X2442067D01*
G01X2443462D02*
X2444392Y603994D01*
X2445167Y605035D01*
X2445477Y606285D01*
X2445167Y607535D01*
X2444392Y608577D01*
X2442997Y609202D01*
X2441602Y608994D01*
X2440207Y608160D01*
G01X2454777Y596285D02*
X2454467Y596494D01*
Y596910D01*
X2454777Y597119D01*
X2455087Y596910D01*
Y596494D01*
X2454777Y596285D01*
G01X2467177Y609202D02*
X2465937Y608785D01*
X2465007Y607744D01*
X2464387Y606494D01*
X2463922Y604827D01*
X2463767Y602952D01*
X2463922Y601077D01*
X2464387Y599410D01*
X2465007Y598160D01*
X2465937Y597119D01*
X2467177Y596702D01*
X2468417Y597119D01*
X2469347Y598160D01*
X2469967Y599410D01*
X2470432Y601077D01*
X2470587Y602952D01*
X2470432Y604827D01*
X2469967Y606494D01*
X2469347Y607744D01*
X2468417Y608785D01*
X2467177Y609202D01*
G01X2366272Y634469D02*
X2369992D01*
G01X2367977Y637177D02*
Y631760D01*
G01X2376967Y632802D02*
X2377897Y631343D01*
X2379137Y630510D01*
X2380532Y630302D01*
X2381772Y630510D01*
X2383012Y631552D01*
X2383787Y632802D01*
X2383942Y634052D01*
X2383632Y635510D01*
X2382547Y636552D01*
X2381462Y636969D01*
X2380067D01*
G01X2381462D02*
X2382392Y637594D01*
X2383167Y638635D01*
X2383477Y639885D01*
X2383167Y641135D01*
X2382392Y642177D01*
X2380997Y642802D01*
X2379602Y642594D01*
X2378207Y641760D01*
G01X2392777Y629885D02*
X2392467Y630094D01*
Y630510D01*
X2392777Y630719D01*
X2393087Y630510D01*
Y630094D01*
X2392777Y629885D01*
G01X2405177Y642802D02*
X2403937Y642385D01*
X2403007Y641344D01*
X2402387Y640094D01*
X2401922Y638427D01*
X2401767Y636552D01*
X2401922Y634677D01*
X2402387Y633010D01*
X2403007Y631760D01*
X2403937Y630719D01*
X2405177Y630302D01*
X2406417Y630719D01*
X2407347Y631760D01*
X2407967Y633010D01*
X2408432Y634677D01*
X2408587Y636552D01*
X2408432Y638427D01*
X2407967Y640094D01*
X2407347Y641344D01*
X2406417Y642385D01*
X2405177Y642802D01*
G01X2414787Y629885D02*
X2420367Y642802D01*
G01X2427962Y634469D02*
X2431992D01*
G01X2438967Y632802D02*
X2439897Y631343D01*
X2441137Y630510D01*
X2442532Y630302D01*
X2443772Y630510D01*
X2445012Y631552D01*
X2445787Y632802D01*
X2445942Y634052D01*
X2445632Y635510D01*
X2444547Y636552D01*
X2443462Y636969D01*
X2442067D01*
G01X2443462D02*
X2444392Y637594D01*
X2445167Y638635D01*
X2445477Y639885D01*
X2445167Y641135D01*
X2444392Y642177D01*
X2442997Y642802D01*
X2441602Y642594D01*
X2440207Y641760D01*
G01X2454777Y629885D02*
X2454467Y630094D01*
Y630510D01*
X2454777Y630719D01*
X2455087Y630510D01*
Y630094D01*
X2454777Y629885D01*
G01X2467177Y642802D02*
X2465937Y642385D01*
X2465007Y641344D01*
X2464387Y640094D01*
X2463922Y638427D01*
X2463767Y636552D01*
X2463922Y634677D01*
X2464387Y633010D01*
X2465007Y631760D01*
X2465937Y630719D01*
X2467177Y630302D01*
X2468417Y630719D01*
X2469347Y631760D01*
X2469967Y633010D01*
X2470432Y634677D01*
X2470587Y636552D01*
X2470432Y638427D01*
X2469967Y640094D01*
X2469347Y641344D01*
X2468417Y642385D01*
X2467177Y642802D01*
G01X2366272Y668069D02*
X2369992D01*
G01X2367977Y670777D02*
Y665360D01*
G01X2380377Y676402D02*
X2379137Y675985D01*
X2378207Y674944D01*
X2377587Y673694D01*
X2377122Y672027D01*
X2376967Y670152D01*
X2377122Y668277D01*
X2377587Y666610D01*
X2378207Y665360D01*
X2379137Y664319D01*
X2380377Y663902D01*
X2381617Y664319D01*
X2382547Y665360D01*
X2383167Y666610D01*
X2383632Y668277D01*
X2383787Y670152D01*
X2383632Y672027D01*
X2383167Y673694D01*
X2382547Y674944D01*
X2381617Y675985D01*
X2380377Y676402D01*
G01X2392777Y663485D02*
X2392467Y663694D01*
Y664110D01*
X2392777Y664319D01*
X2393087Y664110D01*
Y663694D01*
X2392777Y663485D01*
G01X2405177Y676402D02*
X2403937Y675985D01*
X2403007Y674944D01*
X2402387Y673694D01*
X2401922Y672027D01*
X2401767Y670152D01*
X2401922Y668277D01*
X2402387Y666610D01*
X2403007Y665360D01*
X2403937Y664319D01*
X2405177Y663902D01*
X2406417Y664319D01*
X2407347Y665360D01*
X2407967Y666610D01*
X2408432Y668277D01*
X2408587Y670152D01*
X2408432Y672027D01*
X2407967Y673694D01*
X2407347Y674944D01*
X2406417Y675985D01*
X2405177Y676402D01*
G01X2414787Y663485D02*
X2420367Y676402D01*
G01X2427962Y668069D02*
X2431992D01*
G01X2442377Y676402D02*
X2441137Y675985D01*
X2440207Y674944D01*
X2439587Y673694D01*
X2439122Y672027D01*
X2438967Y670152D01*
X2439122Y668277D01*
X2439587Y666610D01*
X2440207Y665360D01*
X2441137Y664319D01*
X2442377Y663902D01*
X2443617Y664319D01*
X2444547Y665360D01*
X2445167Y666610D01*
X2445632Y668277D01*
X2445787Y670152D01*
X2445632Y672027D01*
X2445167Y673694D01*
X2444547Y674944D01*
X2443617Y675985D01*
X2442377Y676402D01*
G01X2454777Y663485D02*
X2454467Y663694D01*
Y664110D01*
X2454777Y664319D01*
X2455087Y664110D01*
Y663694D01*
X2454777Y663485D01*
G01X2467177Y676402D02*
X2465937Y675985D01*
X2465007Y674944D01*
X2464387Y673694D01*
X2463922Y672027D01*
X2463767Y670152D01*
X2463922Y668277D01*
X2464387Y666610D01*
X2465007Y665360D01*
X2465937Y664319D01*
X2467177Y663902D01*
X2468417Y664319D01*
X2469347Y665360D01*
X2469967Y666610D01*
X2470432Y668277D01*
X2470587Y670152D01*
X2470432Y672027D01*
X2469967Y673694D01*
X2469347Y674944D01*
X2468417Y675985D01*
X2467177Y676402D01*
G01X2366272Y701669D02*
X2369992D01*
G01X2367977Y704377D02*
Y698960D01*
G01X2380377Y710002D02*
X2379137Y709585D01*
X2378207Y708544D01*
X2377587Y707294D01*
X2377122Y705627D01*
X2376967Y703752D01*
X2377122Y701877D01*
X2377587Y700210D01*
X2378207Y698960D01*
X2379137Y697919D01*
X2380377Y697502D01*
X2381617Y697919D01*
X2382547Y698960D01*
X2383167Y700210D01*
X2383632Y701877D01*
X2383787Y703752D01*
X2383632Y705627D01*
X2383167Y707294D01*
X2382547Y708544D01*
X2381617Y709585D01*
X2380377Y710002D01*
G01X2392777Y697085D02*
X2392467Y697294D01*
Y697710D01*
X2392777Y697919D01*
X2393087Y697710D01*
Y697294D01*
X2392777Y697085D01*
G01X2405177Y710002D02*
X2403937Y709585D01*
X2403007Y708544D01*
X2402387Y707294D01*
X2401922Y705627D01*
X2401767Y703752D01*
X2401922Y701877D01*
X2402387Y700210D01*
X2403007Y698960D01*
X2403937Y697919D01*
X2405177Y697502D01*
X2406417Y697919D01*
X2407347Y698960D01*
X2407967Y700210D01*
X2408432Y701877D01*
X2408587Y703752D01*
X2408432Y705627D01*
X2407967Y707294D01*
X2407347Y708544D01*
X2406417Y709585D01*
X2405177Y710002D01*
G01X2414787Y697085D02*
X2420367Y710002D01*
G01X2427962Y701669D02*
X2431992D01*
G01X2442377Y710002D02*
X2441137Y709585D01*
X2440207Y708544D01*
X2439587Y707294D01*
X2439122Y705627D01*
X2438967Y703752D01*
X2439122Y701877D01*
X2439587Y700210D01*
X2440207Y698960D01*
X2441137Y697919D01*
X2442377Y697502D01*
X2443617Y697919D01*
X2444547Y698960D01*
X2445167Y700210D01*
X2445632Y701877D01*
X2445787Y703752D01*
X2445632Y705627D01*
X2445167Y707294D01*
X2444547Y708544D01*
X2443617Y709585D01*
X2442377Y710002D01*
G01X2454777Y697085D02*
X2454467Y697294D01*
Y697710D01*
X2454777Y697919D01*
X2455087Y697710D01*
Y697294D01*
X2454777Y697085D01*
G01X2467177Y710002D02*
X2465937Y709585D01*
X2465007Y708544D01*
X2464387Y707294D01*
X2463922Y705627D01*
X2463767Y703752D01*
X2463922Y701877D01*
X2464387Y700210D01*
X2465007Y698960D01*
X2465937Y697919D01*
X2467177Y697502D01*
X2468417Y697919D01*
X2469347Y698960D01*
X2469967Y700210D01*
X2470432Y701877D01*
X2470587Y703752D01*
X2470432Y705627D01*
X2469967Y707294D01*
X2469347Y708544D01*
X2468417Y709585D01*
X2467177Y710002D01*
G01X2366272Y735269D02*
X2369992D01*
G01X2367977Y737977D02*
Y732560D01*
G01X2376967Y733602D02*
X2377897Y732143D01*
X2379137Y731310D01*
X2380532Y731102D01*
X2381772Y731310D01*
X2383012Y732352D01*
X2383787Y733602D01*
X2383942Y734852D01*
X2383632Y736310D01*
X2382547Y737352D01*
X2381462Y737769D01*
X2380067D01*
G01X2381462D02*
X2382392Y738394D01*
X2383167Y739435D01*
X2383477Y740685D01*
X2383167Y741935D01*
X2382392Y742977D01*
X2380997Y743602D01*
X2379602Y743394D01*
X2378207Y742560D01*
G01X2392777Y730685D02*
X2392467Y730894D01*
Y731310D01*
X2392777Y731519D01*
X2393087Y731310D01*
Y730894D01*
X2392777Y730685D01*
G01X2405177Y743602D02*
X2403937Y743185D01*
X2403007Y742144D01*
X2402387Y740894D01*
X2401922Y739227D01*
X2401767Y737352D01*
X2401922Y735477D01*
X2402387Y733810D01*
X2403007Y732560D01*
X2403937Y731519D01*
X2405177Y731102D01*
X2406417Y731519D01*
X2407347Y732560D01*
X2407967Y733810D01*
X2408432Y735477D01*
X2408587Y737352D01*
X2408432Y739227D01*
X2407967Y740894D01*
X2407347Y742144D01*
X2406417Y743185D01*
X2405177Y743602D01*
G01X2414787Y730685D02*
X2420367Y743602D01*
G01X2427962Y735269D02*
X2431992D01*
G01X2438967Y733602D02*
X2439897Y732143D01*
X2441137Y731310D01*
X2442532Y731102D01*
X2443772Y731310D01*
X2445012Y732352D01*
X2445787Y733602D01*
X2445942Y734852D01*
X2445632Y736310D01*
X2444547Y737352D01*
X2443462Y737769D01*
X2442067D01*
G01X2443462D02*
X2444392Y738394D01*
X2445167Y739435D01*
X2445477Y740685D01*
X2445167Y741935D01*
X2444392Y742977D01*
X2442997Y743602D01*
X2441602Y743394D01*
X2440207Y742560D01*
G01X2454777Y730685D02*
X2454467Y730894D01*
Y731310D01*
X2454777Y731519D01*
X2455087Y731310D01*
Y730894D01*
X2454777Y730685D01*
G01X2467177Y743602D02*
X2465937Y743185D01*
X2465007Y742144D01*
X2464387Y740894D01*
X2463922Y739227D01*
X2463767Y737352D01*
X2463922Y735477D01*
X2464387Y733810D01*
X2465007Y732560D01*
X2465937Y731519D01*
X2467177Y731102D01*
X2468417Y731519D01*
X2469347Y732560D01*
X2469967Y733810D01*
X2470432Y735477D01*
X2470587Y737352D01*
X2470432Y739227D01*
X2469967Y740894D01*
X2469347Y742144D01*
X2468417Y743185D01*
X2467177Y743602D01*
G01X2366272Y768869D02*
X2369992D01*
G01X2367977Y771577D02*
Y766160D01*
G01X2380377Y777202D02*
X2379137Y776785D01*
X2378207Y775744D01*
X2377587Y774494D01*
X2377122Y772827D01*
X2376967Y770952D01*
X2377122Y769077D01*
X2377587Y767410D01*
X2378207Y766160D01*
X2379137Y765119D01*
X2380377Y764702D01*
X2381617Y765119D01*
X2382547Y766160D01*
X2383167Y767410D01*
X2383632Y769077D01*
X2383787Y770952D01*
X2383632Y772827D01*
X2383167Y774494D01*
X2382547Y775744D01*
X2381617Y776785D01*
X2380377Y777202D01*
G01X2392777Y764285D02*
X2392467Y764494D01*
Y764910D01*
X2392777Y765119D01*
X2393087Y764910D01*
Y764494D01*
X2392777Y764285D01*
G01X2405177Y777202D02*
X2403937Y776785D01*
X2403007Y775744D01*
X2402387Y774494D01*
X2401922Y772827D01*
X2401767Y770952D01*
X2401922Y769077D01*
X2402387Y767410D01*
X2403007Y766160D01*
X2403937Y765119D01*
X2405177Y764702D01*
X2406417Y765119D01*
X2407347Y766160D01*
X2407967Y767410D01*
X2408432Y769077D01*
X2408587Y770952D01*
X2408432Y772827D01*
X2407967Y774494D01*
X2407347Y775744D01*
X2406417Y776785D01*
X2405177Y777202D01*
G01X2414787Y764285D02*
X2420367Y777202D01*
G01X2427962Y768869D02*
X2431992D01*
G01X2442377Y777202D02*
X2441137Y776785D01*
X2440207Y775744D01*
X2439587Y774494D01*
X2439122Y772827D01*
X2438967Y770952D01*
X2439122Y769077D01*
X2439587Y767410D01*
X2440207Y766160D01*
X2441137Y765119D01*
X2442377Y764702D01*
X2443617Y765119D01*
X2444547Y766160D01*
X2445167Y767410D01*
X2445632Y769077D01*
X2445787Y770952D01*
X2445632Y772827D01*
X2445167Y774494D01*
X2444547Y775744D01*
X2443617Y776785D01*
X2442377Y777202D01*
G01X2454777Y764285D02*
X2454467Y764494D01*
Y764910D01*
X2454777Y765119D01*
X2455087Y764910D01*
Y764494D01*
X2454777Y764285D01*
G01X2467177Y777202D02*
X2465937Y776785D01*
X2465007Y775744D01*
X2464387Y774494D01*
X2463922Y772827D01*
X2463767Y770952D01*
X2463922Y769077D01*
X2464387Y767410D01*
X2465007Y766160D01*
X2465937Y765119D01*
X2467177Y764702D01*
X2468417Y765119D01*
X2469347Y766160D01*
X2469967Y767410D01*
X2470432Y769077D01*
X2470587Y770952D01*
X2470432Y772827D01*
X2469967Y774494D01*
X2469347Y775744D01*
X2468417Y776785D01*
X2467177Y777202D01*
G01X2366272Y802469D02*
X2369992D01*
G01X2367977Y805177D02*
Y799760D01*
G01X2382237Y798302D02*
Y810802D01*
X2376502Y801844D01*
X2384252D01*
G01X2392777Y797885D02*
X2392467Y798094D01*
Y798510D01*
X2392777Y798719D01*
X2393087Y798510D01*
Y798094D01*
X2392777Y797885D01*
G01X2405177Y810802D02*
X2403937Y810385D01*
X2403007Y809344D01*
X2402387Y808094D01*
X2401922Y806427D01*
X2401767Y804552D01*
X2401922Y802677D01*
X2402387Y801010D01*
X2403007Y799760D01*
X2403937Y798719D01*
X2405177Y798302D01*
X2406417Y798719D01*
X2407347Y799760D01*
X2407967Y801010D01*
X2408432Y802677D01*
X2408587Y804552D01*
X2408432Y806427D01*
X2407967Y808094D01*
X2407347Y809344D01*
X2406417Y810385D01*
X2405177Y810802D01*
G01X2414787Y797885D02*
X2420367Y810802D01*
G01X2427962Y802469D02*
X2431992D01*
G01X2444237Y798302D02*
Y810802D01*
X2438502Y801844D01*
X2446252D01*
G01X2454777Y797885D02*
X2454467Y798094D01*
Y798510D01*
X2454777Y798719D01*
X2455087Y798510D01*
Y798094D01*
X2454777Y797885D01*
G01X2467177Y810802D02*
X2465937Y810385D01*
X2465007Y809344D01*
X2464387Y808094D01*
X2463922Y806427D01*
X2463767Y804552D01*
X2463922Y802677D01*
X2464387Y801010D01*
X2465007Y799760D01*
X2465937Y798719D01*
X2467177Y798302D01*
X2468417Y798719D01*
X2469347Y799760D01*
X2469967Y801010D01*
X2470432Y802677D01*
X2470587Y804552D01*
X2470432Y806427D01*
X2469967Y808094D01*
X2469347Y809344D01*
X2468417Y810385D01*
X2467177Y810802D01*
G01X2366272Y836069D02*
X2369992D01*
G01X2367977Y838777D02*
Y833360D01*
G01X2376967Y833777D02*
X2377897Y832735D01*
X2378982Y832110D01*
X2380377Y831902D01*
X2381772Y832319D01*
X2382857Y833152D01*
X2383632Y834610D01*
X2383787Y836277D01*
X2383477Y837944D01*
X2382702Y838985D01*
X2381617Y839819D01*
X2380532Y840027D01*
X2379447Y839819D01*
X2378052Y838985D01*
X2378517Y844402D01*
X2382702D01*
G01X2392777Y831485D02*
X2392467Y831694D01*
Y832110D01*
X2392777Y832319D01*
X2393087Y832110D01*
Y831694D01*
X2392777Y831485D01*
G01X2405177Y844402D02*
X2403937Y843985D01*
X2403007Y842944D01*
X2402387Y841694D01*
X2401922Y840027D01*
X2401767Y838152D01*
X2401922Y836277D01*
X2402387Y834610D01*
X2403007Y833360D01*
X2403937Y832319D01*
X2405177Y831902D01*
X2406417Y832319D01*
X2407347Y833360D01*
X2407967Y834610D01*
X2408432Y836277D01*
X2408587Y838152D01*
X2408432Y840027D01*
X2407967Y841694D01*
X2407347Y842944D01*
X2406417Y843985D01*
X2405177Y844402D01*
G01X2414787Y831485D02*
X2420367Y844402D01*
G01X2427962Y836069D02*
X2431992D01*
G01X2438967Y833777D02*
X2439897Y832735D01*
X2440982Y832110D01*
X2442377Y831902D01*
X2443772Y832319D01*
X2444857Y833152D01*
X2445632Y834610D01*
X2445787Y836277D01*
X2445477Y837944D01*
X2444702Y838985D01*
X2443617Y839819D01*
X2442532Y840027D01*
X2441447Y839819D01*
X2440052Y838985D01*
X2440517Y844402D01*
X2444702D01*
G01X2454777Y831485D02*
X2454467Y831694D01*
Y832110D01*
X2454777Y832319D01*
X2455087Y832110D01*
Y831694D01*
X2454777Y831485D01*
G01X2467177Y844402D02*
X2465937Y843985D01*
X2465007Y842944D01*
X2464387Y841694D01*
X2463922Y840027D01*
X2463767Y838152D01*
X2463922Y836277D01*
X2464387Y834610D01*
X2465007Y833360D01*
X2465937Y832319D01*
X2467177Y831902D01*
X2468417Y832319D01*
X2469347Y833360D01*
X2469967Y834610D01*
X2470432Y836277D01*
X2470587Y838152D01*
X2470432Y840027D01*
X2469967Y841694D01*
X2469347Y842944D01*
X2468417Y843985D01*
X2467177Y844402D01*
G01X2366272Y869669D02*
X2369992D01*
G01X2367977Y872377D02*
Y866960D01*
G01X2376967Y868002D02*
X2377897Y866543D01*
X2379137Y865710D01*
X2380532Y865502D01*
X2381772Y865710D01*
X2383012Y866752D01*
X2383787Y868002D01*
X2383942Y869252D01*
X2383632Y870710D01*
X2382547Y871752D01*
X2381462Y872169D01*
X2380067D01*
G01X2381462D02*
X2382392Y872794D01*
X2383167Y873835D01*
X2383477Y875085D01*
X2383167Y876335D01*
X2382392Y877377D01*
X2380997Y878002D01*
X2379602Y877794D01*
X2378207Y876960D01*
G01X2392777Y865085D02*
X2392467Y865294D01*
Y865710D01*
X2392777Y865919D01*
X2393087Y865710D01*
Y865294D01*
X2392777Y865085D01*
G01X2405177Y878002D02*
X2403937Y877585D01*
X2403007Y876544D01*
X2402387Y875294D01*
X2401922Y873627D01*
X2401767Y871752D01*
X2401922Y869877D01*
X2402387Y868210D01*
X2403007Y866960D01*
X2403937Y865919D01*
X2405177Y865502D01*
X2406417Y865919D01*
X2407347Y866960D01*
X2407967Y868210D01*
X2408432Y869877D01*
X2408587Y871752D01*
X2408432Y873627D01*
X2407967Y875294D01*
X2407347Y876544D01*
X2406417Y877585D01*
X2405177Y878002D01*
G01X2414787Y865085D02*
X2420367Y878002D01*
G01X2427962Y869669D02*
X2431992D01*
G01X2438967Y868002D02*
X2439897Y866543D01*
X2441137Y865710D01*
X2442532Y865502D01*
X2443772Y865710D01*
X2445012Y866752D01*
X2445787Y868002D01*
X2445942Y869252D01*
X2445632Y870710D01*
X2444547Y871752D01*
X2443462Y872169D01*
X2442067D01*
G01X2443462D02*
X2444392Y872794D01*
X2445167Y873835D01*
X2445477Y875085D01*
X2445167Y876335D01*
X2444392Y877377D01*
X2442997Y878002D01*
X2441602Y877794D01*
X2440207Y876960D01*
G01X2454777Y865085D02*
X2454467Y865294D01*
Y865710D01*
X2454777Y865919D01*
X2455087Y865710D01*
Y865294D01*
X2454777Y865085D01*
G01X2467177Y878002D02*
X2465937Y877585D01*
X2465007Y876544D01*
X2464387Y875294D01*
X2463922Y873627D01*
X2463767Y871752D01*
X2463922Y869877D01*
X2464387Y868210D01*
X2465007Y866960D01*
X2465937Y865919D01*
X2467177Y865502D01*
X2468417Y865919D01*
X2469347Y866960D01*
X2469967Y868210D01*
X2470432Y869877D01*
X2470587Y871752D01*
X2470432Y873627D01*
X2469967Y875294D01*
X2469347Y876544D01*
X2468417Y877585D01*
X2467177Y878002D01*
G01X2366272Y903269D02*
X2369992D01*
G01X2367977Y905977D02*
Y900560D01*
G01X2376967Y901602D02*
X2377897Y900143D01*
X2379137Y899310D01*
X2380532Y899102D01*
X2381772Y899310D01*
X2383012Y900352D01*
X2383787Y901602D01*
X2383942Y902852D01*
X2383632Y904310D01*
X2382547Y905352D01*
X2381462Y905769D01*
X2380067D01*
G01X2381462D02*
X2382392Y906394D01*
X2383167Y907435D01*
X2383477Y908685D01*
X2383167Y909935D01*
X2382392Y910977D01*
X2380997Y911602D01*
X2379602Y911394D01*
X2378207Y910560D01*
G01X2392777Y898685D02*
X2392467Y898894D01*
Y899310D01*
X2392777Y899519D01*
X2393087Y899310D01*
Y898894D01*
X2392777Y898685D01*
G01X2405177Y911602D02*
X2403937Y911185D01*
X2403007Y910144D01*
X2402387Y908894D01*
X2401922Y907227D01*
X2401767Y905352D01*
X2401922Y903477D01*
X2402387Y901810D01*
X2403007Y900560D01*
X2403937Y899519D01*
X2405177Y899102D01*
X2406417Y899519D01*
X2407347Y900560D01*
X2407967Y901810D01*
X2408432Y903477D01*
X2408587Y905352D01*
X2408432Y907227D01*
X2407967Y908894D01*
X2407347Y910144D01*
X2406417Y911185D01*
X2405177Y911602D01*
G01X2414787Y898685D02*
X2420367Y911602D01*
G01X2427962Y903269D02*
X2431992D01*
G01X2438967Y901602D02*
X2439897Y900143D01*
X2441137Y899310D01*
X2442532Y899102D01*
X2443772Y899310D01*
X2445012Y900352D01*
X2445787Y901602D01*
X2445942Y902852D01*
X2445632Y904310D01*
X2444547Y905352D01*
X2443462Y905769D01*
X2442067D01*
G01X2443462D02*
X2444392Y906394D01*
X2445167Y907435D01*
X2445477Y908685D01*
X2445167Y909935D01*
X2444392Y910977D01*
X2442997Y911602D01*
X2441602Y911394D01*
X2440207Y910560D01*
G01X2454777Y898685D02*
X2454467Y898894D01*
Y899310D01*
X2454777Y899519D01*
X2455087Y899310D01*
Y898894D01*
X2454777Y898685D01*
G01X2467177Y911602D02*
X2465937Y911185D01*
X2465007Y910144D01*
X2464387Y908894D01*
X2463922Y907227D01*
X2463767Y905352D01*
X2463922Y903477D01*
X2464387Y901810D01*
X2465007Y900560D01*
X2465937Y899519D01*
X2467177Y899102D01*
X2468417Y899519D01*
X2469347Y900560D01*
X2469967Y901810D01*
X2470432Y903477D01*
X2470587Y905352D01*
X2470432Y907227D01*
X2469967Y908894D01*
X2469347Y910144D01*
X2468417Y911185D01*
X2467177Y911602D01*
G01X2366272Y936869D02*
X2369992D01*
G01X2367977Y939577D02*
Y934160D01*
G01X2380377Y945202D02*
X2379137Y944785D01*
X2378207Y943744D01*
X2377587Y942494D01*
X2377122Y940827D01*
X2376967Y938952D01*
X2377122Y937077D01*
X2377587Y935410D01*
X2378207Y934160D01*
X2379137Y933119D01*
X2380377Y932702D01*
X2381617Y933119D01*
X2382547Y934160D01*
X2383167Y935410D01*
X2383632Y937077D01*
X2383787Y938952D01*
X2383632Y940827D01*
X2383167Y942494D01*
X2382547Y943744D01*
X2381617Y944785D01*
X2380377Y945202D01*
G01X2392777Y932285D02*
X2392467Y932494D01*
Y932910D01*
X2392777Y933119D01*
X2393087Y932910D01*
Y932494D01*
X2392777Y932285D01*
G01X2405177Y945202D02*
X2403937Y944785D01*
X2403007Y943744D01*
X2402387Y942494D01*
X2401922Y940827D01*
X2401767Y938952D01*
X2401922Y937077D01*
X2402387Y935410D01*
X2403007Y934160D01*
X2403937Y933119D01*
X2405177Y932702D01*
X2406417Y933119D01*
X2407347Y934160D01*
X2407967Y935410D01*
X2408432Y937077D01*
X2408587Y938952D01*
X2408432Y940827D01*
X2407967Y942494D01*
X2407347Y943744D01*
X2406417Y944785D01*
X2405177Y945202D01*
G01X2414787Y932285D02*
X2420367Y945202D01*
G01X2427962Y936869D02*
X2431992D01*
G01X2442377Y945202D02*
X2441137Y944785D01*
X2440207Y943744D01*
X2439587Y942494D01*
X2439122Y940827D01*
X2438967Y938952D01*
X2439122Y937077D01*
X2439587Y935410D01*
X2440207Y934160D01*
X2441137Y933119D01*
X2442377Y932702D01*
X2443617Y933119D01*
X2444547Y934160D01*
X2445167Y935410D01*
X2445632Y937077D01*
X2445787Y938952D01*
X2445632Y940827D01*
X2445167Y942494D01*
X2444547Y943744D01*
X2443617Y944785D01*
X2442377Y945202D01*
G01X2454777Y932285D02*
X2454467Y932494D01*
Y932910D01*
X2454777Y933119D01*
X2455087Y932910D01*
Y932494D01*
X2454777Y932285D01*
G01X2467177Y945202D02*
X2465937Y944785D01*
X2465007Y943744D01*
X2464387Y942494D01*
X2463922Y940827D01*
X2463767Y938952D01*
X2463922Y937077D01*
X2464387Y935410D01*
X2465007Y934160D01*
X2465937Y933119D01*
X2467177Y932702D01*
X2468417Y933119D01*
X2469347Y934160D01*
X2469967Y935410D01*
X2470432Y937077D01*
X2470587Y938952D01*
X2470432Y940827D01*
X2469967Y942494D01*
X2469347Y943744D01*
X2468417Y944785D01*
X2467177Y945202D01*
G01X2366272Y970469D02*
X2369992D01*
G01X2367977Y973177D02*
Y967760D01*
G01X2376967Y968802D02*
X2377897Y967343D01*
X2379137Y966510D01*
X2380532Y966302D01*
X2381772Y966510D01*
X2383012Y967552D01*
X2383787Y968802D01*
X2383942Y970052D01*
X2383632Y971510D01*
X2382547Y972552D01*
X2381462Y972969D01*
X2380067D01*
G01X2381462D02*
X2382392Y973594D01*
X2383167Y974635D01*
X2383477Y975885D01*
X2383167Y977135D01*
X2382392Y978177D01*
X2380997Y978802D01*
X2379602Y978594D01*
X2378207Y977760D01*
G01X2392777Y965885D02*
X2392467Y966094D01*
Y966510D01*
X2392777Y966719D01*
X2393087Y966510D01*
Y966094D01*
X2392777Y965885D01*
G01X2405177Y978802D02*
X2403937Y978385D01*
X2403007Y977344D01*
X2402387Y976094D01*
X2401922Y974427D01*
X2401767Y972552D01*
X2401922Y970677D01*
X2402387Y969010D01*
X2403007Y967760D01*
X2403937Y966719D01*
X2405177Y966302D01*
X2406417Y966719D01*
X2407347Y967760D01*
X2407967Y969010D01*
X2408432Y970677D01*
X2408587Y972552D01*
X2408432Y974427D01*
X2407967Y976094D01*
X2407347Y977344D01*
X2406417Y978385D01*
X2405177Y978802D01*
G01X2414787Y965885D02*
X2420367Y978802D01*
G01X2427962Y970469D02*
X2431992D01*
G01X2438967Y968802D02*
X2439897Y967343D01*
X2441137Y966510D01*
X2442532Y966302D01*
X2443772Y966510D01*
X2445012Y967552D01*
X2445787Y968802D01*
X2445942Y970052D01*
X2445632Y971510D01*
X2444547Y972552D01*
X2443462Y972969D01*
X2442067D01*
G01X2443462D02*
X2444392Y973594D01*
X2445167Y974635D01*
X2445477Y975885D01*
X2445167Y977135D01*
X2444392Y978177D01*
X2442997Y978802D01*
X2441602Y978594D01*
X2440207Y977760D01*
G01X2454777Y965885D02*
X2454467Y966094D01*
Y966510D01*
X2454777Y966719D01*
X2455087Y966510D01*
Y966094D01*
X2454777Y965885D01*
G01X2467177Y978802D02*
X2465937Y978385D01*
X2465007Y977344D01*
X2464387Y976094D01*
X2463922Y974427D01*
X2463767Y972552D01*
X2463922Y970677D01*
X2464387Y969010D01*
X2465007Y967760D01*
X2465937Y966719D01*
X2467177Y966302D01*
X2468417Y966719D01*
X2469347Y967760D01*
X2469967Y969010D01*
X2470432Y970677D01*
X2470587Y972552D01*
X2470432Y974427D01*
X2469967Y976094D01*
X2469347Y977344D01*
X2468417Y978385D01*
X2467177Y978802D01*
G01X2366272Y1004069D02*
X2369992D01*
G01X2367977Y1006777D02*
Y1001360D01*
G01X2376967Y1002402D02*
X2377897Y1000943D01*
X2379137Y1000110D01*
X2380532Y999902D01*
X2381772Y1000110D01*
X2383012Y1001152D01*
X2383787Y1002402D01*
X2383942Y1003652D01*
X2383632Y1005110D01*
X2382547Y1006152D01*
X2381462Y1006569D01*
X2380067D01*
G01X2381462D02*
X2382392Y1007194D01*
X2383167Y1008235D01*
X2383477Y1009485D01*
X2383167Y1010735D01*
X2382392Y1011777D01*
X2380997Y1012402D01*
X2379602Y1012194D01*
X2378207Y1011360D01*
G01X2392777Y999485D02*
X2392467Y999694D01*
Y1000110D01*
X2392777Y1000319D01*
X2393087Y1000110D01*
Y999694D01*
X2392777Y999485D01*
G01X2405177Y1012402D02*
X2403937Y1011985D01*
X2403007Y1010944D01*
X2402387Y1009694D01*
X2401922Y1008027D01*
X2401767Y1006152D01*
X2401922Y1004277D01*
X2402387Y1002610D01*
X2403007Y1001360D01*
X2403937Y1000319D01*
X2405177Y999902D01*
X2406417Y1000319D01*
X2407347Y1001360D01*
X2407967Y1002610D01*
X2408432Y1004277D01*
X2408587Y1006152D01*
X2408432Y1008027D01*
X2407967Y1009694D01*
X2407347Y1010944D01*
X2406417Y1011985D01*
X2405177Y1012402D01*
G01X2414787Y999485D02*
X2420367Y1012402D01*
G01X2427962Y1004069D02*
X2431992D01*
G01X2438967Y1002402D02*
X2439897Y1000943D01*
X2441137Y1000110D01*
X2442532Y999902D01*
X2443772Y1000110D01*
X2445012Y1001152D01*
X2445787Y1002402D01*
X2445942Y1003652D01*
X2445632Y1005110D01*
X2444547Y1006152D01*
X2443462Y1006569D01*
X2442067D01*
G01X2443462D02*
X2444392Y1007194D01*
X2445167Y1008235D01*
X2445477Y1009485D01*
X2445167Y1010735D01*
X2444392Y1011777D01*
X2442997Y1012402D01*
X2441602Y1012194D01*
X2440207Y1011360D01*
G01X2454777Y999485D02*
X2454467Y999694D01*
Y1000110D01*
X2454777Y1000319D01*
X2455087Y1000110D01*
Y999694D01*
X2454777Y999485D01*
G01X2467177Y1012402D02*
X2465937Y1011985D01*
X2465007Y1010944D01*
X2464387Y1009694D01*
X2463922Y1008027D01*
X2463767Y1006152D01*
X2463922Y1004277D01*
X2464387Y1002610D01*
X2465007Y1001360D01*
X2465937Y1000319D01*
X2467177Y999902D01*
X2468417Y1000319D01*
X2469347Y1001360D01*
X2469967Y1002610D01*
X2470432Y1004277D01*
X2470587Y1006152D01*
X2470432Y1008027D01*
X2469967Y1009694D01*
X2469347Y1010944D01*
X2468417Y1011985D01*
X2467177Y1012402D01*
G01X2366272Y1037669D02*
X2369992D01*
G01X2367977Y1040377D02*
Y1034960D01*
G01X2380377Y1046002D02*
X2379137Y1045585D01*
X2378207Y1044544D01*
X2377587Y1043294D01*
X2377122Y1041627D01*
X2376967Y1039752D01*
X2377122Y1037877D01*
X2377587Y1036210D01*
X2378207Y1034960D01*
X2379137Y1033919D01*
X2380377Y1033502D01*
X2381617Y1033919D01*
X2382547Y1034960D01*
X2383167Y1036210D01*
X2383632Y1037877D01*
X2383787Y1039752D01*
X2383632Y1041627D01*
X2383167Y1043294D01*
X2382547Y1044544D01*
X2381617Y1045585D01*
X2380377Y1046002D01*
G01X2392777Y1033085D02*
X2392467Y1033294D01*
Y1033710D01*
X2392777Y1033919D01*
X2393087Y1033710D01*
Y1033294D01*
X2392777Y1033085D01*
G01X2405177Y1046002D02*
X2403937Y1045585D01*
X2403007Y1044544D01*
X2402387Y1043294D01*
X2401922Y1041627D01*
X2401767Y1039752D01*
X2401922Y1037877D01*
X2402387Y1036210D01*
X2403007Y1034960D01*
X2403937Y1033919D01*
X2405177Y1033502D01*
X2406417Y1033919D01*
X2407347Y1034960D01*
X2407967Y1036210D01*
X2408432Y1037877D01*
X2408587Y1039752D01*
X2408432Y1041627D01*
X2407967Y1043294D01*
X2407347Y1044544D01*
X2406417Y1045585D01*
X2405177Y1046002D01*
G01X2414787Y1033085D02*
X2420367Y1046002D01*
G01X2427962Y1037669D02*
X2431992D01*
G01X2442377Y1046002D02*
X2441137Y1045585D01*
X2440207Y1044544D01*
X2439587Y1043294D01*
X2439122Y1041627D01*
X2438967Y1039752D01*
X2439122Y1037877D01*
X2439587Y1036210D01*
X2440207Y1034960D01*
X2441137Y1033919D01*
X2442377Y1033502D01*
X2443617Y1033919D01*
X2444547Y1034960D01*
X2445167Y1036210D01*
X2445632Y1037877D01*
X2445787Y1039752D01*
X2445632Y1041627D01*
X2445167Y1043294D01*
X2444547Y1044544D01*
X2443617Y1045585D01*
X2442377Y1046002D01*
G01X2454777Y1033085D02*
X2454467Y1033294D01*
Y1033710D01*
X2454777Y1033919D01*
X2455087Y1033710D01*
Y1033294D01*
X2454777Y1033085D01*
G01X2467177Y1046002D02*
X2465937Y1045585D01*
X2465007Y1044544D01*
X2464387Y1043294D01*
X2463922Y1041627D01*
X2463767Y1039752D01*
X2463922Y1037877D01*
X2464387Y1036210D01*
X2465007Y1034960D01*
X2465937Y1033919D01*
X2467177Y1033502D01*
X2468417Y1033919D01*
X2469347Y1034960D01*
X2469967Y1036210D01*
X2470432Y1037877D01*
X2470587Y1039752D01*
X2470432Y1041627D01*
X2469967Y1043294D01*
X2469347Y1044544D01*
X2468417Y1045585D01*
X2467177Y1046002D01*
G01X2366272Y1071269D02*
X2369992D01*
G01X2367977Y1073977D02*
Y1068560D01*
G01X2376967Y1069602D02*
X2377897Y1068143D01*
X2379137Y1067310D01*
X2380532Y1067102D01*
X2381772Y1067310D01*
X2383012Y1068352D01*
X2383787Y1069602D01*
X2383942Y1070852D01*
X2383632Y1072310D01*
X2382547Y1073352D01*
X2381462Y1073769D01*
X2380067D01*
G01X2381462D02*
X2382392Y1074394D01*
X2383167Y1075435D01*
X2383477Y1076685D01*
X2383167Y1077935D01*
X2382392Y1078977D01*
X2380997Y1079602D01*
X2379602Y1079394D01*
X2378207Y1078560D01*
G01X2392777Y1066685D02*
X2392467Y1066894D01*
Y1067310D01*
X2392777Y1067519D01*
X2393087Y1067310D01*
Y1066894D01*
X2392777Y1066685D01*
G01X2405177Y1079602D02*
X2403937Y1079185D01*
X2403007Y1078144D01*
X2402387Y1076894D01*
X2401922Y1075227D01*
X2401767Y1073352D01*
X2401922Y1071477D01*
X2402387Y1069810D01*
X2403007Y1068560D01*
X2403937Y1067519D01*
X2405177Y1067102D01*
X2406417Y1067519D01*
X2407347Y1068560D01*
X2407967Y1069810D01*
X2408432Y1071477D01*
X2408587Y1073352D01*
X2408432Y1075227D01*
X2407967Y1076894D01*
X2407347Y1078144D01*
X2406417Y1079185D01*
X2405177Y1079602D01*
G01X2414787Y1066685D02*
X2420367Y1079602D01*
G01X2427962Y1071269D02*
X2431992D01*
G01X2438967Y1069602D02*
X2439897Y1068143D01*
X2441137Y1067310D01*
X2442532Y1067102D01*
X2443772Y1067310D01*
X2445012Y1068352D01*
X2445787Y1069602D01*
X2445942Y1070852D01*
X2445632Y1072310D01*
X2444547Y1073352D01*
X2443462Y1073769D01*
X2442067D01*
G01X2443462D02*
X2444392Y1074394D01*
X2445167Y1075435D01*
X2445477Y1076685D01*
X2445167Y1077935D01*
X2444392Y1078977D01*
X2442997Y1079602D01*
X2441602Y1079394D01*
X2440207Y1078560D01*
G01X2454777Y1066685D02*
X2454467Y1066894D01*
Y1067310D01*
X2454777Y1067519D01*
X2455087Y1067310D01*
Y1066894D01*
X2454777Y1066685D01*
G01X2467177Y1079602D02*
X2465937Y1079185D01*
X2465007Y1078144D01*
X2464387Y1076894D01*
X2463922Y1075227D01*
X2463767Y1073352D01*
X2463922Y1071477D01*
X2464387Y1069810D01*
X2465007Y1068560D01*
X2465937Y1067519D01*
X2467177Y1067102D01*
X2468417Y1067519D01*
X2469347Y1068560D01*
X2469967Y1069810D01*
X2470432Y1071477D01*
X2470587Y1073352D01*
X2470432Y1075227D01*
X2469967Y1076894D01*
X2469347Y1078144D01*
X2468417Y1079185D01*
X2467177Y1079602D01*
G01X2366272Y1104869D02*
X2369992D01*
G01X2367977Y1107577D02*
Y1102160D01*
G01X2380377Y1113202D02*
X2379137Y1112785D01*
X2378207Y1111744D01*
X2377587Y1110494D01*
X2377122Y1108827D01*
X2376967Y1106952D01*
X2377122Y1105077D01*
X2377587Y1103410D01*
X2378207Y1102160D01*
X2379137Y1101119D01*
X2380377Y1100702D01*
X2381617Y1101119D01*
X2382547Y1102160D01*
X2383167Y1103410D01*
X2383632Y1105077D01*
X2383787Y1106952D01*
X2383632Y1108827D01*
X2383167Y1110494D01*
X2382547Y1111744D01*
X2381617Y1112785D01*
X2380377Y1113202D01*
G01X2392777Y1100285D02*
X2392467Y1100494D01*
Y1100910D01*
X2392777Y1101119D01*
X2393087Y1100910D01*
Y1100494D01*
X2392777Y1100285D01*
G01X2405177Y1113202D02*
X2403937Y1112785D01*
X2403007Y1111744D01*
X2402387Y1110494D01*
X2401922Y1108827D01*
X2401767Y1106952D01*
X2401922Y1105077D01*
X2402387Y1103410D01*
X2403007Y1102160D01*
X2403937Y1101119D01*
X2405177Y1100702D01*
X2406417Y1101119D01*
X2407347Y1102160D01*
X2407967Y1103410D01*
X2408432Y1105077D01*
X2408587Y1106952D01*
X2408432Y1108827D01*
X2407967Y1110494D01*
X2407347Y1111744D01*
X2406417Y1112785D01*
X2405177Y1113202D01*
G01X2414787Y1100285D02*
X2420367Y1113202D01*
G01X2427962Y1104869D02*
X2431992D01*
G01X2442377Y1113202D02*
X2441137Y1112785D01*
X2440207Y1111744D01*
X2439587Y1110494D01*
X2439122Y1108827D01*
X2438967Y1106952D01*
X2439122Y1105077D01*
X2439587Y1103410D01*
X2440207Y1102160D01*
X2441137Y1101119D01*
X2442377Y1100702D01*
X2443617Y1101119D01*
X2444547Y1102160D01*
X2445167Y1103410D01*
X2445632Y1105077D01*
X2445787Y1106952D01*
X2445632Y1108827D01*
X2445167Y1110494D01*
X2444547Y1111744D01*
X2443617Y1112785D01*
X2442377Y1113202D01*
G01X2454777Y1100285D02*
X2454467Y1100494D01*
Y1100910D01*
X2454777Y1101119D01*
X2455087Y1100910D01*
Y1100494D01*
X2454777Y1100285D01*
G01X2467177Y1113202D02*
X2465937Y1112785D01*
X2465007Y1111744D01*
X2464387Y1110494D01*
X2463922Y1108827D01*
X2463767Y1106952D01*
X2463922Y1105077D01*
X2464387Y1103410D01*
X2465007Y1102160D01*
X2465937Y1101119D01*
X2467177Y1100702D01*
X2468417Y1101119D01*
X2469347Y1102160D01*
X2469967Y1103410D01*
X2470432Y1105077D01*
X2470587Y1106952D01*
X2470432Y1108827D01*
X2469967Y1110494D01*
X2469347Y1111744D01*
X2468417Y1112785D01*
X2467177Y1113202D01*
G01X2366272Y1138469D02*
X2369992D01*
G01X2367977Y1141177D02*
Y1135760D01*
G01X2376967Y1136802D02*
X2377897Y1135343D01*
X2379137Y1134510D01*
X2380532Y1134302D01*
X2381772Y1134510D01*
X2383012Y1135552D01*
X2383787Y1136802D01*
X2383942Y1138052D01*
X2383632Y1139510D01*
X2382547Y1140552D01*
X2381462Y1140969D01*
X2380067D01*
G01X2381462D02*
X2382392Y1141594D01*
X2383167Y1142635D01*
X2383477Y1143885D01*
X2383167Y1145135D01*
X2382392Y1146177D01*
X2380997Y1146802D01*
X2379602Y1146594D01*
X2378207Y1145760D01*
G01X2392777Y1133885D02*
X2392467Y1134094D01*
Y1134510D01*
X2392777Y1134719D01*
X2393087Y1134510D01*
Y1134094D01*
X2392777Y1133885D01*
G01X2405177Y1146802D02*
X2403937Y1146385D01*
X2403007Y1145344D01*
X2402387Y1144094D01*
X2401922Y1142427D01*
X2401767Y1140552D01*
X2401922Y1138677D01*
X2402387Y1137010D01*
X2403007Y1135760D01*
X2403937Y1134719D01*
X2405177Y1134302D01*
X2406417Y1134719D01*
X2407347Y1135760D01*
X2407967Y1137010D01*
X2408432Y1138677D01*
X2408587Y1140552D01*
X2408432Y1142427D01*
X2407967Y1144094D01*
X2407347Y1145344D01*
X2406417Y1146385D01*
X2405177Y1146802D01*
G01X2414787Y1133885D02*
X2420367Y1146802D01*
G01X2427962Y1138469D02*
X2431992D01*
G01X2438967Y1136802D02*
X2439897Y1135343D01*
X2441137Y1134510D01*
X2442532Y1134302D01*
X2443772Y1134510D01*
X2445012Y1135552D01*
X2445787Y1136802D01*
X2445942Y1138052D01*
X2445632Y1139510D01*
X2444547Y1140552D01*
X2443462Y1140969D01*
X2442067D01*
G01X2443462D02*
X2444392Y1141594D01*
X2445167Y1142635D01*
X2445477Y1143885D01*
X2445167Y1145135D01*
X2444392Y1146177D01*
X2442997Y1146802D01*
X2441602Y1146594D01*
X2440207Y1145760D01*
G01X2454777Y1133885D02*
X2454467Y1134094D01*
Y1134510D01*
X2454777Y1134719D01*
X2455087Y1134510D01*
Y1134094D01*
X2454777Y1133885D01*
G01X2467177Y1146802D02*
X2465937Y1146385D01*
X2465007Y1145344D01*
X2464387Y1144094D01*
X2463922Y1142427D01*
X2463767Y1140552D01*
X2463922Y1138677D01*
X2464387Y1137010D01*
X2465007Y1135760D01*
X2465937Y1134719D01*
X2467177Y1134302D01*
X2468417Y1134719D01*
X2469347Y1135760D01*
X2469967Y1137010D01*
X2470432Y1138677D01*
X2470587Y1140552D01*
X2470432Y1142427D01*
X2469967Y1144094D01*
X2469347Y1145344D01*
X2468417Y1146385D01*
X2467177Y1146802D01*
G01X2366272Y1172069D02*
X2369992D01*
G01X2367977Y1174777D02*
Y1169360D01*
G01X2380377Y1180402D02*
X2379137Y1179985D01*
X2378207Y1178944D01*
X2377587Y1177694D01*
X2377122Y1176027D01*
X2376967Y1174152D01*
X2377122Y1172277D01*
X2377587Y1170610D01*
X2378207Y1169360D01*
X2379137Y1168319D01*
X2380377Y1167902D01*
X2381617Y1168319D01*
X2382547Y1169360D01*
X2383167Y1170610D01*
X2383632Y1172277D01*
X2383787Y1174152D01*
X2383632Y1176027D01*
X2383167Y1177694D01*
X2382547Y1178944D01*
X2381617Y1179985D01*
X2380377Y1180402D01*
G01X2392777Y1167485D02*
X2392467Y1167694D01*
Y1168110D01*
X2392777Y1168319D01*
X2393087Y1168110D01*
Y1167694D01*
X2392777Y1167485D01*
G01X2405177Y1180402D02*
X2403937Y1179985D01*
X2403007Y1178944D01*
X2402387Y1177694D01*
X2401922Y1176027D01*
X2401767Y1174152D01*
X2401922Y1172277D01*
X2402387Y1170610D01*
X2403007Y1169360D01*
X2403937Y1168319D01*
X2405177Y1167902D01*
X2406417Y1168319D01*
X2407347Y1169360D01*
X2407967Y1170610D01*
X2408432Y1172277D01*
X2408587Y1174152D01*
X2408432Y1176027D01*
X2407967Y1177694D01*
X2407347Y1178944D01*
X2406417Y1179985D01*
X2405177Y1180402D01*
G01X2414787Y1167485D02*
X2420367Y1180402D01*
G01X2427962Y1172069D02*
X2431992D01*
G01X2442377Y1180402D02*
X2441137Y1179985D01*
X2440207Y1178944D01*
X2439587Y1177694D01*
X2439122Y1176027D01*
X2438967Y1174152D01*
X2439122Y1172277D01*
X2439587Y1170610D01*
X2440207Y1169360D01*
X2441137Y1168319D01*
X2442377Y1167902D01*
X2443617Y1168319D01*
X2444547Y1169360D01*
X2445167Y1170610D01*
X2445632Y1172277D01*
X2445787Y1174152D01*
X2445632Y1176027D01*
X2445167Y1177694D01*
X2444547Y1178944D01*
X2443617Y1179985D01*
X2442377Y1180402D01*
G01X2454777Y1167485D02*
X2454467Y1167694D01*
Y1168110D01*
X2454777Y1168319D01*
X2455087Y1168110D01*
Y1167694D01*
X2454777Y1167485D01*
G01X2467177Y1180402D02*
X2465937Y1179985D01*
X2465007Y1178944D01*
X2464387Y1177694D01*
X2463922Y1176027D01*
X2463767Y1174152D01*
X2463922Y1172277D01*
X2464387Y1170610D01*
X2465007Y1169360D01*
X2465937Y1168319D01*
X2467177Y1167902D01*
X2468417Y1168319D01*
X2469347Y1169360D01*
X2469967Y1170610D01*
X2470432Y1172277D01*
X2470587Y1174152D01*
X2470432Y1176027D01*
X2469967Y1177694D01*
X2469347Y1178944D01*
X2468417Y1179985D01*
X2467177Y1180402D01*
G01X2366272Y1205669D02*
X2369992D01*
G01X2367977Y1208377D02*
Y1202960D01*
G01X2380377Y1214002D02*
X2379137Y1213585D01*
X2378207Y1212544D01*
X2377587Y1211294D01*
X2377122Y1209627D01*
X2376967Y1207752D01*
X2377122Y1205877D01*
X2377587Y1204210D01*
X2378207Y1202960D01*
X2379137Y1201919D01*
X2380377Y1201502D01*
X2381617Y1201919D01*
X2382547Y1202960D01*
X2383167Y1204210D01*
X2383632Y1205877D01*
X2383787Y1207752D01*
X2383632Y1209627D01*
X2383167Y1211294D01*
X2382547Y1212544D01*
X2381617Y1213585D01*
X2380377Y1214002D01*
G01X2392777Y1201085D02*
X2392467Y1201294D01*
Y1201710D01*
X2392777Y1201919D01*
X2393087Y1201710D01*
Y1201294D01*
X2392777Y1201085D01*
G01X2405177Y1214002D02*
X2403937Y1213585D01*
X2403007Y1212544D01*
X2402387Y1211294D01*
X2401922Y1209627D01*
X2401767Y1207752D01*
X2401922Y1205877D01*
X2402387Y1204210D01*
X2403007Y1202960D01*
X2403937Y1201919D01*
X2405177Y1201502D01*
X2406417Y1201919D01*
X2407347Y1202960D01*
X2407967Y1204210D01*
X2408432Y1205877D01*
X2408587Y1207752D01*
X2408432Y1209627D01*
X2407967Y1211294D01*
X2407347Y1212544D01*
X2406417Y1213585D01*
X2405177Y1214002D01*
G01X2414787Y1201085D02*
X2420367Y1214002D01*
G01X2427962Y1205669D02*
X2431992D01*
G01X2442377Y1214002D02*
X2441137Y1213585D01*
X2440207Y1212544D01*
X2439587Y1211294D01*
X2439122Y1209627D01*
X2438967Y1207752D01*
X2439122Y1205877D01*
X2439587Y1204210D01*
X2440207Y1202960D01*
X2441137Y1201919D01*
X2442377Y1201502D01*
X2443617Y1201919D01*
X2444547Y1202960D01*
X2445167Y1204210D01*
X2445632Y1205877D01*
X2445787Y1207752D01*
X2445632Y1209627D01*
X2445167Y1211294D01*
X2444547Y1212544D01*
X2443617Y1213585D01*
X2442377Y1214002D01*
G01X2454777Y1201085D02*
X2454467Y1201294D01*
Y1201710D01*
X2454777Y1201919D01*
X2455087Y1201710D01*
Y1201294D01*
X2454777Y1201085D01*
G01X2467177Y1214002D02*
X2465937Y1213585D01*
X2465007Y1212544D01*
X2464387Y1211294D01*
X2463922Y1209627D01*
X2463767Y1207752D01*
X2463922Y1205877D01*
X2464387Y1204210D01*
X2465007Y1202960D01*
X2465937Y1201919D01*
X2467177Y1201502D01*
X2468417Y1201919D01*
X2469347Y1202960D01*
X2469967Y1204210D01*
X2470432Y1205877D01*
X2470587Y1207752D01*
X2470432Y1209627D01*
X2469967Y1211294D01*
X2469347Y1212544D01*
X2468417Y1213585D01*
X2467177Y1214002D01*
G01X2366272Y1239269D02*
X2369992D01*
G01X2367977Y1241977D02*
Y1236560D01*
G01X2376967Y1237602D02*
X2377897Y1236143D01*
X2379137Y1235310D01*
X2380532Y1235102D01*
X2381772Y1235310D01*
X2383012Y1236352D01*
X2383787Y1237602D01*
X2383942Y1238852D01*
X2383632Y1240310D01*
X2382547Y1241352D01*
X2381462Y1241769D01*
X2380067D01*
G01X2381462D02*
X2382392Y1242394D01*
X2383167Y1243435D01*
X2383477Y1244685D01*
X2383167Y1245935D01*
X2382392Y1246977D01*
X2380997Y1247602D01*
X2379602Y1247394D01*
X2378207Y1246560D01*
G01X2392777Y1234685D02*
X2392467Y1234894D01*
Y1235310D01*
X2392777Y1235519D01*
X2393087Y1235310D01*
Y1234894D01*
X2392777Y1234685D01*
G01X2405177Y1247602D02*
X2403937Y1247185D01*
X2403007Y1246144D01*
X2402387Y1244894D01*
X2401922Y1243227D01*
X2401767Y1241352D01*
X2401922Y1239477D01*
X2402387Y1237810D01*
X2403007Y1236560D01*
X2403937Y1235519D01*
X2405177Y1235102D01*
X2406417Y1235519D01*
X2407347Y1236560D01*
X2407967Y1237810D01*
X2408432Y1239477D01*
X2408587Y1241352D01*
X2408432Y1243227D01*
X2407967Y1244894D01*
X2407347Y1246144D01*
X2406417Y1247185D01*
X2405177Y1247602D01*
G01X2414787Y1234685D02*
X2420367Y1247602D01*
G01X2427962Y1239269D02*
X2431992D01*
G01X2438967Y1237602D02*
X2439897Y1236143D01*
X2441137Y1235310D01*
X2442532Y1235102D01*
X2443772Y1235310D01*
X2445012Y1236352D01*
X2445787Y1237602D01*
X2445942Y1238852D01*
X2445632Y1240310D01*
X2444547Y1241352D01*
X2443462Y1241769D01*
X2442067D01*
G01X2443462D02*
X2444392Y1242394D01*
X2445167Y1243435D01*
X2445477Y1244685D01*
X2445167Y1245935D01*
X2444392Y1246977D01*
X2442997Y1247602D01*
X2441602Y1247394D01*
X2440207Y1246560D01*
G01X2454777Y1234685D02*
X2454467Y1234894D01*
Y1235310D01*
X2454777Y1235519D01*
X2455087Y1235310D01*
Y1234894D01*
X2454777Y1234685D01*
G01X2467177Y1247602D02*
X2465937Y1247185D01*
X2465007Y1246144D01*
X2464387Y1244894D01*
X2463922Y1243227D01*
X2463767Y1241352D01*
X2463922Y1239477D01*
X2464387Y1237810D01*
X2465007Y1236560D01*
X2465937Y1235519D01*
X2467177Y1235102D01*
X2468417Y1235519D01*
X2469347Y1236560D01*
X2469967Y1237810D01*
X2470432Y1239477D01*
X2470587Y1241352D01*
X2470432Y1243227D01*
X2469967Y1244894D01*
X2469347Y1246144D01*
X2468417Y1247185D01*
X2467177Y1247602D01*
G01X2366272Y1272869D02*
X2369992D01*
G01X2367977Y1275577D02*
Y1270160D01*
G01X2380377Y1281202D02*
X2379137Y1280785D01*
X2378207Y1279744D01*
X2377587Y1278494D01*
X2377122Y1276827D01*
X2376967Y1274952D01*
X2377122Y1273077D01*
X2377587Y1271410D01*
X2378207Y1270160D01*
X2379137Y1269119D01*
X2380377Y1268702D01*
X2381617Y1269119D01*
X2382547Y1270160D01*
X2383167Y1271410D01*
X2383632Y1273077D01*
X2383787Y1274952D01*
X2383632Y1276827D01*
X2383167Y1278494D01*
X2382547Y1279744D01*
X2381617Y1280785D01*
X2380377Y1281202D01*
G01X2392777Y1268285D02*
X2392467Y1268494D01*
Y1268910D01*
X2392777Y1269119D01*
X2393087Y1268910D01*
Y1268494D01*
X2392777Y1268285D01*
G01X2405177Y1281202D02*
X2403937Y1280785D01*
X2403007Y1279744D01*
X2402387Y1278494D01*
X2401922Y1276827D01*
X2401767Y1274952D01*
X2401922Y1273077D01*
X2402387Y1271410D01*
X2403007Y1270160D01*
X2403937Y1269119D01*
X2405177Y1268702D01*
X2406417Y1269119D01*
X2407347Y1270160D01*
X2407967Y1271410D01*
X2408432Y1273077D01*
X2408587Y1274952D01*
X2408432Y1276827D01*
X2407967Y1278494D01*
X2407347Y1279744D01*
X2406417Y1280785D01*
X2405177Y1281202D01*
G01X2414787Y1268285D02*
X2420367Y1281202D01*
G01X2427962Y1272869D02*
X2431992D01*
G01X2442377Y1281202D02*
X2441137Y1280785D01*
X2440207Y1279744D01*
X2439587Y1278494D01*
X2439122Y1276827D01*
X2438967Y1274952D01*
X2439122Y1273077D01*
X2439587Y1271410D01*
X2440207Y1270160D01*
X2441137Y1269119D01*
X2442377Y1268702D01*
X2443617Y1269119D01*
X2444547Y1270160D01*
X2445167Y1271410D01*
X2445632Y1273077D01*
X2445787Y1274952D01*
X2445632Y1276827D01*
X2445167Y1278494D01*
X2444547Y1279744D01*
X2443617Y1280785D01*
X2442377Y1281202D01*
G01X2454777Y1268285D02*
X2454467Y1268494D01*
Y1268910D01*
X2454777Y1269119D01*
X2455087Y1268910D01*
Y1268494D01*
X2454777Y1268285D01*
G01X2467177Y1281202D02*
X2465937Y1280785D01*
X2465007Y1279744D01*
X2464387Y1278494D01*
X2463922Y1276827D01*
X2463767Y1274952D01*
X2463922Y1273077D01*
X2464387Y1271410D01*
X2465007Y1270160D01*
X2465937Y1269119D01*
X2467177Y1268702D01*
X2468417Y1269119D01*
X2469347Y1270160D01*
X2469967Y1271410D01*
X2470432Y1273077D01*
X2470587Y1274952D01*
X2470432Y1276827D01*
X2469967Y1278494D01*
X2469347Y1279744D01*
X2468417Y1280785D01*
X2467177Y1281202D01*
G01X2366272Y1306469D02*
X2369992D01*
G01X2367977Y1309177D02*
Y1303760D01*
G01X2376967Y1304802D02*
X2377897Y1303343D01*
X2379137Y1302510D01*
X2380532Y1302302D01*
X2381772Y1302510D01*
X2383012Y1303552D01*
X2383787Y1304802D01*
X2383942Y1306052D01*
X2383632Y1307510D01*
X2382547Y1308552D01*
X2381462Y1308969D01*
X2380067D01*
G01X2381462D02*
X2382392Y1309594D01*
X2383167Y1310635D01*
X2383477Y1311885D01*
X2383167Y1313135D01*
X2382392Y1314177D01*
X2380997Y1314802D01*
X2379602Y1314594D01*
X2378207Y1313760D01*
G01X2392777Y1301885D02*
X2392467Y1302094D01*
Y1302510D01*
X2392777Y1302719D01*
X2393087Y1302510D01*
Y1302094D01*
X2392777Y1301885D01*
G01X2405177Y1314802D02*
X2403937Y1314385D01*
X2403007Y1313344D01*
X2402387Y1312094D01*
X2401922Y1310427D01*
X2401767Y1308552D01*
X2401922Y1306677D01*
X2402387Y1305010D01*
X2403007Y1303760D01*
X2403937Y1302719D01*
X2405177Y1302302D01*
X2406417Y1302719D01*
X2407347Y1303760D01*
X2407967Y1305010D01*
X2408432Y1306677D01*
X2408587Y1308552D01*
X2408432Y1310427D01*
X2407967Y1312094D01*
X2407347Y1313344D01*
X2406417Y1314385D01*
X2405177Y1314802D01*
G01X2414787Y1301885D02*
X2420367Y1314802D01*
G01X2427962Y1306469D02*
X2431992D01*
G01X2438967Y1304802D02*
X2439897Y1303343D01*
X2441137Y1302510D01*
X2442532Y1302302D01*
X2443772Y1302510D01*
X2445012Y1303552D01*
X2445787Y1304802D01*
X2445942Y1306052D01*
X2445632Y1307510D01*
X2444547Y1308552D01*
X2443462Y1308969D01*
X2442067D01*
G01X2443462D02*
X2444392Y1309594D01*
X2445167Y1310635D01*
X2445477Y1311885D01*
X2445167Y1313135D01*
X2444392Y1314177D01*
X2442997Y1314802D01*
X2441602Y1314594D01*
X2440207Y1313760D01*
G01X2454777Y1301885D02*
X2454467Y1302094D01*
Y1302510D01*
X2454777Y1302719D01*
X2455087Y1302510D01*
Y1302094D01*
X2454777Y1301885D01*
G01X2467177Y1314802D02*
X2465937Y1314385D01*
X2465007Y1313344D01*
X2464387Y1312094D01*
X2463922Y1310427D01*
X2463767Y1308552D01*
X2463922Y1306677D01*
X2464387Y1305010D01*
X2465007Y1303760D01*
X2465937Y1302719D01*
X2467177Y1302302D01*
X2468417Y1302719D01*
X2469347Y1303760D01*
X2469967Y1305010D01*
X2470432Y1306677D01*
X2470587Y1308552D01*
X2470432Y1310427D01*
X2469967Y1312094D01*
X2469347Y1313344D01*
X2468417Y1314385D01*
X2467177Y1314802D01*
G01X2366272Y1340069D02*
X2369992D01*
G01X2367977Y1342777D02*
Y1337360D01*
G01X2380377Y1348402D02*
X2379137Y1347985D01*
X2378207Y1346944D01*
X2377587Y1345694D01*
X2377122Y1344027D01*
X2376967Y1342152D01*
X2377122Y1340277D01*
X2377587Y1338610D01*
X2378207Y1337360D01*
X2379137Y1336319D01*
X2380377Y1335902D01*
X2381617Y1336319D01*
X2382547Y1337360D01*
X2383167Y1338610D01*
X2383632Y1340277D01*
X2383787Y1342152D01*
X2383632Y1344027D01*
X2383167Y1345694D01*
X2382547Y1346944D01*
X2381617Y1347985D01*
X2380377Y1348402D01*
G01X2392777Y1335485D02*
X2392467Y1335694D01*
Y1336110D01*
X2392777Y1336319D01*
X2393087Y1336110D01*
Y1335694D01*
X2392777Y1335485D01*
G01X2405177Y1348402D02*
X2403937Y1347985D01*
X2403007Y1346944D01*
X2402387Y1345694D01*
X2401922Y1344027D01*
X2401767Y1342152D01*
X2401922Y1340277D01*
X2402387Y1338610D01*
X2403007Y1337360D01*
X2403937Y1336319D01*
X2405177Y1335902D01*
X2406417Y1336319D01*
X2407347Y1337360D01*
X2407967Y1338610D01*
X2408432Y1340277D01*
X2408587Y1342152D01*
X2408432Y1344027D01*
X2407967Y1345694D01*
X2407347Y1346944D01*
X2406417Y1347985D01*
X2405177Y1348402D01*
G01X2414787Y1335485D02*
X2420367Y1348402D01*
G01X2427962Y1340069D02*
X2431992D01*
G01X2442377Y1348402D02*
X2441137Y1347985D01*
X2440207Y1346944D01*
X2439587Y1345694D01*
X2439122Y1344027D01*
X2438967Y1342152D01*
X2439122Y1340277D01*
X2439587Y1338610D01*
X2440207Y1337360D01*
X2441137Y1336319D01*
X2442377Y1335902D01*
X2443617Y1336319D01*
X2444547Y1337360D01*
X2445167Y1338610D01*
X2445632Y1340277D01*
X2445787Y1342152D01*
X2445632Y1344027D01*
X2445167Y1345694D01*
X2444547Y1346944D01*
X2443617Y1347985D01*
X2442377Y1348402D01*
G01X2454777Y1335485D02*
X2454467Y1335694D01*
Y1336110D01*
X2454777Y1336319D01*
X2455087Y1336110D01*
Y1335694D01*
X2454777Y1335485D01*
G01X2467177Y1348402D02*
X2465937Y1347985D01*
X2465007Y1346944D01*
X2464387Y1345694D01*
X2463922Y1344027D01*
X2463767Y1342152D01*
X2463922Y1340277D01*
X2464387Y1338610D01*
X2465007Y1337360D01*
X2465937Y1336319D01*
X2467177Y1335902D01*
X2468417Y1336319D01*
X2469347Y1337360D01*
X2469967Y1338610D01*
X2470432Y1340277D01*
X2470587Y1342152D01*
X2470432Y1344027D01*
X2469967Y1345694D01*
X2469347Y1346944D01*
X2468417Y1347985D01*
X2467177Y1348402D01*
G01X2366272Y1373669D02*
X2369992D01*
G01X2367977Y1376377D02*
Y1370960D01*
G01X2380377Y1382002D02*
X2379137Y1381585D01*
X2378207Y1380544D01*
X2377587Y1379294D01*
X2377122Y1377627D01*
X2376967Y1375752D01*
X2377122Y1373877D01*
X2377587Y1372210D01*
X2378207Y1370960D01*
X2379137Y1369919D01*
X2380377Y1369502D01*
X2381617Y1369919D01*
X2382547Y1370960D01*
X2383167Y1372210D01*
X2383632Y1373877D01*
X2383787Y1375752D01*
X2383632Y1377627D01*
X2383167Y1379294D01*
X2382547Y1380544D01*
X2381617Y1381585D01*
X2380377Y1382002D01*
G01X2392777Y1369085D02*
X2392467Y1369294D01*
Y1369710D01*
X2392777Y1369919D01*
X2393087Y1369710D01*
Y1369294D01*
X2392777Y1369085D01*
G01X2405177Y1382002D02*
X2403937Y1381585D01*
X2403007Y1380544D01*
X2402387Y1379294D01*
X2401922Y1377627D01*
X2401767Y1375752D01*
X2401922Y1373877D01*
X2402387Y1372210D01*
X2403007Y1370960D01*
X2403937Y1369919D01*
X2405177Y1369502D01*
X2406417Y1369919D01*
X2407347Y1370960D01*
X2407967Y1372210D01*
X2408432Y1373877D01*
X2408587Y1375752D01*
X2408432Y1377627D01*
X2407967Y1379294D01*
X2407347Y1380544D01*
X2406417Y1381585D01*
X2405177Y1382002D01*
G01X2414787Y1369085D02*
X2420367Y1382002D01*
G01X2427962Y1373669D02*
X2431992D01*
G01X2442377Y1382002D02*
X2441137Y1381585D01*
X2440207Y1380544D01*
X2439587Y1379294D01*
X2439122Y1377627D01*
X2438967Y1375752D01*
X2439122Y1373877D01*
X2439587Y1372210D01*
X2440207Y1370960D01*
X2441137Y1369919D01*
X2442377Y1369502D01*
X2443617Y1369919D01*
X2444547Y1370960D01*
X2445167Y1372210D01*
X2445632Y1373877D01*
X2445787Y1375752D01*
X2445632Y1377627D01*
X2445167Y1379294D01*
X2444547Y1380544D01*
X2443617Y1381585D01*
X2442377Y1382002D01*
G01X2454777Y1369085D02*
X2454467Y1369294D01*
Y1369710D01*
X2454777Y1369919D01*
X2455087Y1369710D01*
Y1369294D01*
X2454777Y1369085D01*
G01X2467177Y1382002D02*
X2465937Y1381585D01*
X2465007Y1380544D01*
X2464387Y1379294D01*
X2463922Y1377627D01*
X2463767Y1375752D01*
X2463922Y1373877D01*
X2464387Y1372210D01*
X2465007Y1370960D01*
X2465937Y1369919D01*
X2467177Y1369502D01*
X2468417Y1369919D01*
X2469347Y1370960D01*
X2469967Y1372210D01*
X2470432Y1373877D01*
X2470587Y1375752D01*
X2470432Y1377627D01*
X2469967Y1379294D01*
X2469347Y1380544D01*
X2468417Y1381585D01*
X2467177Y1382002D01*
G01X2366272Y1407269D02*
X2369992D01*
G01X2367977Y1409977D02*
Y1404560D01*
G01X2380377Y1415602D02*
X2379137Y1415185D01*
X2378207Y1414144D01*
X2377587Y1412894D01*
X2377122Y1411227D01*
X2376967Y1409352D01*
X2377122Y1407477D01*
X2377587Y1405810D01*
X2378207Y1404560D01*
X2379137Y1403519D01*
X2380377Y1403102D01*
X2381617Y1403519D01*
X2382547Y1404560D01*
X2383167Y1405810D01*
X2383632Y1407477D01*
X2383787Y1409352D01*
X2383632Y1411227D01*
X2383167Y1412894D01*
X2382547Y1414144D01*
X2381617Y1415185D01*
X2380377Y1415602D01*
G01X2392777Y1402685D02*
X2392467Y1402894D01*
Y1403310D01*
X2392777Y1403519D01*
X2393087Y1403310D01*
Y1402894D01*
X2392777Y1402685D01*
G01X2405177Y1415602D02*
X2403937Y1415185D01*
X2403007Y1414144D01*
X2402387Y1412894D01*
X2401922Y1411227D01*
X2401767Y1409352D01*
X2401922Y1407477D01*
X2402387Y1405810D01*
X2403007Y1404560D01*
X2403937Y1403519D01*
X2405177Y1403102D01*
X2406417Y1403519D01*
X2407347Y1404560D01*
X2407967Y1405810D01*
X2408432Y1407477D01*
X2408587Y1409352D01*
X2408432Y1411227D01*
X2407967Y1412894D01*
X2407347Y1414144D01*
X2406417Y1415185D01*
X2405177Y1415602D01*
G01X2414787Y1402685D02*
X2420367Y1415602D01*
G01X2427962Y1407269D02*
X2431992D01*
G01X2442377Y1415602D02*
X2441137Y1415185D01*
X2440207Y1414144D01*
X2439587Y1412894D01*
X2439122Y1411227D01*
X2438967Y1409352D01*
X2439122Y1407477D01*
X2439587Y1405810D01*
X2440207Y1404560D01*
X2441137Y1403519D01*
X2442377Y1403102D01*
X2443617Y1403519D01*
X2444547Y1404560D01*
X2445167Y1405810D01*
X2445632Y1407477D01*
X2445787Y1409352D01*
X2445632Y1411227D01*
X2445167Y1412894D01*
X2444547Y1414144D01*
X2443617Y1415185D01*
X2442377Y1415602D01*
G01X2454777Y1402685D02*
X2454467Y1402894D01*
Y1403310D01*
X2454777Y1403519D01*
X2455087Y1403310D01*
Y1402894D01*
X2454777Y1402685D01*
G01X2467177Y1415602D02*
X2465937Y1415185D01*
X2465007Y1414144D01*
X2464387Y1412894D01*
X2463922Y1411227D01*
X2463767Y1409352D01*
X2463922Y1407477D01*
X2464387Y1405810D01*
X2465007Y1404560D01*
X2465937Y1403519D01*
X2467177Y1403102D01*
X2468417Y1403519D01*
X2469347Y1404560D01*
X2469967Y1405810D01*
X2470432Y1407477D01*
X2470587Y1409352D01*
X2470432Y1411227D01*
X2469967Y1412894D01*
X2469347Y1414144D01*
X2468417Y1415185D01*
X2467177Y1415602D01*
G01X2366272Y1440869D02*
X2369992D01*
G01X2367977Y1443577D02*
Y1438160D01*
G01X2376967Y1439202D02*
X2377897Y1437743D01*
X2379137Y1436910D01*
X2380532Y1436702D01*
X2381772Y1436910D01*
X2383012Y1437952D01*
X2383787Y1439202D01*
X2383942Y1440452D01*
X2383632Y1441910D01*
X2382547Y1442952D01*
X2381462Y1443369D01*
X2380067D01*
G01X2381462D02*
X2382392Y1443994D01*
X2383167Y1445035D01*
X2383477Y1446285D01*
X2383167Y1447535D01*
X2382392Y1448577D01*
X2380997Y1449202D01*
X2379602Y1448994D01*
X2378207Y1448160D01*
G01X2392777Y1436285D02*
X2392467Y1436494D01*
Y1436910D01*
X2392777Y1437119D01*
X2393087Y1436910D01*
Y1436494D01*
X2392777Y1436285D01*
G01X2405177Y1449202D02*
X2403937Y1448785D01*
X2403007Y1447744D01*
X2402387Y1446494D01*
X2401922Y1444827D01*
X2401767Y1442952D01*
X2401922Y1441077D01*
X2402387Y1439410D01*
X2403007Y1438160D01*
X2403937Y1437119D01*
X2405177Y1436702D01*
X2406417Y1437119D01*
X2407347Y1438160D01*
X2407967Y1439410D01*
X2408432Y1441077D01*
X2408587Y1442952D01*
X2408432Y1444827D01*
X2407967Y1446494D01*
X2407347Y1447744D01*
X2406417Y1448785D01*
X2405177Y1449202D01*
G01X2414787Y1436285D02*
X2420367Y1449202D01*
G01X2427962Y1440869D02*
X2431992D01*
G01X2438967Y1439202D02*
X2439897Y1437743D01*
X2441137Y1436910D01*
X2442532Y1436702D01*
X2443772Y1436910D01*
X2445012Y1437952D01*
X2445787Y1439202D01*
X2445942Y1440452D01*
X2445632Y1441910D01*
X2444547Y1442952D01*
X2443462Y1443369D01*
X2442067D01*
G01X2443462D02*
X2444392Y1443994D01*
X2445167Y1445035D01*
X2445477Y1446285D01*
X2445167Y1447535D01*
X2444392Y1448577D01*
X2442997Y1449202D01*
X2441602Y1448994D01*
X2440207Y1448160D01*
G01X2454777Y1436285D02*
X2454467Y1436494D01*
Y1436910D01*
X2454777Y1437119D01*
X2455087Y1436910D01*
Y1436494D01*
X2454777Y1436285D01*
G01X2467177Y1449202D02*
X2465937Y1448785D01*
X2465007Y1447744D01*
X2464387Y1446494D01*
X2463922Y1444827D01*
X2463767Y1442952D01*
X2463922Y1441077D01*
X2464387Y1439410D01*
X2465007Y1438160D01*
X2465937Y1437119D01*
X2467177Y1436702D01*
X2468417Y1437119D01*
X2469347Y1438160D01*
X2469967Y1439410D01*
X2470432Y1441077D01*
X2470587Y1442952D01*
X2470432Y1444827D01*
X2469967Y1446494D01*
X2469347Y1447744D01*
X2468417Y1448785D01*
X2467177Y1449202D01*
G01X2366272Y1474469D02*
X2369992D01*
G01X2367977Y1477177D02*
Y1471760D01*
G01X2380377Y1482802D02*
X2379137Y1482385D01*
X2378207Y1481344D01*
X2377587Y1480094D01*
X2377122Y1478427D01*
X2376967Y1476552D01*
X2377122Y1474677D01*
X2377587Y1473010D01*
X2378207Y1471760D01*
X2379137Y1470719D01*
X2380377Y1470302D01*
X2381617Y1470719D01*
X2382547Y1471760D01*
X2383167Y1473010D01*
X2383632Y1474677D01*
X2383787Y1476552D01*
X2383632Y1478427D01*
X2383167Y1480094D01*
X2382547Y1481344D01*
X2381617Y1482385D01*
X2380377Y1482802D01*
G01X2392777Y1469885D02*
X2392467Y1470094D01*
Y1470510D01*
X2392777Y1470719D01*
X2393087Y1470510D01*
Y1470094D01*
X2392777Y1469885D01*
G01X2405177Y1482802D02*
X2403937Y1482385D01*
X2403007Y1481344D01*
X2402387Y1480094D01*
X2401922Y1478427D01*
X2401767Y1476552D01*
X2401922Y1474677D01*
X2402387Y1473010D01*
X2403007Y1471760D01*
X2403937Y1470719D01*
X2405177Y1470302D01*
X2406417Y1470719D01*
X2407347Y1471760D01*
X2407967Y1473010D01*
X2408432Y1474677D01*
X2408587Y1476552D01*
X2408432Y1478427D01*
X2407967Y1480094D01*
X2407347Y1481344D01*
X2406417Y1482385D01*
X2405177Y1482802D01*
G01X2414787Y1469885D02*
X2420367Y1482802D01*
G01X2427962Y1474469D02*
X2431992D01*
G01X2442377Y1482802D02*
X2441137Y1482385D01*
X2440207Y1481344D01*
X2439587Y1480094D01*
X2439122Y1478427D01*
X2438967Y1476552D01*
X2439122Y1474677D01*
X2439587Y1473010D01*
X2440207Y1471760D01*
X2441137Y1470719D01*
X2442377Y1470302D01*
X2443617Y1470719D01*
X2444547Y1471760D01*
X2445167Y1473010D01*
X2445632Y1474677D01*
X2445787Y1476552D01*
X2445632Y1478427D01*
X2445167Y1480094D01*
X2444547Y1481344D01*
X2443617Y1482385D01*
X2442377Y1482802D01*
G01X2454777Y1469885D02*
X2454467Y1470094D01*
Y1470510D01*
X2454777Y1470719D01*
X2455087Y1470510D01*
Y1470094D01*
X2454777Y1469885D01*
G01X2467177Y1482802D02*
X2465937Y1482385D01*
X2465007Y1481344D01*
X2464387Y1480094D01*
X2463922Y1478427D01*
X2463767Y1476552D01*
X2463922Y1474677D01*
X2464387Y1473010D01*
X2465007Y1471760D01*
X2465937Y1470719D01*
X2467177Y1470302D01*
X2468417Y1470719D01*
X2469347Y1471760D01*
X2469967Y1473010D01*
X2470432Y1474677D01*
X2470587Y1476552D01*
X2470432Y1478427D01*
X2469967Y1480094D01*
X2469347Y1481344D01*
X2468417Y1482385D01*
X2467177Y1482802D01*
G01X2366272Y1508069D02*
X2369992D01*
G01X2367977Y1510777D02*
Y1505360D01*
G01X2380377Y1516402D02*
X2379137Y1515985D01*
X2378207Y1514944D01*
X2377587Y1513694D01*
X2377122Y1512027D01*
X2376967Y1510152D01*
X2377122Y1508277D01*
X2377587Y1506610D01*
X2378207Y1505360D01*
X2379137Y1504319D01*
X2380377Y1503902D01*
X2381617Y1504319D01*
X2382547Y1505360D01*
X2383167Y1506610D01*
X2383632Y1508277D01*
X2383787Y1510152D01*
X2383632Y1512027D01*
X2383167Y1513694D01*
X2382547Y1514944D01*
X2381617Y1515985D01*
X2380377Y1516402D01*
G01X2392777Y1503485D02*
X2392467Y1503694D01*
Y1504110D01*
X2392777Y1504319D01*
X2393087Y1504110D01*
Y1503694D01*
X2392777Y1503485D01*
G01X2405177Y1516402D02*
X2403937Y1515985D01*
X2403007Y1514944D01*
X2402387Y1513694D01*
X2401922Y1512027D01*
X2401767Y1510152D01*
X2401922Y1508277D01*
X2402387Y1506610D01*
X2403007Y1505360D01*
X2403937Y1504319D01*
X2405177Y1503902D01*
X2406417Y1504319D01*
X2407347Y1505360D01*
X2407967Y1506610D01*
X2408432Y1508277D01*
X2408587Y1510152D01*
X2408432Y1512027D01*
X2407967Y1513694D01*
X2407347Y1514944D01*
X2406417Y1515985D01*
X2405177Y1516402D01*
G01X2414787Y1503485D02*
X2420367Y1516402D01*
G01X2427962Y1508069D02*
X2431992D01*
G01X2442377Y1516402D02*
X2441137Y1515985D01*
X2440207Y1514944D01*
X2439587Y1513694D01*
X2439122Y1512027D01*
X2438967Y1510152D01*
X2439122Y1508277D01*
X2439587Y1506610D01*
X2440207Y1505360D01*
X2441137Y1504319D01*
X2442377Y1503902D01*
X2443617Y1504319D01*
X2444547Y1505360D01*
X2445167Y1506610D01*
X2445632Y1508277D01*
X2445787Y1510152D01*
X2445632Y1512027D01*
X2445167Y1513694D01*
X2444547Y1514944D01*
X2443617Y1515985D01*
X2442377Y1516402D01*
G01X2454777Y1503485D02*
X2454467Y1503694D01*
Y1504110D01*
X2454777Y1504319D01*
X2455087Y1504110D01*
Y1503694D01*
X2454777Y1503485D01*
G01X2467177Y1516402D02*
X2465937Y1515985D01*
X2465007Y1514944D01*
X2464387Y1513694D01*
X2463922Y1512027D01*
X2463767Y1510152D01*
X2463922Y1508277D01*
X2464387Y1506610D01*
X2465007Y1505360D01*
X2465937Y1504319D01*
X2467177Y1503902D01*
X2468417Y1504319D01*
X2469347Y1505360D01*
X2469967Y1506610D01*
X2470432Y1508277D01*
X2470587Y1510152D01*
X2470432Y1512027D01*
X2469967Y1513694D01*
X2469347Y1514944D01*
X2468417Y1515985D01*
X2467177Y1516402D01*
G01X2366272Y1541669D02*
X2369992D01*
G01X2367977Y1544377D02*
Y1538960D01*
G01X2380377Y1550002D02*
X2379137Y1549585D01*
X2378207Y1548544D01*
X2377587Y1547294D01*
X2377122Y1545627D01*
X2376967Y1543752D01*
X2377122Y1541877D01*
X2377587Y1540210D01*
X2378207Y1538960D01*
X2379137Y1537919D01*
X2380377Y1537502D01*
X2381617Y1537919D01*
X2382547Y1538960D01*
X2383167Y1540210D01*
X2383632Y1541877D01*
X2383787Y1543752D01*
X2383632Y1545627D01*
X2383167Y1547294D01*
X2382547Y1548544D01*
X2381617Y1549585D01*
X2380377Y1550002D01*
G01X2392777Y1537085D02*
X2392467Y1537294D01*
Y1537710D01*
X2392777Y1537919D01*
X2393087Y1537710D01*
Y1537294D01*
X2392777Y1537085D01*
G01X2405177Y1550002D02*
X2403937Y1549585D01*
X2403007Y1548544D01*
X2402387Y1547294D01*
X2401922Y1545627D01*
X2401767Y1543752D01*
X2401922Y1541877D01*
X2402387Y1540210D01*
X2403007Y1538960D01*
X2403937Y1537919D01*
X2405177Y1537502D01*
X2406417Y1537919D01*
X2407347Y1538960D01*
X2407967Y1540210D01*
X2408432Y1541877D01*
X2408587Y1543752D01*
X2408432Y1545627D01*
X2407967Y1547294D01*
X2407347Y1548544D01*
X2406417Y1549585D01*
X2405177Y1550002D01*
G01X2414787Y1537085D02*
X2420367Y1550002D01*
G01X2427962Y1541669D02*
X2431992D01*
G01X2442377Y1550002D02*
X2441137Y1549585D01*
X2440207Y1548544D01*
X2439587Y1547294D01*
X2439122Y1545627D01*
X2438967Y1543752D01*
X2439122Y1541877D01*
X2439587Y1540210D01*
X2440207Y1538960D01*
X2441137Y1537919D01*
X2442377Y1537502D01*
X2443617Y1537919D01*
X2444547Y1538960D01*
X2445167Y1540210D01*
X2445632Y1541877D01*
X2445787Y1543752D01*
X2445632Y1545627D01*
X2445167Y1547294D01*
X2444547Y1548544D01*
X2443617Y1549585D01*
X2442377Y1550002D01*
G01X2454777Y1537085D02*
X2454467Y1537294D01*
Y1537710D01*
X2454777Y1537919D01*
X2455087Y1537710D01*
Y1537294D01*
X2454777Y1537085D01*
G01X2467177Y1550002D02*
X2465937Y1549585D01*
X2465007Y1548544D01*
X2464387Y1547294D01*
X2463922Y1545627D01*
X2463767Y1543752D01*
X2463922Y1541877D01*
X2464387Y1540210D01*
X2465007Y1538960D01*
X2465937Y1537919D01*
X2467177Y1537502D01*
X2468417Y1537919D01*
X2469347Y1538960D01*
X2469967Y1540210D01*
X2470432Y1541877D01*
X2470587Y1543752D01*
X2470432Y1545627D01*
X2469967Y1547294D01*
X2469347Y1548544D01*
X2468417Y1549585D01*
X2467177Y1550002D01*
G01X2366272Y1575269D02*
X2369992D01*
G01X2367977Y1577977D02*
Y1572560D01*
G01X2380377Y1583602D02*
X2379137Y1583185D01*
X2378207Y1582144D01*
X2377587Y1580894D01*
X2377122Y1579227D01*
X2376967Y1577352D01*
X2377122Y1575477D01*
X2377587Y1573810D01*
X2378207Y1572560D01*
X2379137Y1571519D01*
X2380377Y1571102D01*
X2381617Y1571519D01*
X2382547Y1572560D01*
X2383167Y1573810D01*
X2383632Y1575477D01*
X2383787Y1577352D01*
X2383632Y1579227D01*
X2383167Y1580894D01*
X2382547Y1582144D01*
X2381617Y1583185D01*
X2380377Y1583602D01*
G01X2392777Y1570685D02*
X2392467Y1570894D01*
Y1571310D01*
X2392777Y1571519D01*
X2393087Y1571310D01*
Y1570894D01*
X2392777Y1570685D01*
G01X2405177Y1583602D02*
X2403937Y1583185D01*
X2403007Y1582144D01*
X2402387Y1580894D01*
X2401922Y1579227D01*
X2401767Y1577352D01*
X2401922Y1575477D01*
X2402387Y1573810D01*
X2403007Y1572560D01*
X2403937Y1571519D01*
X2405177Y1571102D01*
X2406417Y1571519D01*
X2407347Y1572560D01*
X2407967Y1573810D01*
X2408432Y1575477D01*
X2408587Y1577352D01*
X2408432Y1579227D01*
X2407967Y1580894D01*
X2407347Y1582144D01*
X2406417Y1583185D01*
X2405177Y1583602D01*
G01X2414787Y1570685D02*
X2420367Y1583602D01*
G01X2427962Y1575269D02*
X2431992D01*
G01X2442377Y1583602D02*
X2441137Y1583185D01*
X2440207Y1582144D01*
X2439587Y1580894D01*
X2439122Y1579227D01*
X2438967Y1577352D01*
X2439122Y1575477D01*
X2439587Y1573810D01*
X2440207Y1572560D01*
X2441137Y1571519D01*
X2442377Y1571102D01*
X2443617Y1571519D01*
X2444547Y1572560D01*
X2445167Y1573810D01*
X2445632Y1575477D01*
X2445787Y1577352D01*
X2445632Y1579227D01*
X2445167Y1580894D01*
X2444547Y1582144D01*
X2443617Y1583185D01*
X2442377Y1583602D01*
G01X2454777Y1570685D02*
X2454467Y1570894D01*
Y1571310D01*
X2454777Y1571519D01*
X2455087Y1571310D01*
Y1570894D01*
X2454777Y1570685D01*
G01X2467177Y1583602D02*
X2465937Y1583185D01*
X2465007Y1582144D01*
X2464387Y1580894D01*
X2463922Y1579227D01*
X2463767Y1577352D01*
X2463922Y1575477D01*
X2464387Y1573810D01*
X2465007Y1572560D01*
X2465937Y1571519D01*
X2467177Y1571102D01*
X2468417Y1571519D01*
X2469347Y1572560D01*
X2469967Y1573810D01*
X2470432Y1575477D01*
X2470587Y1577352D01*
X2470432Y1579227D01*
X2469967Y1580894D01*
X2469347Y1582144D01*
X2468417Y1583185D01*
X2467177Y1583602D01*
G01X2366272Y1608869D02*
X2369992D01*
G01X2367977Y1611577D02*
Y1606160D01*
G01X2380377Y1617202D02*
X2379137Y1616785D01*
X2378207Y1615744D01*
X2377587Y1614494D01*
X2377122Y1612827D01*
X2376967Y1610952D01*
X2377122Y1609077D01*
X2377587Y1607410D01*
X2378207Y1606160D01*
X2379137Y1605119D01*
X2380377Y1604702D01*
X2381617Y1605119D01*
X2382547Y1606160D01*
X2383167Y1607410D01*
X2383632Y1609077D01*
X2383787Y1610952D01*
X2383632Y1612827D01*
X2383167Y1614494D01*
X2382547Y1615744D01*
X2381617Y1616785D01*
X2380377Y1617202D01*
G01X2392777Y1604285D02*
X2392467Y1604494D01*
Y1604910D01*
X2392777Y1605119D01*
X2393087Y1604910D01*
Y1604494D01*
X2392777Y1604285D01*
G01X2405177Y1617202D02*
X2403937Y1616785D01*
X2403007Y1615744D01*
X2402387Y1614494D01*
X2401922Y1612827D01*
X2401767Y1610952D01*
X2401922Y1609077D01*
X2402387Y1607410D01*
X2403007Y1606160D01*
X2403937Y1605119D01*
X2405177Y1604702D01*
X2406417Y1605119D01*
X2407347Y1606160D01*
X2407967Y1607410D01*
X2408432Y1609077D01*
X2408587Y1610952D01*
X2408432Y1612827D01*
X2407967Y1614494D01*
X2407347Y1615744D01*
X2406417Y1616785D01*
X2405177Y1617202D01*
G01X2414787Y1604285D02*
X2420367Y1617202D01*
G01X2427962Y1608869D02*
X2431992D01*
G01X2442377Y1617202D02*
X2441137Y1616785D01*
X2440207Y1615744D01*
X2439587Y1614494D01*
X2439122Y1612827D01*
X2438967Y1610952D01*
X2439122Y1609077D01*
X2439587Y1607410D01*
X2440207Y1606160D01*
X2441137Y1605119D01*
X2442377Y1604702D01*
X2443617Y1605119D01*
X2444547Y1606160D01*
X2445167Y1607410D01*
X2445632Y1609077D01*
X2445787Y1610952D01*
X2445632Y1612827D01*
X2445167Y1614494D01*
X2444547Y1615744D01*
X2443617Y1616785D01*
X2442377Y1617202D01*
G01X2454777Y1604285D02*
X2454467Y1604494D01*
Y1604910D01*
X2454777Y1605119D01*
X2455087Y1604910D01*
Y1604494D01*
X2454777Y1604285D01*
G01X2467177Y1617202D02*
X2465937Y1616785D01*
X2465007Y1615744D01*
X2464387Y1614494D01*
X2463922Y1612827D01*
X2463767Y1610952D01*
X2463922Y1609077D01*
X2464387Y1607410D01*
X2465007Y1606160D01*
X2465937Y1605119D01*
X2467177Y1604702D01*
X2468417Y1605119D01*
X2469347Y1606160D01*
X2469967Y1607410D01*
X2470432Y1609077D01*
X2470587Y1610952D01*
X2470432Y1612827D01*
X2469967Y1614494D01*
X2469347Y1615744D01*
X2468417Y1616785D01*
X2467177Y1617202D01*
G01X2366272Y1642469D02*
X2369992D01*
G01X2367977Y1645177D02*
Y1639760D01*
G01X2377432Y1648719D02*
X2378362Y1649968D01*
X2379447Y1650594D01*
X2380687Y1650802D01*
X2382237Y1650385D01*
X2383322Y1649344D01*
X2383632Y1648094D01*
X2383477Y1646843D01*
X2382857Y1645802D01*
X2379757Y1643719D01*
X2378362Y1642260D01*
X2377432Y1640177D01*
X2377122Y1638302D01*
X2383632D01*
G01X2392777Y1637885D02*
X2392467Y1638094D01*
Y1638510D01*
X2392777Y1638719D01*
X2393087Y1638510D01*
Y1638094D01*
X2392777Y1637885D01*
G01X2405177Y1650802D02*
X2403937Y1650385D01*
X2403007Y1649344D01*
X2402387Y1648094D01*
X2401922Y1646427D01*
X2401767Y1644552D01*
X2401922Y1642677D01*
X2402387Y1641010D01*
X2403007Y1639760D01*
X2403937Y1638719D01*
X2405177Y1638302D01*
X2406417Y1638719D01*
X2407347Y1639760D01*
X2407967Y1641010D01*
X2408432Y1642677D01*
X2408587Y1644552D01*
X2408432Y1646427D01*
X2407967Y1648094D01*
X2407347Y1649344D01*
X2406417Y1650385D01*
X2405177Y1650802D01*
G01X2414787Y1637885D02*
X2420367Y1650802D01*
G01X2427962Y1642469D02*
X2431992D01*
G01X2439432Y1648719D02*
X2440362Y1649968D01*
X2441447Y1650594D01*
X2442687Y1650802D01*
X2444237Y1650385D01*
X2445322Y1649344D01*
X2445632Y1648094D01*
X2445477Y1646843D01*
X2444857Y1645802D01*
X2441757Y1643719D01*
X2440362Y1642260D01*
X2439432Y1640177D01*
X2439122Y1638302D01*
X2445632D01*
G01X2454777Y1637885D02*
X2454467Y1638094D01*
Y1638510D01*
X2454777Y1638719D01*
X2455087Y1638510D01*
Y1638094D01*
X2454777Y1637885D01*
G01X2467177Y1650802D02*
X2465937Y1650385D01*
X2465007Y1649344D01*
X2464387Y1648094D01*
X2463922Y1646427D01*
X2463767Y1644552D01*
X2463922Y1642677D01*
X2464387Y1641010D01*
X2465007Y1639760D01*
X2465937Y1638719D01*
X2467177Y1638302D01*
X2468417Y1638719D01*
X2469347Y1639760D01*
X2469967Y1641010D01*
X2470432Y1642677D01*
X2470587Y1644552D01*
X2470432Y1646427D01*
X2469967Y1648094D01*
X2469347Y1649344D01*
X2468417Y1650385D01*
X2467177Y1650802D01*
G01X2366272Y1676069D02*
X2369992D01*
G01X2367977Y1678777D02*
Y1673360D01*
G01X2376967Y1674402D02*
X2377897Y1672943D01*
X2379137Y1672110D01*
X2380532Y1671902D01*
X2381772Y1672110D01*
X2383012Y1673152D01*
X2383787Y1674402D01*
X2383942Y1675652D01*
X2383632Y1677110D01*
X2382547Y1678152D01*
X2381462Y1678569D01*
X2380067D01*
G01X2381462D02*
X2382392Y1679194D01*
X2383167Y1680235D01*
X2383477Y1681485D01*
X2383167Y1682735D01*
X2382392Y1683777D01*
X2380997Y1684402D01*
X2379602Y1684194D01*
X2378207Y1683360D01*
G01X2392777Y1671485D02*
X2392467Y1671694D01*
Y1672110D01*
X2392777Y1672319D01*
X2393087Y1672110D01*
Y1671694D01*
X2392777Y1671485D01*
G01X2405177Y1684402D02*
X2403937Y1683985D01*
X2403007Y1682944D01*
X2402387Y1681694D01*
X2401922Y1680027D01*
X2401767Y1678152D01*
X2401922Y1676277D01*
X2402387Y1674610D01*
X2403007Y1673360D01*
X2403937Y1672319D01*
X2405177Y1671902D01*
X2406417Y1672319D01*
X2407347Y1673360D01*
X2407967Y1674610D01*
X2408432Y1676277D01*
X2408587Y1678152D01*
X2408432Y1680027D01*
X2407967Y1681694D01*
X2407347Y1682944D01*
X2406417Y1683985D01*
X2405177Y1684402D01*
G01X2414787Y1671485D02*
X2420367Y1684402D01*
G01X2427962Y1676069D02*
X2431992D01*
G01X2438967Y1674402D02*
X2439897Y1672943D01*
X2441137Y1672110D01*
X2442532Y1671902D01*
X2443772Y1672110D01*
X2445012Y1673152D01*
X2445787Y1674402D01*
X2445942Y1675652D01*
X2445632Y1677110D01*
X2444547Y1678152D01*
X2443462Y1678569D01*
X2442067D01*
G01X2443462D02*
X2444392Y1679194D01*
X2445167Y1680235D01*
X2445477Y1681485D01*
X2445167Y1682735D01*
X2444392Y1683777D01*
X2442997Y1684402D01*
X2441602Y1684194D01*
X2440207Y1683360D01*
G01X2454777Y1671485D02*
X2454467Y1671694D01*
Y1672110D01*
X2454777Y1672319D01*
X2455087Y1672110D01*
Y1671694D01*
X2454777Y1671485D01*
G01X2467177Y1684402D02*
X2465937Y1683985D01*
X2465007Y1682944D01*
X2464387Y1681694D01*
X2463922Y1680027D01*
X2463767Y1678152D01*
X2463922Y1676277D01*
X2464387Y1674610D01*
X2465007Y1673360D01*
X2465937Y1672319D01*
X2467177Y1671902D01*
X2468417Y1672319D01*
X2469347Y1673360D01*
X2469967Y1674610D01*
X2470432Y1676277D01*
X2470587Y1678152D01*
X2470432Y1680027D01*
X2469967Y1681694D01*
X2469347Y1682944D01*
X2468417Y1683985D01*
X2467177Y1684402D01*
G01X2366272Y1709669D02*
X2369992D01*
G01X2367977Y1712377D02*
Y1706960D01*
G01X2380377Y1718002D02*
X2379137Y1717585D01*
X2378207Y1716544D01*
X2377587Y1715294D01*
X2377122Y1713627D01*
X2376967Y1711752D01*
X2377122Y1709877D01*
X2377587Y1708210D01*
X2378207Y1706960D01*
X2379137Y1705919D01*
X2380377Y1705502D01*
X2381617Y1705919D01*
X2382547Y1706960D01*
X2383167Y1708210D01*
X2383632Y1709877D01*
X2383787Y1711752D01*
X2383632Y1713627D01*
X2383167Y1715294D01*
X2382547Y1716544D01*
X2381617Y1717585D01*
X2380377Y1718002D01*
G01X2392777Y1705085D02*
X2392467Y1705294D01*
Y1705710D01*
X2392777Y1705919D01*
X2393087Y1705710D01*
Y1705294D01*
X2392777Y1705085D01*
G01X2405177Y1718002D02*
X2403937Y1717585D01*
X2403007Y1716544D01*
X2402387Y1715294D01*
X2401922Y1713627D01*
X2401767Y1711752D01*
X2401922Y1709877D01*
X2402387Y1708210D01*
X2403007Y1706960D01*
X2403937Y1705919D01*
X2405177Y1705502D01*
X2406417Y1705919D01*
X2407347Y1706960D01*
X2407967Y1708210D01*
X2408432Y1709877D01*
X2408587Y1711752D01*
X2408432Y1713627D01*
X2407967Y1715294D01*
X2407347Y1716544D01*
X2406417Y1717585D01*
X2405177Y1718002D01*
G01X2414787Y1705085D02*
X2420367Y1718002D01*
G01X2427962Y1709669D02*
X2431992D01*
G01X2442377Y1718002D02*
X2441137Y1717585D01*
X2440207Y1716544D01*
X2439587Y1715294D01*
X2439122Y1713627D01*
X2438967Y1711752D01*
X2439122Y1709877D01*
X2439587Y1708210D01*
X2440207Y1706960D01*
X2441137Y1705919D01*
X2442377Y1705502D01*
X2443617Y1705919D01*
X2444547Y1706960D01*
X2445167Y1708210D01*
X2445632Y1709877D01*
X2445787Y1711752D01*
X2445632Y1713627D01*
X2445167Y1715294D01*
X2444547Y1716544D01*
X2443617Y1717585D01*
X2442377Y1718002D01*
G01X2454777Y1705085D02*
X2454467Y1705294D01*
Y1705710D01*
X2454777Y1705919D01*
X2455087Y1705710D01*
Y1705294D01*
X2454777Y1705085D01*
G01X2467177Y1718002D02*
X2465937Y1717585D01*
X2465007Y1716544D01*
X2464387Y1715294D01*
X2463922Y1713627D01*
X2463767Y1711752D01*
X2463922Y1709877D01*
X2464387Y1708210D01*
X2465007Y1706960D01*
X2465937Y1705919D01*
X2467177Y1705502D01*
X2468417Y1705919D01*
X2469347Y1706960D01*
X2469967Y1708210D01*
X2470432Y1709877D01*
X2470587Y1711752D01*
X2470432Y1713627D01*
X2469967Y1715294D01*
X2469347Y1716544D01*
X2468417Y1717585D01*
X2467177Y1718002D01*
G01X2360072Y1743269D02*
X2363792D01*
G01X2361777Y1745977D02*
Y1740560D01*
G01X2376037Y1739102D02*
Y1751602D01*
X2370302Y1742644D01*
X2378052D01*
G01X2386577Y1738685D02*
X2386267Y1738894D01*
Y1739310D01*
X2386577Y1739519D01*
X2386887Y1739310D01*
Y1738894D01*
X2386577Y1738685D01*
G01X2398977Y1751602D02*
X2397737Y1751185D01*
X2396807Y1750144D01*
X2396187Y1748894D01*
X2395722Y1747227D01*
X2395567Y1745352D01*
X2395722Y1743477D01*
X2396187Y1741810D01*
X2396807Y1740560D01*
X2397737Y1739519D01*
X2398977Y1739102D01*
X2400217Y1739519D01*
X2401147Y1740560D01*
X2401767Y1741810D01*
X2402232Y1743477D01*
X2402387Y1745352D01*
X2402232Y1747227D01*
X2401767Y1748894D01*
X2401147Y1750144D01*
X2400217Y1751185D01*
X2398977Y1751602D01*
G01X2408587Y1738685D02*
X2414167Y1751602D01*
G01X2421762Y1743269D02*
X2425792D01*
G01X2436177Y1739102D02*
Y1751602D01*
X2434317Y1749102D01*
G01Y1739102D02*
X2438037D01*
G01X2448577Y1751602D02*
X2447337Y1751185D01*
X2446407Y1750144D01*
X2445787Y1748894D01*
X2445322Y1747227D01*
X2445167Y1745352D01*
X2445322Y1743477D01*
X2445787Y1741810D01*
X2446407Y1740560D01*
X2447337Y1739519D01*
X2448577Y1739102D01*
X2449817Y1739519D01*
X2450747Y1740560D01*
X2451367Y1741810D01*
X2451832Y1743477D01*
X2451987Y1745352D01*
X2451832Y1747227D01*
X2451367Y1748894D01*
X2450747Y1750144D01*
X2449817Y1751185D01*
X2448577Y1751602D01*
G01X2460977Y1738685D02*
X2460667Y1738894D01*
Y1739310D01*
X2460977Y1739519D01*
X2461287Y1739310D01*
Y1738894D01*
X2460977Y1738685D01*
G01X2473377Y1751602D02*
X2472137Y1751185D01*
X2471207Y1750144D01*
X2470587Y1748894D01*
X2470122Y1747227D01*
X2469967Y1745352D01*
X2470122Y1743477D01*
X2470587Y1741810D01*
X2471207Y1740560D01*
X2472137Y1739519D01*
X2473377Y1739102D01*
X2474617Y1739519D01*
X2475547Y1740560D01*
X2476167Y1741810D01*
X2476632Y1743477D01*
X2476787Y1745352D01*
X2476632Y1747227D01*
X2476167Y1748894D01*
X2475547Y1750144D01*
X2474617Y1751185D01*
X2473377Y1751602D01*
G01X2366272Y1776869D02*
X2369992D01*
G01X2367977Y1779577D02*
Y1774160D01*
G01X2380377Y1785202D02*
X2379137Y1784785D01*
X2378207Y1783744D01*
X2377587Y1782494D01*
X2377122Y1780827D01*
X2376967Y1778952D01*
X2377122Y1777077D01*
X2377587Y1775410D01*
X2378207Y1774160D01*
X2379137Y1773119D01*
X2380377Y1772702D01*
X2381617Y1773119D01*
X2382547Y1774160D01*
X2383167Y1775410D01*
X2383632Y1777077D01*
X2383787Y1778952D01*
X2383632Y1780827D01*
X2383167Y1782494D01*
X2382547Y1783744D01*
X2381617Y1784785D01*
X2380377Y1785202D01*
G01X2392777Y1772285D02*
X2392467Y1772494D01*
Y1772910D01*
X2392777Y1773119D01*
X2393087Y1772910D01*
Y1772494D01*
X2392777Y1772285D01*
G01X2405177Y1785202D02*
X2403937Y1784785D01*
X2403007Y1783744D01*
X2402387Y1782494D01*
X2401922Y1780827D01*
X2401767Y1778952D01*
X2401922Y1777077D01*
X2402387Y1775410D01*
X2403007Y1774160D01*
X2403937Y1773119D01*
X2405177Y1772702D01*
X2406417Y1773119D01*
X2407347Y1774160D01*
X2407967Y1775410D01*
X2408432Y1777077D01*
X2408587Y1778952D01*
X2408432Y1780827D01*
X2407967Y1782494D01*
X2407347Y1783744D01*
X2406417Y1784785D01*
X2405177Y1785202D01*
G01X2414787Y1772285D02*
X2420367Y1785202D01*
G01X2427962Y1776869D02*
X2431992D01*
G01X2442377Y1785202D02*
X2441137Y1784785D01*
X2440207Y1783744D01*
X2439587Y1782494D01*
X2439122Y1780827D01*
X2438967Y1778952D01*
X2439122Y1777077D01*
X2439587Y1775410D01*
X2440207Y1774160D01*
X2441137Y1773119D01*
X2442377Y1772702D01*
X2443617Y1773119D01*
X2444547Y1774160D01*
X2445167Y1775410D01*
X2445632Y1777077D01*
X2445787Y1778952D01*
X2445632Y1780827D01*
X2445167Y1782494D01*
X2444547Y1783744D01*
X2443617Y1784785D01*
X2442377Y1785202D01*
G01X2454777Y1772285D02*
X2454467Y1772494D01*
Y1772910D01*
X2454777Y1773119D01*
X2455087Y1772910D01*
Y1772494D01*
X2454777Y1772285D01*
G01X2467177Y1785202D02*
X2465937Y1784785D01*
X2465007Y1783744D01*
X2464387Y1782494D01*
X2463922Y1780827D01*
X2463767Y1778952D01*
X2463922Y1777077D01*
X2464387Y1775410D01*
X2465007Y1774160D01*
X2465937Y1773119D01*
X2467177Y1772702D01*
X2468417Y1773119D01*
X2469347Y1774160D01*
X2469967Y1775410D01*
X2470432Y1777077D01*
X2470587Y1778952D01*
X2470432Y1780827D01*
X2469967Y1782494D01*
X2469347Y1783744D01*
X2468417Y1784785D01*
X2467177Y1785202D01*
G01X2366272Y1810469D02*
X2369992D01*
G01X2367977Y1813177D02*
Y1807760D01*
G01X2380377Y1818802D02*
X2379137Y1818385D01*
X2378207Y1817344D01*
X2377587Y1816094D01*
X2377122Y1814427D01*
X2376967Y1812552D01*
X2377122Y1810677D01*
X2377587Y1809010D01*
X2378207Y1807760D01*
X2379137Y1806719D01*
X2380377Y1806302D01*
X2381617Y1806719D01*
X2382547Y1807760D01*
X2383167Y1809010D01*
X2383632Y1810677D01*
X2383787Y1812552D01*
X2383632Y1814427D01*
X2383167Y1816094D01*
X2382547Y1817344D01*
X2381617Y1818385D01*
X2380377Y1818802D01*
G01X2392777Y1805885D02*
X2392467Y1806094D01*
Y1806510D01*
X2392777Y1806719D01*
X2393087Y1806510D01*
Y1806094D01*
X2392777Y1805885D01*
G01X2405177Y1818802D02*
X2403937Y1818385D01*
X2403007Y1817344D01*
X2402387Y1816094D01*
X2401922Y1814427D01*
X2401767Y1812552D01*
X2401922Y1810677D01*
X2402387Y1809010D01*
X2403007Y1807760D01*
X2403937Y1806719D01*
X2405177Y1806302D01*
X2406417Y1806719D01*
X2407347Y1807760D01*
X2407967Y1809010D01*
X2408432Y1810677D01*
X2408587Y1812552D01*
X2408432Y1814427D01*
X2407967Y1816094D01*
X2407347Y1817344D01*
X2406417Y1818385D01*
X2405177Y1818802D01*
G01X2414787Y1805885D02*
X2420367Y1818802D01*
G01X2427962Y1810469D02*
X2431992D01*
G01X2442377Y1818802D02*
X2441137Y1818385D01*
X2440207Y1817344D01*
X2439587Y1816094D01*
X2439122Y1814427D01*
X2438967Y1812552D01*
X2439122Y1810677D01*
X2439587Y1809010D01*
X2440207Y1807760D01*
X2441137Y1806719D01*
X2442377Y1806302D01*
X2443617Y1806719D01*
X2444547Y1807760D01*
X2445167Y1809010D01*
X2445632Y1810677D01*
X2445787Y1812552D01*
X2445632Y1814427D01*
X2445167Y1816094D01*
X2444547Y1817344D01*
X2443617Y1818385D01*
X2442377Y1818802D01*
G01X2454777Y1805885D02*
X2454467Y1806094D01*
Y1806510D01*
X2454777Y1806719D01*
X2455087Y1806510D01*
Y1806094D01*
X2454777Y1805885D01*
G01X2467177Y1818802D02*
X2465937Y1818385D01*
X2465007Y1817344D01*
X2464387Y1816094D01*
X2463922Y1814427D01*
X2463767Y1812552D01*
X2463922Y1810677D01*
X2464387Y1809010D01*
X2465007Y1807760D01*
X2465937Y1806719D01*
X2467177Y1806302D01*
X2468417Y1806719D01*
X2469347Y1807760D01*
X2469967Y1809010D01*
X2470432Y1810677D01*
X2470587Y1812552D01*
X2470432Y1814427D01*
X2469967Y1816094D01*
X2469347Y1817344D01*
X2468417Y1818385D01*
X2467177Y1818802D01*
G01X2366272Y1844069D02*
X2369992D01*
G01X2367977Y1846777D02*
Y1841360D01*
G01X2380377Y1852402D02*
X2379137Y1851985D01*
X2378207Y1850944D01*
X2377587Y1849694D01*
X2377122Y1848027D01*
X2376967Y1846152D01*
X2377122Y1844277D01*
X2377587Y1842610D01*
X2378207Y1841360D01*
X2379137Y1840319D01*
X2380377Y1839902D01*
X2381617Y1840319D01*
X2382547Y1841360D01*
X2383167Y1842610D01*
X2383632Y1844277D01*
X2383787Y1846152D01*
X2383632Y1848027D01*
X2383167Y1849694D01*
X2382547Y1850944D01*
X2381617Y1851985D01*
X2380377Y1852402D01*
G01X2392777Y1839485D02*
X2392467Y1839694D01*
Y1840110D01*
X2392777Y1840319D01*
X2393087Y1840110D01*
Y1839694D01*
X2392777Y1839485D01*
G01X2405177Y1852402D02*
X2403937Y1851985D01*
X2403007Y1850944D01*
X2402387Y1849694D01*
X2401922Y1848027D01*
X2401767Y1846152D01*
X2401922Y1844277D01*
X2402387Y1842610D01*
X2403007Y1841360D01*
X2403937Y1840319D01*
X2405177Y1839902D01*
X2406417Y1840319D01*
X2407347Y1841360D01*
X2407967Y1842610D01*
X2408432Y1844277D01*
X2408587Y1846152D01*
X2408432Y1848027D01*
X2407967Y1849694D01*
X2407347Y1850944D01*
X2406417Y1851985D01*
X2405177Y1852402D01*
G01X2414787Y1839485D02*
X2420367Y1852402D01*
G01X2427962Y1844069D02*
X2431992D01*
G01X2442377Y1852402D02*
X2441137Y1851985D01*
X2440207Y1850944D01*
X2439587Y1849694D01*
X2439122Y1848027D01*
X2438967Y1846152D01*
X2439122Y1844277D01*
X2439587Y1842610D01*
X2440207Y1841360D01*
X2441137Y1840319D01*
X2442377Y1839902D01*
X2443617Y1840319D01*
X2444547Y1841360D01*
X2445167Y1842610D01*
X2445632Y1844277D01*
X2445787Y1846152D01*
X2445632Y1848027D01*
X2445167Y1849694D01*
X2444547Y1850944D01*
X2443617Y1851985D01*
X2442377Y1852402D01*
G01X2454777Y1839485D02*
X2454467Y1839694D01*
Y1840110D01*
X2454777Y1840319D01*
X2455087Y1840110D01*
Y1839694D01*
X2454777Y1839485D01*
G01X2467177Y1852402D02*
X2465937Y1851985D01*
X2465007Y1850944D01*
X2464387Y1849694D01*
X2463922Y1848027D01*
X2463767Y1846152D01*
X2463922Y1844277D01*
X2464387Y1842610D01*
X2465007Y1841360D01*
X2465937Y1840319D01*
X2467177Y1839902D01*
X2468417Y1840319D01*
X2469347Y1841360D01*
X2469967Y1842610D01*
X2470432Y1844277D01*
X2470587Y1846152D01*
X2470432Y1848027D01*
X2469967Y1849694D01*
X2469347Y1850944D01*
X2468417Y1851985D01*
X2467177Y1852402D01*
G01X2367977Y1881702D02*
Y1869202D01*
G01X2364412Y1881702D02*
X2371542D01*
G01X2380377Y1869202D02*
X2379137Y1869410D01*
X2378052Y1870243D01*
X2377122Y1871494D01*
X2376502Y1872952D01*
X2376192Y1874619D01*
Y1876285D01*
X2376502Y1877952D01*
X2377122Y1879410D01*
X2378052Y1880660D01*
X2379137Y1881494D01*
X2380377Y1881702D01*
X2381617Y1881494D01*
X2382702Y1880660D01*
X2383632Y1879410D01*
X2384252Y1877952D01*
X2384562Y1876285D01*
Y1874619D01*
X2384252Y1872952D01*
X2383632Y1871494D01*
X2382702Y1870243D01*
X2381617Y1869410D01*
X2380377Y1869202D01*
G01X2389677Y1881702D02*
Y1869202D01*
X2395877D01*
G01X2408277D02*
X2402077D01*
Y1881702D01*
X2408277D01*
G01X2405797Y1875660D02*
X2402077D01*
G01X2414477Y1869202D02*
Y1881702D01*
X2418352D01*
X2419592Y1881077D01*
X2420367Y1880244D01*
X2420677Y1878577D01*
X2420367Y1876910D01*
X2419437Y1875869D01*
X2418352Y1875244D01*
X2414477D01*
G01X2418352D02*
X2420677Y1869202D01*
G01X2426102D02*
X2429977Y1881702D01*
X2433852Y1869202D01*
G01X2432457Y1873577D02*
X2427497D01*
G01X2438812Y1869202D02*
Y1881702D01*
X2445942Y1869202D01*
Y1881702D01*
G01X2458187Y1880660D02*
X2457257Y1881285D01*
X2456172Y1881702D01*
X2454932D01*
X2453537Y1881077D01*
X2452452Y1880035D01*
X2451677Y1878785D01*
X2451057Y1876702D01*
X2450902Y1874827D01*
X2451212Y1872952D01*
X2451677Y1871702D01*
X2452607Y1870452D01*
X2453692Y1869619D01*
X2454777Y1869202D01*
X2455862D01*
X2456947Y1869619D01*
X2457877Y1870243D01*
X2458652Y1871077D01*
G01X2470277Y1869202D02*
X2464077D01*
Y1881702D01*
X2470277D01*
G01X2467797Y1875660D02*
X2464077D01*
G01X2512127Y1887952D02*
Y-287448D01*
G01X2516312Y-276898D02*
Y-264398D01*
X2523442Y-276898D01*
Y-264398D01*
G01X2532277Y-276898D02*
X2531037Y-276690D01*
X2529952Y-275857D01*
X2529022Y-274606D01*
X2528402Y-273148D01*
X2528092Y-271481D01*
Y-269815D01*
X2528402Y-268148D01*
X2529022Y-266690D01*
X2529952Y-265440D01*
X2531037Y-264606D01*
X2532277Y-264398D01*
X2533517Y-264606D01*
X2534602Y-265440D01*
X2535532Y-266690D01*
X2536152Y-268148D01*
X2536462Y-269815D01*
Y-271481D01*
X2536152Y-273148D01*
X2535532Y-274606D01*
X2534602Y-275857D01*
X2533517Y-276690D01*
X2532277Y-276898D01*
G01X2541112D02*
Y-264398D01*
X2548242Y-276898D01*
Y-264398D01*
G01X2555062Y-272731D02*
X2559092D01*
G01X2566377Y-276898D02*
Y-264398D01*
X2570097D01*
X2571337Y-265023D01*
X2572267Y-266481D01*
X2572577Y-268148D01*
X2572267Y-269815D01*
X2571492Y-271065D01*
X2570097Y-271690D01*
X2566377D01*
G01X2578777Y-264398D02*
Y-276898D01*
X2584977D01*
G01X2590402D02*
X2594277Y-264398D01*
X2598152Y-276898D01*
G01X2596757Y-272523D02*
X2591797D01*
G01X2606677Y-264398D02*
Y-276898D01*
G01X2603112Y-264398D02*
X2610242D01*
G01X2622177Y-276898D02*
X2615977D01*
Y-264398D01*
X2622177D01*
G01X2619697Y-270440D02*
X2615977D01*
G01X2628067Y-276898D02*
Y-264398D01*
X2631167D01*
X2632407Y-265023D01*
X2633337Y-265856D01*
X2634112Y-267106D01*
X2634732Y-268565D01*
X2634887Y-270648D01*
X2634732Y-272731D01*
X2634112Y-274190D01*
X2633337Y-275440D01*
X2632407Y-276273D01*
X2631167Y-276898D01*
X2628067D01*
G01X2516312Y-243298D02*
Y-230798D01*
X2523442Y-243298D01*
Y-230798D01*
G01X2532277Y-243298D02*
X2531037Y-243090D01*
X2529952Y-242257D01*
X2529022Y-241006D01*
X2528402Y-239548D01*
X2528092Y-237881D01*
Y-236215D01*
X2528402Y-234548D01*
X2529022Y-233090D01*
X2529952Y-231840D01*
X2531037Y-231006D01*
X2532277Y-230798D01*
X2533517Y-231006D01*
X2534602Y-231840D01*
X2535532Y-233090D01*
X2536152Y-234548D01*
X2536462Y-236215D01*
Y-237881D01*
X2536152Y-239548D01*
X2535532Y-241006D01*
X2534602Y-242257D01*
X2533517Y-243090D01*
X2532277Y-243298D01*
G01X2541112D02*
Y-230798D01*
X2548242Y-243298D01*
Y-230798D01*
G01X2555062Y-239131D02*
X2559092D01*
G01X2566377Y-243298D02*
Y-230798D01*
X2570097D01*
X2571337Y-231423D01*
X2572267Y-232881D01*
X2572577Y-234548D01*
X2572267Y-236215D01*
X2571492Y-237465D01*
X2570097Y-238090D01*
X2566377D01*
G01X2578777Y-230798D02*
Y-243298D01*
X2584977D01*
G01X2590402D02*
X2594277Y-230798D01*
X2598152Y-243298D01*
G01X2596757Y-238923D02*
X2591797D01*
G01X2606677Y-230798D02*
Y-243298D01*
G01X2603112Y-230798D02*
X2610242D01*
G01X2622177Y-243298D02*
X2615977D01*
Y-230798D01*
X2622177D01*
G01X2619697Y-236840D02*
X2615977D01*
G01X2628067Y-243298D02*
Y-230798D01*
X2631167D01*
X2632407Y-231423D01*
X2633337Y-232256D01*
X2634112Y-233506D01*
X2634732Y-234965D01*
X2634887Y-237048D01*
X2634732Y-239131D01*
X2634112Y-240590D01*
X2633337Y-241840D01*
X2632407Y-242673D01*
X2631167Y-243298D01*
X2628067D01*
G01X2541577Y-209698D02*
Y-197198D01*
X2545297D01*
X2546537Y-197823D01*
X2547467Y-199281D01*
X2547777Y-200948D01*
X2547467Y-202615D01*
X2546692Y-203865D01*
X2545297Y-204490D01*
X2541577D01*
G01X2553977Y-197198D02*
Y-209698D01*
X2560177D01*
G01X2565602D02*
X2569477Y-197198D01*
X2573352Y-209698D01*
G01X2571957Y-205323D02*
X2566997D01*
G01X2581877Y-197198D02*
Y-209698D01*
G01X2578312Y-197198D02*
X2585442D01*
G01X2597377Y-209698D02*
X2591177D01*
Y-197198D01*
X2597377D01*
G01X2594897Y-203240D02*
X2591177D01*
G01X2603267Y-209698D02*
Y-197198D01*
X2606367D01*
X2607607Y-197823D01*
X2608537Y-198656D01*
X2609312Y-199906D01*
X2609932Y-201365D01*
X2610087Y-203448D01*
X2609932Y-205531D01*
X2609312Y-206990D01*
X2608537Y-208240D01*
X2607607Y-209073D01*
X2606367Y-209698D01*
X2603267D01*
G01X2541577Y-176098D02*
Y-163598D01*
X2545297D01*
X2546537Y-164223D01*
X2547467Y-165681D01*
X2547777Y-167348D01*
X2547467Y-169015D01*
X2546692Y-170265D01*
X2545297Y-170890D01*
X2541577D01*
G01X2553977Y-163598D02*
Y-176098D01*
X2560177D01*
G01X2565602D02*
X2569477Y-163598D01*
X2573352Y-176098D01*
G01X2571957Y-171723D02*
X2566997D01*
G01X2581877Y-163598D02*
Y-176098D01*
G01X2578312Y-163598D02*
X2585442D01*
G01X2597377Y-176098D02*
X2591177D01*
Y-163598D01*
X2597377D01*
G01X2594897Y-169640D02*
X2591177D01*
G01X2603267Y-176098D02*
Y-163598D01*
X2606367D01*
X2607607Y-164223D01*
X2608537Y-165056D01*
X2609312Y-166306D01*
X2609932Y-167765D01*
X2610087Y-169848D01*
X2609932Y-171931D01*
X2609312Y-173390D01*
X2608537Y-174640D01*
X2607607Y-175473D01*
X2606367Y-176098D01*
X2603267D01*
G01X2541577Y-142498D02*
Y-129998D01*
X2545297D01*
X2546537Y-130623D01*
X2547467Y-132081D01*
X2547777Y-133748D01*
X2547467Y-135415D01*
X2546692Y-136665D01*
X2545297Y-137290D01*
X2541577D01*
G01X2553977Y-129998D02*
Y-142498D01*
X2560177D01*
G01X2565602D02*
X2569477Y-129998D01*
X2573352Y-142498D01*
G01X2571957Y-138123D02*
X2566997D01*
G01X2581877Y-129998D02*
Y-142498D01*
G01X2578312Y-129998D02*
X2585442D01*
G01X2597377Y-142498D02*
X2591177D01*
Y-129998D01*
X2597377D01*
G01X2594897Y-136040D02*
X2591177D01*
G01X2603267Y-142498D02*
Y-129998D01*
X2606367D01*
X2607607Y-130623D01*
X2608537Y-131456D01*
X2609312Y-132706D01*
X2609932Y-134165D01*
X2610087Y-136248D01*
X2609932Y-138331D01*
X2609312Y-139790D01*
X2608537Y-141040D01*
X2607607Y-141873D01*
X2606367Y-142498D01*
X2603267D01*
G01X2541577Y-108898D02*
Y-96398D01*
X2545297D01*
X2546537Y-97023D01*
X2547467Y-98481D01*
X2547777Y-100148D01*
X2547467Y-101815D01*
X2546692Y-103065D01*
X2545297Y-103690D01*
X2541577D01*
G01X2553977Y-96398D02*
Y-108898D01*
X2560177D01*
G01X2565602D02*
X2569477Y-96398D01*
X2573352Y-108898D01*
G01X2571957Y-104523D02*
X2566997D01*
G01X2581877Y-96398D02*
Y-108898D01*
G01X2578312Y-96398D02*
X2585442D01*
G01X2597377Y-108898D02*
X2591177D01*
Y-96398D01*
X2597377D01*
G01X2594897Y-102440D02*
X2591177D01*
G01X2603267Y-108898D02*
Y-96398D01*
X2606367D01*
X2607607Y-97023D01*
X2608537Y-97856D01*
X2609312Y-99106D01*
X2609932Y-100565D01*
X2610087Y-102648D01*
X2609932Y-104731D01*
X2609312Y-106190D01*
X2608537Y-107440D01*
X2607607Y-108273D01*
X2606367Y-108898D01*
X2603267D01*
G01X2541577Y-75298D02*
Y-62798D01*
X2545297D01*
X2546537Y-63423D01*
X2547467Y-64881D01*
X2547777Y-66548D01*
X2547467Y-68215D01*
X2546692Y-69465D01*
X2545297Y-70090D01*
X2541577D01*
G01X2553977Y-62798D02*
Y-75298D01*
X2560177D01*
G01X2565602D02*
X2569477Y-62798D01*
X2573352Y-75298D01*
G01X2571957Y-70923D02*
X2566997D01*
G01X2581877Y-62798D02*
Y-75298D01*
G01X2578312Y-62798D02*
X2585442D01*
G01X2597377Y-75298D02*
X2591177D01*
Y-62798D01*
X2597377D01*
G01X2594897Y-68840D02*
X2591177D01*
G01X2603267Y-75298D02*
Y-62798D01*
X2606367D01*
X2607607Y-63423D01*
X2608537Y-64256D01*
X2609312Y-65506D01*
X2609932Y-66965D01*
X2610087Y-69048D01*
X2609932Y-71131D01*
X2609312Y-72590D01*
X2608537Y-73840D01*
X2607607Y-74673D01*
X2606367Y-75298D01*
X2603267D01*
G01X2541577Y-41698D02*
Y-29198D01*
X2545297D01*
X2546537Y-29823D01*
X2547467Y-31281D01*
X2547777Y-32948D01*
X2547467Y-34615D01*
X2546692Y-35865D01*
X2545297Y-36490D01*
X2541577D01*
G01X2553977Y-29198D02*
Y-41698D01*
X2560177D01*
G01X2565602D02*
X2569477Y-29198D01*
X2573352Y-41698D01*
G01X2571957Y-37323D02*
X2566997D01*
G01X2581877Y-29198D02*
Y-41698D01*
G01X2578312Y-29198D02*
X2585442D01*
G01X2597377Y-41698D02*
X2591177D01*
Y-29198D01*
X2597377D01*
G01X2594897Y-35240D02*
X2591177D01*
G01X2603267Y-41698D02*
Y-29198D01*
X2606367D01*
X2607607Y-29823D01*
X2608537Y-30656D01*
X2609312Y-31906D01*
X2609932Y-33365D01*
X2610087Y-35448D01*
X2609932Y-37531D01*
X2609312Y-38990D01*
X2608537Y-40240D01*
X2607607Y-41073D01*
X2606367Y-41698D01*
X2603267D01*
G01X2516312Y-8098D02*
Y4402D01*
X2523442Y-8098D01*
Y4402D01*
G01X2532277Y-8098D02*
X2531037Y-7890D01*
X2529952Y-7057D01*
X2529022Y-5806D01*
X2528402Y-4348D01*
X2528092Y-2681D01*
Y-1015D01*
X2528402Y652D01*
X2529022Y2110D01*
X2529952Y3360D01*
X2531037Y4194D01*
X2532277Y4402D01*
X2533517Y4194D01*
X2534602Y3360D01*
X2535532Y2110D01*
X2536152Y652D01*
X2536462Y-1015D01*
Y-2681D01*
X2536152Y-4348D01*
X2535532Y-5806D01*
X2534602Y-7057D01*
X2533517Y-7890D01*
X2532277Y-8098D01*
G01X2541112D02*
Y4402D01*
X2548242Y-8098D01*
Y4402D01*
G01X2555062Y-3931D02*
X2559092D01*
G01X2566377Y-8098D02*
Y4402D01*
X2570097D01*
X2571337Y3777D01*
X2572267Y2319D01*
X2572577Y652D01*
X2572267Y-1015D01*
X2571492Y-2265D01*
X2570097Y-2890D01*
X2566377D01*
G01X2578777Y4402D02*
Y-8098D01*
X2584977D01*
G01X2590402D02*
X2594277Y4402D01*
X2598152Y-8098D01*
G01X2596757Y-3723D02*
X2591797D01*
G01X2606677Y4402D02*
Y-8098D01*
G01X2603112Y4402D02*
X2610242D01*
G01X2622177Y-8098D02*
X2615977D01*
Y4402D01*
X2622177D01*
G01X2619697Y-1640D02*
X2615977D01*
G01X2628067Y-8098D02*
Y4402D01*
X2631167D01*
X2632407Y3777D01*
X2633337Y2944D01*
X2634112Y1694D01*
X2634732Y235D01*
X2634887Y-1848D01*
X2634732Y-3931D01*
X2634112Y-5390D01*
X2633337Y-6640D01*
X2632407Y-7473D01*
X2631167Y-8098D01*
X2628067D01*
G01X2516312Y25502D02*
Y38002D01*
X2523442Y25502D01*
Y38002D01*
G01X2532277Y25502D02*
X2531037Y25710D01*
X2529952Y26543D01*
X2529022Y27794D01*
X2528402Y29252D01*
X2528092Y30919D01*
Y32585D01*
X2528402Y34252D01*
X2529022Y35710D01*
X2529952Y36960D01*
X2531037Y37794D01*
X2532277Y38002D01*
X2533517Y37794D01*
X2534602Y36960D01*
X2535532Y35710D01*
X2536152Y34252D01*
X2536462Y32585D01*
Y30919D01*
X2536152Y29252D01*
X2535532Y27794D01*
X2534602Y26543D01*
X2533517Y25710D01*
X2532277Y25502D01*
G01X2541112D02*
Y38002D01*
X2548242Y25502D01*
Y38002D01*
G01X2555062Y29669D02*
X2559092D01*
G01X2566377Y25502D02*
Y38002D01*
X2570097D01*
X2571337Y37377D01*
X2572267Y35919D01*
X2572577Y34252D01*
X2572267Y32585D01*
X2571492Y31335D01*
X2570097Y30710D01*
X2566377D01*
G01X2578777Y38002D02*
Y25502D01*
X2584977D01*
G01X2590402D02*
X2594277Y38002D01*
X2598152Y25502D01*
G01X2596757Y29877D02*
X2591797D01*
G01X2606677Y38002D02*
Y25502D01*
G01X2603112Y38002D02*
X2610242D01*
G01X2622177Y25502D02*
X2615977D01*
Y38002D01*
X2622177D01*
G01X2619697Y31960D02*
X2615977D01*
G01X2628067Y25502D02*
Y38002D01*
X2631167D01*
X2632407Y37377D01*
X2633337Y36544D01*
X2634112Y35294D01*
X2634732Y33835D01*
X2634887Y31752D01*
X2634732Y29669D01*
X2634112Y28210D01*
X2633337Y26960D01*
X2632407Y26127D01*
X2631167Y25502D01*
X2628067D01*
G01X2516312Y59102D02*
Y71602D01*
X2523442Y59102D01*
Y71602D01*
G01X2532277Y59102D02*
X2531037Y59310D01*
X2529952Y60143D01*
X2529022Y61394D01*
X2528402Y62852D01*
X2528092Y64519D01*
Y66185D01*
X2528402Y67852D01*
X2529022Y69310D01*
X2529952Y70560D01*
X2531037Y71394D01*
X2532277Y71602D01*
X2533517Y71394D01*
X2534602Y70560D01*
X2535532Y69310D01*
X2536152Y67852D01*
X2536462Y66185D01*
Y64519D01*
X2536152Y62852D01*
X2535532Y61394D01*
X2534602Y60143D01*
X2533517Y59310D01*
X2532277Y59102D01*
G01X2541112D02*
Y71602D01*
X2548242Y59102D01*
Y71602D01*
G01X2555062Y63269D02*
X2559092D01*
G01X2566377Y59102D02*
Y71602D01*
X2570097D01*
X2571337Y70977D01*
X2572267Y69519D01*
X2572577Y67852D01*
X2572267Y66185D01*
X2571492Y64935D01*
X2570097Y64310D01*
X2566377D01*
G01X2578777Y71602D02*
Y59102D01*
X2584977D01*
G01X2590402D02*
X2594277Y71602D01*
X2598152Y59102D01*
G01X2596757Y63477D02*
X2591797D01*
G01X2606677Y71602D02*
Y59102D01*
G01X2603112Y71602D02*
X2610242D01*
G01X2622177Y59102D02*
X2615977D01*
Y71602D01*
X2622177D01*
G01X2619697Y65560D02*
X2615977D01*
G01X2628067Y59102D02*
Y71602D01*
X2631167D01*
X2632407Y70977D01*
X2633337Y70144D01*
X2634112Y68894D01*
X2634732Y67435D01*
X2634887Y65352D01*
X2634732Y63269D01*
X2634112Y61810D01*
X2633337Y60560D01*
X2632407Y59727D01*
X2631167Y59102D01*
X2628067D01*
G01X2516312Y92702D02*
Y105202D01*
X2523442Y92702D01*
Y105202D01*
G01X2532277Y92702D02*
X2531037Y92910D01*
X2529952Y93743D01*
X2529022Y94994D01*
X2528402Y96452D01*
X2528092Y98119D01*
Y99785D01*
X2528402Y101452D01*
X2529022Y102910D01*
X2529952Y104160D01*
X2531037Y104994D01*
X2532277Y105202D01*
X2533517Y104994D01*
X2534602Y104160D01*
X2535532Y102910D01*
X2536152Y101452D01*
X2536462Y99785D01*
Y98119D01*
X2536152Y96452D01*
X2535532Y94994D01*
X2534602Y93743D01*
X2533517Y92910D01*
X2532277Y92702D01*
G01X2541112D02*
Y105202D01*
X2548242Y92702D01*
Y105202D01*
G01X2555062Y96869D02*
X2559092D01*
G01X2566377Y92702D02*
Y105202D01*
X2570097D01*
X2571337Y104577D01*
X2572267Y103119D01*
X2572577Y101452D01*
X2572267Y99785D01*
X2571492Y98535D01*
X2570097Y97910D01*
X2566377D01*
G01X2578777Y105202D02*
Y92702D01*
X2584977D01*
G01X2590402D02*
X2594277Y105202D01*
X2598152Y92702D01*
G01X2596757Y97077D02*
X2591797D01*
G01X2606677Y105202D02*
Y92702D01*
G01X2603112Y105202D02*
X2610242D01*
G01X2622177Y92702D02*
X2615977D01*
Y105202D01*
X2622177D01*
G01X2619697Y99160D02*
X2615977D01*
G01X2628067Y92702D02*
Y105202D01*
X2631167D01*
X2632407Y104577D01*
X2633337Y103744D01*
X2634112Y102494D01*
X2634732Y101035D01*
X2634887Y98952D01*
X2634732Y96869D01*
X2634112Y95410D01*
X2633337Y94160D01*
X2632407Y93327D01*
X2631167Y92702D01*
X2628067D01*
G01X2516312Y126302D02*
Y138802D01*
X2523442Y126302D01*
Y138802D01*
G01X2532277Y126302D02*
X2531037Y126510D01*
X2529952Y127343D01*
X2529022Y128594D01*
X2528402Y130052D01*
X2528092Y131719D01*
Y133385D01*
X2528402Y135052D01*
X2529022Y136510D01*
X2529952Y137760D01*
X2531037Y138594D01*
X2532277Y138802D01*
X2533517Y138594D01*
X2534602Y137760D01*
X2535532Y136510D01*
X2536152Y135052D01*
X2536462Y133385D01*
Y131719D01*
X2536152Y130052D01*
X2535532Y128594D01*
X2534602Y127343D01*
X2533517Y126510D01*
X2532277Y126302D01*
G01X2541112D02*
Y138802D01*
X2548242Y126302D01*
Y138802D01*
G01X2555062Y130469D02*
X2559092D01*
G01X2566377Y126302D02*
Y138802D01*
X2570097D01*
X2571337Y138177D01*
X2572267Y136719D01*
X2572577Y135052D01*
X2572267Y133385D01*
X2571492Y132135D01*
X2570097Y131510D01*
X2566377D01*
G01X2578777Y138802D02*
Y126302D01*
X2584977D01*
G01X2590402D02*
X2594277Y138802D01*
X2598152Y126302D01*
G01X2596757Y130677D02*
X2591797D01*
G01X2606677Y138802D02*
Y126302D01*
G01X2603112Y138802D02*
X2610242D01*
G01X2622177Y126302D02*
X2615977D01*
Y138802D01*
X2622177D01*
G01X2619697Y132760D02*
X2615977D01*
G01X2628067Y126302D02*
Y138802D01*
X2631167D01*
X2632407Y138177D01*
X2633337Y137344D01*
X2634112Y136094D01*
X2634732Y134635D01*
X2634887Y132552D01*
X2634732Y130469D01*
X2634112Y129010D01*
X2633337Y127760D01*
X2632407Y126927D01*
X2631167Y126302D01*
X2628067D01*
G01X2516312Y159902D02*
Y172402D01*
X2523442Y159902D01*
Y172402D01*
G01X2532277Y159902D02*
X2531037Y160110D01*
X2529952Y160943D01*
X2529022Y162194D01*
X2528402Y163652D01*
X2528092Y165319D01*
Y166985D01*
X2528402Y168652D01*
X2529022Y170110D01*
X2529952Y171360D01*
X2531037Y172194D01*
X2532277Y172402D01*
X2533517Y172194D01*
X2534602Y171360D01*
X2535532Y170110D01*
X2536152Y168652D01*
X2536462Y166985D01*
Y165319D01*
X2536152Y163652D01*
X2535532Y162194D01*
X2534602Y160943D01*
X2533517Y160110D01*
X2532277Y159902D01*
G01X2541112D02*
Y172402D01*
X2548242Y159902D01*
Y172402D01*
G01X2555062Y164069D02*
X2559092D01*
G01X2566377Y159902D02*
Y172402D01*
X2570097D01*
X2571337Y171777D01*
X2572267Y170319D01*
X2572577Y168652D01*
X2572267Y166985D01*
X2571492Y165735D01*
X2570097Y165110D01*
X2566377D01*
G01X2578777Y172402D02*
Y159902D01*
X2584977D01*
G01X2590402D02*
X2594277Y172402D01*
X2598152Y159902D01*
G01X2596757Y164277D02*
X2591797D01*
G01X2606677Y172402D02*
Y159902D01*
G01X2603112Y172402D02*
X2610242D01*
G01X2622177Y159902D02*
X2615977D01*
Y172402D01*
X2622177D01*
G01X2619697Y166360D02*
X2615977D01*
G01X2628067Y159902D02*
Y172402D01*
X2631167D01*
X2632407Y171777D01*
X2633337Y170944D01*
X2634112Y169694D01*
X2634732Y168235D01*
X2634887Y166152D01*
X2634732Y164069D01*
X2634112Y162610D01*
X2633337Y161360D01*
X2632407Y160527D01*
X2631167Y159902D01*
X2628067D01*
G01X2516312Y193502D02*
Y206002D01*
X2523442Y193502D01*
Y206002D01*
G01X2532277Y193502D02*
X2531037Y193710D01*
X2529952Y194543D01*
X2529022Y195794D01*
X2528402Y197252D01*
X2528092Y198919D01*
Y200585D01*
X2528402Y202252D01*
X2529022Y203710D01*
X2529952Y204960D01*
X2531037Y205794D01*
X2532277Y206002D01*
X2533517Y205794D01*
X2534602Y204960D01*
X2535532Y203710D01*
X2536152Y202252D01*
X2536462Y200585D01*
Y198919D01*
X2536152Y197252D01*
X2535532Y195794D01*
X2534602Y194543D01*
X2533517Y193710D01*
X2532277Y193502D01*
G01X2541112D02*
Y206002D01*
X2548242Y193502D01*
Y206002D01*
G01X2555062Y197669D02*
X2559092D01*
G01X2566377Y193502D02*
Y206002D01*
X2570097D01*
X2571337Y205377D01*
X2572267Y203919D01*
X2572577Y202252D01*
X2572267Y200585D01*
X2571492Y199335D01*
X2570097Y198710D01*
X2566377D01*
G01X2578777Y206002D02*
Y193502D01*
X2584977D01*
G01X2590402D02*
X2594277Y206002D01*
X2598152Y193502D01*
G01X2596757Y197877D02*
X2591797D01*
G01X2606677Y206002D02*
Y193502D01*
G01X2603112Y206002D02*
X2610242D01*
G01X2622177Y193502D02*
X2615977D01*
Y206002D01*
X2622177D01*
G01X2619697Y199960D02*
X2615977D01*
G01X2628067Y193502D02*
Y206002D01*
X2631167D01*
X2632407Y205377D01*
X2633337Y204544D01*
X2634112Y203294D01*
X2634732Y201835D01*
X2634887Y199752D01*
X2634732Y197669D01*
X2634112Y196210D01*
X2633337Y194960D01*
X2632407Y194127D01*
X2631167Y193502D01*
X2628067D01*
G01X2516312Y227102D02*
Y239602D01*
X2523442Y227102D01*
Y239602D01*
G01X2532277Y227102D02*
X2531037Y227310D01*
X2529952Y228143D01*
X2529022Y229394D01*
X2528402Y230852D01*
X2528092Y232519D01*
Y234185D01*
X2528402Y235852D01*
X2529022Y237310D01*
X2529952Y238560D01*
X2531037Y239394D01*
X2532277Y239602D01*
X2533517Y239394D01*
X2534602Y238560D01*
X2535532Y237310D01*
X2536152Y235852D01*
X2536462Y234185D01*
Y232519D01*
X2536152Y230852D01*
X2535532Y229394D01*
X2534602Y228143D01*
X2533517Y227310D01*
X2532277Y227102D01*
G01X2541112D02*
Y239602D01*
X2548242Y227102D01*
Y239602D01*
G01X2555062Y231269D02*
X2559092D01*
G01X2566377Y227102D02*
Y239602D01*
X2570097D01*
X2571337Y238977D01*
X2572267Y237519D01*
X2572577Y235852D01*
X2572267Y234185D01*
X2571492Y232935D01*
X2570097Y232310D01*
X2566377D01*
G01X2578777Y239602D02*
Y227102D01*
X2584977D01*
G01X2590402D02*
X2594277Y239602D01*
X2598152Y227102D01*
G01X2596757Y231477D02*
X2591797D01*
G01X2606677Y239602D02*
Y227102D01*
G01X2603112Y239602D02*
X2610242D01*
G01X2622177Y227102D02*
X2615977D01*
Y239602D01*
X2622177D01*
G01X2619697Y233560D02*
X2615977D01*
G01X2628067Y227102D02*
Y239602D01*
X2631167D01*
X2632407Y238977D01*
X2633337Y238144D01*
X2634112Y236894D01*
X2634732Y235435D01*
X2634887Y233352D01*
X2634732Y231269D01*
X2634112Y229810D01*
X2633337Y228560D01*
X2632407Y227727D01*
X2631167Y227102D01*
X2628067D01*
G01X2516312Y260702D02*
Y273202D01*
X2523442Y260702D01*
Y273202D01*
G01X2532277Y260702D02*
X2531037Y260910D01*
X2529952Y261743D01*
X2529022Y262994D01*
X2528402Y264452D01*
X2528092Y266119D01*
Y267785D01*
X2528402Y269452D01*
X2529022Y270910D01*
X2529952Y272160D01*
X2531037Y272994D01*
X2532277Y273202D01*
X2533517Y272994D01*
X2534602Y272160D01*
X2535532Y270910D01*
X2536152Y269452D01*
X2536462Y267785D01*
Y266119D01*
X2536152Y264452D01*
X2535532Y262994D01*
X2534602Y261743D01*
X2533517Y260910D01*
X2532277Y260702D01*
G01X2541112D02*
Y273202D01*
X2548242Y260702D01*
Y273202D01*
G01X2555062Y264869D02*
X2559092D01*
G01X2566377Y260702D02*
Y273202D01*
X2570097D01*
X2571337Y272577D01*
X2572267Y271119D01*
X2572577Y269452D01*
X2572267Y267785D01*
X2571492Y266535D01*
X2570097Y265910D01*
X2566377D01*
G01X2578777Y273202D02*
Y260702D01*
X2584977D01*
G01X2590402D02*
X2594277Y273202D01*
X2598152Y260702D01*
G01X2596757Y265077D02*
X2591797D01*
G01X2606677Y273202D02*
Y260702D01*
G01X2603112Y273202D02*
X2610242D01*
G01X2622177Y260702D02*
X2615977D01*
Y273202D01*
X2622177D01*
G01X2619697Y267160D02*
X2615977D01*
G01X2628067Y260702D02*
Y273202D01*
X2631167D01*
X2632407Y272577D01*
X2633337Y271744D01*
X2634112Y270494D01*
X2634732Y269035D01*
X2634887Y266952D01*
X2634732Y264869D01*
X2634112Y263410D01*
X2633337Y262160D01*
X2632407Y261327D01*
X2631167Y260702D01*
X2628067D01*
G01X2516312Y294302D02*
Y306802D01*
X2523442Y294302D01*
Y306802D01*
G01X2532277Y294302D02*
X2531037Y294510D01*
X2529952Y295343D01*
X2529022Y296594D01*
X2528402Y298052D01*
X2528092Y299719D01*
Y301385D01*
X2528402Y303052D01*
X2529022Y304510D01*
X2529952Y305760D01*
X2531037Y306594D01*
X2532277Y306802D01*
X2533517Y306594D01*
X2534602Y305760D01*
X2535532Y304510D01*
X2536152Y303052D01*
X2536462Y301385D01*
Y299719D01*
X2536152Y298052D01*
X2535532Y296594D01*
X2534602Y295343D01*
X2533517Y294510D01*
X2532277Y294302D01*
G01X2541112D02*
Y306802D01*
X2548242Y294302D01*
Y306802D01*
G01X2555062Y298469D02*
X2559092D01*
G01X2566377Y294302D02*
Y306802D01*
X2570097D01*
X2571337Y306177D01*
X2572267Y304719D01*
X2572577Y303052D01*
X2572267Y301385D01*
X2571492Y300135D01*
X2570097Y299510D01*
X2566377D01*
G01X2578777Y306802D02*
Y294302D01*
X2584977D01*
G01X2590402D02*
X2594277Y306802D01*
X2598152Y294302D01*
G01X2596757Y298677D02*
X2591797D01*
G01X2606677Y306802D02*
Y294302D01*
G01X2603112Y306802D02*
X2610242D01*
G01X2622177Y294302D02*
X2615977D01*
Y306802D01*
X2622177D01*
G01X2619697Y300760D02*
X2615977D01*
G01X2628067Y294302D02*
Y306802D01*
X2631167D01*
X2632407Y306177D01*
X2633337Y305344D01*
X2634112Y304094D01*
X2634732Y302635D01*
X2634887Y300552D01*
X2634732Y298469D01*
X2634112Y297010D01*
X2633337Y295760D01*
X2632407Y294927D01*
X2631167Y294302D01*
X2628067D01*
G01X2516312Y327902D02*
Y340402D01*
X2523442Y327902D01*
Y340402D01*
G01X2532277Y327902D02*
X2531037Y328110D01*
X2529952Y328943D01*
X2529022Y330194D01*
X2528402Y331652D01*
X2528092Y333319D01*
Y334985D01*
X2528402Y336652D01*
X2529022Y338110D01*
X2529952Y339360D01*
X2531037Y340194D01*
X2532277Y340402D01*
X2533517Y340194D01*
X2534602Y339360D01*
X2535532Y338110D01*
X2536152Y336652D01*
X2536462Y334985D01*
Y333319D01*
X2536152Y331652D01*
X2535532Y330194D01*
X2534602Y328943D01*
X2533517Y328110D01*
X2532277Y327902D01*
G01X2541112D02*
Y340402D01*
X2548242Y327902D01*
Y340402D01*
G01X2555062Y332069D02*
X2559092D01*
G01X2566377Y327902D02*
Y340402D01*
X2570097D01*
X2571337Y339777D01*
X2572267Y338319D01*
X2572577Y336652D01*
X2572267Y334985D01*
X2571492Y333735D01*
X2570097Y333110D01*
X2566377D01*
G01X2578777Y340402D02*
Y327902D01*
X2584977D01*
G01X2590402D02*
X2594277Y340402D01*
X2598152Y327902D01*
G01X2596757Y332277D02*
X2591797D01*
G01X2606677Y340402D02*
Y327902D01*
G01X2603112Y340402D02*
X2610242D01*
G01X2622177Y327902D02*
X2615977D01*
Y340402D01*
X2622177D01*
G01X2619697Y334360D02*
X2615977D01*
G01X2628067Y327902D02*
Y340402D01*
X2631167D01*
X2632407Y339777D01*
X2633337Y338944D01*
X2634112Y337694D01*
X2634732Y336235D01*
X2634887Y334152D01*
X2634732Y332069D01*
X2634112Y330610D01*
X2633337Y329360D01*
X2632407Y328527D01*
X2631167Y327902D01*
X2628067D01*
G01X2516312Y361502D02*
Y374002D01*
X2523442Y361502D01*
Y374002D01*
G01X2532277Y361502D02*
X2531037Y361710D01*
X2529952Y362543D01*
X2529022Y363794D01*
X2528402Y365252D01*
X2528092Y366919D01*
Y368585D01*
X2528402Y370252D01*
X2529022Y371710D01*
X2529952Y372960D01*
X2531037Y373794D01*
X2532277Y374002D01*
X2533517Y373794D01*
X2534602Y372960D01*
X2535532Y371710D01*
X2536152Y370252D01*
X2536462Y368585D01*
Y366919D01*
X2536152Y365252D01*
X2535532Y363794D01*
X2534602Y362543D01*
X2533517Y361710D01*
X2532277Y361502D01*
G01X2541112D02*
Y374002D01*
X2548242Y361502D01*
Y374002D01*
G01X2555062Y365669D02*
X2559092D01*
G01X2566377Y361502D02*
Y374002D01*
X2570097D01*
X2571337Y373377D01*
X2572267Y371919D01*
X2572577Y370252D01*
X2572267Y368585D01*
X2571492Y367335D01*
X2570097Y366710D01*
X2566377D01*
G01X2578777Y374002D02*
Y361502D01*
X2584977D01*
G01X2590402D02*
X2594277Y374002D01*
X2598152Y361502D01*
G01X2596757Y365877D02*
X2591797D01*
G01X2606677Y374002D02*
Y361502D01*
G01X2603112Y374002D02*
X2610242D01*
G01X2622177Y361502D02*
X2615977D01*
Y374002D01*
X2622177D01*
G01X2619697Y367960D02*
X2615977D01*
G01X2628067Y361502D02*
Y374002D01*
X2631167D01*
X2632407Y373377D01*
X2633337Y372544D01*
X2634112Y371294D01*
X2634732Y369835D01*
X2634887Y367752D01*
X2634732Y365669D01*
X2634112Y364210D01*
X2633337Y362960D01*
X2632407Y362127D01*
X2631167Y361502D01*
X2628067D01*
G01X2516312Y395102D02*
Y407602D01*
X2523442Y395102D01*
Y407602D01*
G01X2532277Y395102D02*
X2531037Y395310D01*
X2529952Y396143D01*
X2529022Y397394D01*
X2528402Y398852D01*
X2528092Y400519D01*
Y402185D01*
X2528402Y403852D01*
X2529022Y405310D01*
X2529952Y406560D01*
X2531037Y407394D01*
X2532277Y407602D01*
X2533517Y407394D01*
X2534602Y406560D01*
X2535532Y405310D01*
X2536152Y403852D01*
X2536462Y402185D01*
Y400519D01*
X2536152Y398852D01*
X2535532Y397394D01*
X2534602Y396143D01*
X2533517Y395310D01*
X2532277Y395102D01*
G01X2541112D02*
Y407602D01*
X2548242Y395102D01*
Y407602D01*
G01X2555062Y399269D02*
X2559092D01*
G01X2566377Y395102D02*
Y407602D01*
X2570097D01*
X2571337Y406977D01*
X2572267Y405519D01*
X2572577Y403852D01*
X2572267Y402185D01*
X2571492Y400935D01*
X2570097Y400310D01*
X2566377D01*
G01X2578777Y407602D02*
Y395102D01*
X2584977D01*
G01X2590402D02*
X2594277Y407602D01*
X2598152Y395102D01*
G01X2596757Y399477D02*
X2591797D01*
G01X2606677Y407602D02*
Y395102D01*
G01X2603112Y407602D02*
X2610242D01*
G01X2622177Y395102D02*
X2615977D01*
Y407602D01*
X2622177D01*
G01X2619697Y401560D02*
X2615977D01*
G01X2628067Y395102D02*
Y407602D01*
X2631167D01*
X2632407Y406977D01*
X2633337Y406144D01*
X2634112Y404894D01*
X2634732Y403435D01*
X2634887Y401352D01*
X2634732Y399269D01*
X2634112Y397810D01*
X2633337Y396560D01*
X2632407Y395727D01*
X2631167Y395102D01*
X2628067D01*
G01X2516312Y428702D02*
Y441202D01*
X2523442Y428702D01*
Y441202D01*
G01X2532277Y428702D02*
X2531037Y428910D01*
X2529952Y429743D01*
X2529022Y430994D01*
X2528402Y432452D01*
X2528092Y434119D01*
Y435785D01*
X2528402Y437452D01*
X2529022Y438910D01*
X2529952Y440160D01*
X2531037Y440994D01*
X2532277Y441202D01*
X2533517Y440994D01*
X2534602Y440160D01*
X2535532Y438910D01*
X2536152Y437452D01*
X2536462Y435785D01*
Y434119D01*
X2536152Y432452D01*
X2535532Y430994D01*
X2534602Y429743D01*
X2533517Y428910D01*
X2532277Y428702D01*
G01X2541112D02*
Y441202D01*
X2548242Y428702D01*
Y441202D01*
G01X2555062Y432869D02*
X2559092D01*
G01X2566377Y428702D02*
Y441202D01*
X2570097D01*
X2571337Y440577D01*
X2572267Y439119D01*
X2572577Y437452D01*
X2572267Y435785D01*
X2571492Y434535D01*
X2570097Y433910D01*
X2566377D01*
G01X2578777Y441202D02*
Y428702D01*
X2584977D01*
G01X2590402D02*
X2594277Y441202D01*
X2598152Y428702D01*
G01X2596757Y433077D02*
X2591797D01*
G01X2606677Y441202D02*
Y428702D01*
G01X2603112Y441202D02*
X2610242D01*
G01X2622177Y428702D02*
X2615977D01*
Y441202D01*
X2622177D01*
G01X2619697Y435160D02*
X2615977D01*
G01X2628067Y428702D02*
Y441202D01*
X2631167D01*
X2632407Y440577D01*
X2633337Y439744D01*
X2634112Y438494D01*
X2634732Y437035D01*
X2634887Y434952D01*
X2634732Y432869D01*
X2634112Y431410D01*
X2633337Y430160D01*
X2632407Y429327D01*
X2631167Y428702D01*
X2628067D01*
G01X2516312Y462302D02*
Y474802D01*
X2523442Y462302D01*
Y474802D01*
G01X2532277Y462302D02*
X2531037Y462510D01*
X2529952Y463343D01*
X2529022Y464594D01*
X2528402Y466052D01*
X2528092Y467719D01*
Y469385D01*
X2528402Y471052D01*
X2529022Y472510D01*
X2529952Y473760D01*
X2531037Y474594D01*
X2532277Y474802D01*
X2533517Y474594D01*
X2534602Y473760D01*
X2535532Y472510D01*
X2536152Y471052D01*
X2536462Y469385D01*
Y467719D01*
X2536152Y466052D01*
X2535532Y464594D01*
X2534602Y463343D01*
X2533517Y462510D01*
X2532277Y462302D01*
G01X2541112D02*
Y474802D01*
X2548242Y462302D01*
Y474802D01*
G01X2555062Y466469D02*
X2559092D01*
G01X2566377Y462302D02*
Y474802D01*
X2570097D01*
X2571337Y474177D01*
X2572267Y472719D01*
X2572577Y471052D01*
X2572267Y469385D01*
X2571492Y468135D01*
X2570097Y467510D01*
X2566377D01*
G01X2578777Y474802D02*
Y462302D01*
X2584977D01*
G01X2590402D02*
X2594277Y474802D01*
X2598152Y462302D01*
G01X2596757Y466677D02*
X2591797D01*
G01X2606677Y474802D02*
Y462302D01*
G01X2603112Y474802D02*
X2610242D01*
G01X2622177Y462302D02*
X2615977D01*
Y474802D01*
X2622177D01*
G01X2619697Y468760D02*
X2615977D01*
G01X2628067Y462302D02*
Y474802D01*
X2631167D01*
X2632407Y474177D01*
X2633337Y473344D01*
X2634112Y472094D01*
X2634732Y470635D01*
X2634887Y468552D01*
X2634732Y466469D01*
X2634112Y465010D01*
X2633337Y463760D01*
X2632407Y462927D01*
X2631167Y462302D01*
X2628067D01*
G01X2516312Y495902D02*
Y508402D01*
X2523442Y495902D01*
Y508402D01*
G01X2532277Y495902D02*
X2531037Y496110D01*
X2529952Y496943D01*
X2529022Y498194D01*
X2528402Y499652D01*
X2528092Y501319D01*
Y502985D01*
X2528402Y504652D01*
X2529022Y506110D01*
X2529952Y507360D01*
X2531037Y508194D01*
X2532277Y508402D01*
X2533517Y508194D01*
X2534602Y507360D01*
X2535532Y506110D01*
X2536152Y504652D01*
X2536462Y502985D01*
Y501319D01*
X2536152Y499652D01*
X2535532Y498194D01*
X2534602Y496943D01*
X2533517Y496110D01*
X2532277Y495902D01*
G01X2541112D02*
Y508402D01*
X2548242Y495902D01*
Y508402D01*
G01X2555062Y500069D02*
X2559092D01*
G01X2566377Y495902D02*
Y508402D01*
X2570097D01*
X2571337Y507777D01*
X2572267Y506319D01*
X2572577Y504652D01*
X2572267Y502985D01*
X2571492Y501735D01*
X2570097Y501110D01*
X2566377D01*
G01X2578777Y508402D02*
Y495902D01*
X2584977D01*
G01X2590402D02*
X2594277Y508402D01*
X2598152Y495902D01*
G01X2596757Y500277D02*
X2591797D01*
G01X2606677Y508402D02*
Y495902D01*
G01X2603112Y508402D02*
X2610242D01*
G01X2622177Y495902D02*
X2615977D01*
Y508402D01*
X2622177D01*
G01X2619697Y502360D02*
X2615977D01*
G01X2628067Y495902D02*
Y508402D01*
X2631167D01*
X2632407Y507777D01*
X2633337Y506944D01*
X2634112Y505694D01*
X2634732Y504235D01*
X2634887Y502152D01*
X2634732Y500069D01*
X2634112Y498610D01*
X2633337Y497360D01*
X2632407Y496527D01*
X2631167Y495902D01*
X2628067D01*
G01X2516312Y529502D02*
Y542002D01*
X2523442Y529502D01*
Y542002D01*
G01X2532277Y529502D02*
X2531037Y529710D01*
X2529952Y530543D01*
X2529022Y531794D01*
X2528402Y533252D01*
X2528092Y534919D01*
Y536585D01*
X2528402Y538252D01*
X2529022Y539710D01*
X2529952Y540960D01*
X2531037Y541794D01*
X2532277Y542002D01*
X2533517Y541794D01*
X2534602Y540960D01*
X2535532Y539710D01*
X2536152Y538252D01*
X2536462Y536585D01*
Y534919D01*
X2536152Y533252D01*
X2535532Y531794D01*
X2534602Y530543D01*
X2533517Y529710D01*
X2532277Y529502D01*
G01X2541112D02*
Y542002D01*
X2548242Y529502D01*
Y542002D01*
G01X2555062Y533669D02*
X2559092D01*
G01X2566377Y529502D02*
Y542002D01*
X2570097D01*
X2571337Y541377D01*
X2572267Y539919D01*
X2572577Y538252D01*
X2572267Y536585D01*
X2571492Y535335D01*
X2570097Y534710D01*
X2566377D01*
G01X2578777Y542002D02*
Y529502D01*
X2584977D01*
G01X2590402D02*
X2594277Y542002D01*
X2598152Y529502D01*
G01X2596757Y533877D02*
X2591797D01*
G01X2606677Y542002D02*
Y529502D01*
G01X2603112Y542002D02*
X2610242D01*
G01X2622177Y529502D02*
X2615977D01*
Y542002D01*
X2622177D01*
G01X2619697Y535960D02*
X2615977D01*
G01X2628067Y529502D02*
Y542002D01*
X2631167D01*
X2632407Y541377D01*
X2633337Y540544D01*
X2634112Y539294D01*
X2634732Y537835D01*
X2634887Y535752D01*
X2634732Y533669D01*
X2634112Y532210D01*
X2633337Y530960D01*
X2632407Y530127D01*
X2631167Y529502D01*
X2628067D01*
G01X2516312Y563102D02*
Y575602D01*
X2523442Y563102D01*
Y575602D01*
G01X2532277Y563102D02*
X2531037Y563310D01*
X2529952Y564143D01*
X2529022Y565394D01*
X2528402Y566852D01*
X2528092Y568519D01*
Y570185D01*
X2528402Y571852D01*
X2529022Y573310D01*
X2529952Y574560D01*
X2531037Y575394D01*
X2532277Y575602D01*
X2533517Y575394D01*
X2534602Y574560D01*
X2535532Y573310D01*
X2536152Y571852D01*
X2536462Y570185D01*
Y568519D01*
X2536152Y566852D01*
X2535532Y565394D01*
X2534602Y564143D01*
X2533517Y563310D01*
X2532277Y563102D01*
G01X2541112D02*
Y575602D01*
X2548242Y563102D01*
Y575602D01*
G01X2555062Y567269D02*
X2559092D01*
G01X2566377Y563102D02*
Y575602D01*
X2570097D01*
X2571337Y574977D01*
X2572267Y573519D01*
X2572577Y571852D01*
X2572267Y570185D01*
X2571492Y568935D01*
X2570097Y568310D01*
X2566377D01*
G01X2578777Y575602D02*
Y563102D01*
X2584977D01*
G01X2590402D02*
X2594277Y575602D01*
X2598152Y563102D01*
G01X2596757Y567477D02*
X2591797D01*
G01X2606677Y575602D02*
Y563102D01*
G01X2603112Y575602D02*
X2610242D01*
G01X2622177Y563102D02*
X2615977D01*
Y575602D01*
X2622177D01*
G01X2619697Y569560D02*
X2615977D01*
G01X2628067Y563102D02*
Y575602D01*
X2631167D01*
X2632407Y574977D01*
X2633337Y574144D01*
X2634112Y572894D01*
X2634732Y571435D01*
X2634887Y569352D01*
X2634732Y567269D01*
X2634112Y565810D01*
X2633337Y564560D01*
X2632407Y563727D01*
X2631167Y563102D01*
X2628067D01*
G01X2516312Y596702D02*
Y609202D01*
X2523442Y596702D01*
Y609202D01*
G01X2532277Y596702D02*
X2531037Y596910D01*
X2529952Y597743D01*
X2529022Y598994D01*
X2528402Y600452D01*
X2528092Y602119D01*
Y603785D01*
X2528402Y605452D01*
X2529022Y606910D01*
X2529952Y608160D01*
X2531037Y608994D01*
X2532277Y609202D01*
X2533517Y608994D01*
X2534602Y608160D01*
X2535532Y606910D01*
X2536152Y605452D01*
X2536462Y603785D01*
Y602119D01*
X2536152Y600452D01*
X2535532Y598994D01*
X2534602Y597743D01*
X2533517Y596910D01*
X2532277Y596702D01*
G01X2541112D02*
Y609202D01*
X2548242Y596702D01*
Y609202D01*
G01X2555062Y600869D02*
X2559092D01*
G01X2566377Y596702D02*
Y609202D01*
X2570097D01*
X2571337Y608577D01*
X2572267Y607119D01*
X2572577Y605452D01*
X2572267Y603785D01*
X2571492Y602535D01*
X2570097Y601910D01*
X2566377D01*
G01X2578777Y609202D02*
Y596702D01*
X2584977D01*
G01X2590402D02*
X2594277Y609202D01*
X2598152Y596702D01*
G01X2596757Y601077D02*
X2591797D01*
G01X2606677Y609202D02*
Y596702D01*
G01X2603112Y609202D02*
X2610242D01*
G01X2622177Y596702D02*
X2615977D01*
Y609202D01*
X2622177D01*
G01X2619697Y603160D02*
X2615977D01*
G01X2628067Y596702D02*
Y609202D01*
X2631167D01*
X2632407Y608577D01*
X2633337Y607744D01*
X2634112Y606494D01*
X2634732Y605035D01*
X2634887Y602952D01*
X2634732Y600869D01*
X2634112Y599410D01*
X2633337Y598160D01*
X2632407Y597327D01*
X2631167Y596702D01*
X2628067D01*
G01X2516312Y630302D02*
Y642802D01*
X2523442Y630302D01*
Y642802D01*
G01X2532277Y630302D02*
X2531037Y630510D01*
X2529952Y631343D01*
X2529022Y632594D01*
X2528402Y634052D01*
X2528092Y635719D01*
Y637385D01*
X2528402Y639052D01*
X2529022Y640510D01*
X2529952Y641760D01*
X2531037Y642594D01*
X2532277Y642802D01*
X2533517Y642594D01*
X2534602Y641760D01*
X2535532Y640510D01*
X2536152Y639052D01*
X2536462Y637385D01*
Y635719D01*
X2536152Y634052D01*
X2535532Y632594D01*
X2534602Y631343D01*
X2533517Y630510D01*
X2532277Y630302D01*
G01X2541112D02*
Y642802D01*
X2548242Y630302D01*
Y642802D01*
G01X2555062Y634469D02*
X2559092D01*
G01X2566377Y630302D02*
Y642802D01*
X2570097D01*
X2571337Y642177D01*
X2572267Y640719D01*
X2572577Y639052D01*
X2572267Y637385D01*
X2571492Y636135D01*
X2570097Y635510D01*
X2566377D01*
G01X2578777Y642802D02*
Y630302D01*
X2584977D01*
G01X2590402D02*
X2594277Y642802D01*
X2598152Y630302D01*
G01X2596757Y634677D02*
X2591797D01*
G01X2606677Y642802D02*
Y630302D01*
G01X2603112Y642802D02*
X2610242D01*
G01X2622177Y630302D02*
X2615977D01*
Y642802D01*
X2622177D01*
G01X2619697Y636760D02*
X2615977D01*
G01X2628067Y630302D02*
Y642802D01*
X2631167D01*
X2632407Y642177D01*
X2633337Y641344D01*
X2634112Y640094D01*
X2634732Y638635D01*
X2634887Y636552D01*
X2634732Y634469D01*
X2634112Y633010D01*
X2633337Y631760D01*
X2632407Y630927D01*
X2631167Y630302D01*
X2628067D01*
G01X2516312Y663902D02*
Y676402D01*
X2523442Y663902D01*
Y676402D01*
G01X2532277Y663902D02*
X2531037Y664110D01*
X2529952Y664943D01*
X2529022Y666194D01*
X2528402Y667652D01*
X2528092Y669319D01*
Y670985D01*
X2528402Y672652D01*
X2529022Y674110D01*
X2529952Y675360D01*
X2531037Y676194D01*
X2532277Y676402D01*
X2533517Y676194D01*
X2534602Y675360D01*
X2535532Y674110D01*
X2536152Y672652D01*
X2536462Y670985D01*
Y669319D01*
X2536152Y667652D01*
X2535532Y666194D01*
X2534602Y664943D01*
X2533517Y664110D01*
X2532277Y663902D01*
G01X2541112D02*
Y676402D01*
X2548242Y663902D01*
Y676402D01*
G01X2555062Y668069D02*
X2559092D01*
G01X2566377Y663902D02*
Y676402D01*
X2570097D01*
X2571337Y675777D01*
X2572267Y674319D01*
X2572577Y672652D01*
X2572267Y670985D01*
X2571492Y669735D01*
X2570097Y669110D01*
X2566377D01*
G01X2578777Y676402D02*
Y663902D01*
X2584977D01*
G01X2590402D02*
X2594277Y676402D01*
X2598152Y663902D01*
G01X2596757Y668277D02*
X2591797D01*
G01X2606677Y676402D02*
Y663902D01*
G01X2603112Y676402D02*
X2610242D01*
G01X2622177Y663902D02*
X2615977D01*
Y676402D01*
X2622177D01*
G01X2619697Y670360D02*
X2615977D01*
G01X2628067Y663902D02*
Y676402D01*
X2631167D01*
X2632407Y675777D01*
X2633337Y674944D01*
X2634112Y673694D01*
X2634732Y672235D01*
X2634887Y670152D01*
X2634732Y668069D01*
X2634112Y666610D01*
X2633337Y665360D01*
X2632407Y664527D01*
X2631167Y663902D01*
X2628067D01*
G01X2516312Y697502D02*
Y710002D01*
X2523442Y697502D01*
Y710002D01*
G01X2532277Y697502D02*
X2531037Y697710D01*
X2529952Y698543D01*
X2529022Y699794D01*
X2528402Y701252D01*
X2528092Y702919D01*
Y704585D01*
X2528402Y706252D01*
X2529022Y707710D01*
X2529952Y708960D01*
X2531037Y709794D01*
X2532277Y710002D01*
X2533517Y709794D01*
X2534602Y708960D01*
X2535532Y707710D01*
X2536152Y706252D01*
X2536462Y704585D01*
Y702919D01*
X2536152Y701252D01*
X2535532Y699794D01*
X2534602Y698543D01*
X2533517Y697710D01*
X2532277Y697502D01*
G01X2541112D02*
Y710002D01*
X2548242Y697502D01*
Y710002D01*
G01X2555062Y701669D02*
X2559092D01*
G01X2566377Y697502D02*
Y710002D01*
X2570097D01*
X2571337Y709377D01*
X2572267Y707919D01*
X2572577Y706252D01*
X2572267Y704585D01*
X2571492Y703335D01*
X2570097Y702710D01*
X2566377D01*
G01X2578777Y710002D02*
Y697502D01*
X2584977D01*
G01X2590402D02*
X2594277Y710002D01*
X2598152Y697502D01*
G01X2596757Y701877D02*
X2591797D01*
G01X2606677Y710002D02*
Y697502D01*
G01X2603112Y710002D02*
X2610242D01*
G01X2622177Y697502D02*
X2615977D01*
Y710002D01*
X2622177D01*
G01X2619697Y703960D02*
X2615977D01*
G01X2628067Y697502D02*
Y710002D01*
X2631167D01*
X2632407Y709377D01*
X2633337Y708544D01*
X2634112Y707294D01*
X2634732Y705835D01*
X2634887Y703752D01*
X2634732Y701669D01*
X2634112Y700210D01*
X2633337Y698960D01*
X2632407Y698127D01*
X2631167Y697502D01*
X2628067D01*
G01X2516312Y731102D02*
Y743602D01*
X2523442Y731102D01*
Y743602D01*
G01X2532277Y731102D02*
X2531037Y731310D01*
X2529952Y732143D01*
X2529022Y733394D01*
X2528402Y734852D01*
X2528092Y736519D01*
Y738185D01*
X2528402Y739852D01*
X2529022Y741310D01*
X2529952Y742560D01*
X2531037Y743394D01*
X2532277Y743602D01*
X2533517Y743394D01*
X2534602Y742560D01*
X2535532Y741310D01*
X2536152Y739852D01*
X2536462Y738185D01*
Y736519D01*
X2536152Y734852D01*
X2535532Y733394D01*
X2534602Y732143D01*
X2533517Y731310D01*
X2532277Y731102D01*
G01X2541112D02*
Y743602D01*
X2548242Y731102D01*
Y743602D01*
G01X2555062Y735269D02*
X2559092D01*
G01X2566377Y731102D02*
Y743602D01*
X2570097D01*
X2571337Y742977D01*
X2572267Y741519D01*
X2572577Y739852D01*
X2572267Y738185D01*
X2571492Y736935D01*
X2570097Y736310D01*
X2566377D01*
G01X2578777Y743602D02*
Y731102D01*
X2584977D01*
G01X2590402D02*
X2594277Y743602D01*
X2598152Y731102D01*
G01X2596757Y735477D02*
X2591797D01*
G01X2606677Y743602D02*
Y731102D01*
G01X2603112Y743602D02*
X2610242D01*
G01X2622177Y731102D02*
X2615977D01*
Y743602D01*
X2622177D01*
G01X2619697Y737560D02*
X2615977D01*
G01X2628067Y731102D02*
Y743602D01*
X2631167D01*
X2632407Y742977D01*
X2633337Y742144D01*
X2634112Y740894D01*
X2634732Y739435D01*
X2634887Y737352D01*
X2634732Y735269D01*
X2634112Y733810D01*
X2633337Y732560D01*
X2632407Y731727D01*
X2631167Y731102D01*
X2628067D01*
G01X2541577Y764702D02*
Y777202D01*
X2545297D01*
X2546537Y776577D01*
X2547467Y775119D01*
X2547777Y773452D01*
X2547467Y771785D01*
X2546692Y770535D01*
X2545297Y769910D01*
X2541577D01*
G01X2553977Y777202D02*
Y764702D01*
X2560177D01*
G01X2565602D02*
X2569477Y777202D01*
X2573352Y764702D01*
G01X2571957Y769077D02*
X2566997D01*
G01X2581877Y777202D02*
Y764702D01*
G01X2578312Y777202D02*
X2585442D01*
G01X2597377Y764702D02*
X2591177D01*
Y777202D01*
X2597377D01*
G01X2594897Y771160D02*
X2591177D01*
G01X2603267Y764702D02*
Y777202D01*
X2606367D01*
X2607607Y776577D01*
X2608537Y775744D01*
X2609312Y774494D01*
X2609932Y773035D01*
X2610087Y770952D01*
X2609932Y768869D01*
X2609312Y767410D01*
X2608537Y766160D01*
X2607607Y765327D01*
X2606367Y764702D01*
X2603267D01*
G01X2541577Y798302D02*
Y810802D01*
X2545297D01*
X2546537Y810177D01*
X2547467Y808719D01*
X2547777Y807052D01*
X2547467Y805385D01*
X2546692Y804135D01*
X2545297Y803510D01*
X2541577D01*
G01X2553977Y810802D02*
Y798302D01*
X2560177D01*
G01X2565602D02*
X2569477Y810802D01*
X2573352Y798302D01*
G01X2571957Y802677D02*
X2566997D01*
G01X2581877Y810802D02*
Y798302D01*
G01X2578312Y810802D02*
X2585442D01*
G01X2597377Y798302D02*
X2591177D01*
Y810802D01*
X2597377D01*
G01X2594897Y804760D02*
X2591177D01*
G01X2603267Y798302D02*
Y810802D01*
X2606367D01*
X2607607Y810177D01*
X2608537Y809344D01*
X2609312Y808094D01*
X2609932Y806635D01*
X2610087Y804552D01*
X2609932Y802469D01*
X2609312Y801010D01*
X2608537Y799760D01*
X2607607Y798927D01*
X2606367Y798302D01*
X2603267D01*
G01X2541577Y831902D02*
Y844402D01*
X2545297D01*
X2546537Y843777D01*
X2547467Y842319D01*
X2547777Y840652D01*
X2547467Y838985D01*
X2546692Y837735D01*
X2545297Y837110D01*
X2541577D01*
G01X2553977Y844402D02*
Y831902D01*
X2560177D01*
G01X2565602D02*
X2569477Y844402D01*
X2573352Y831902D01*
G01X2571957Y836277D02*
X2566997D01*
G01X2581877Y844402D02*
Y831902D01*
G01X2578312Y844402D02*
X2585442D01*
G01X2597377Y831902D02*
X2591177D01*
Y844402D01*
X2597377D01*
G01X2594897Y838360D02*
X2591177D01*
G01X2603267Y831902D02*
Y844402D01*
X2606367D01*
X2607607Y843777D01*
X2608537Y842944D01*
X2609312Y841694D01*
X2609932Y840235D01*
X2610087Y838152D01*
X2609932Y836069D01*
X2609312Y834610D01*
X2608537Y833360D01*
X2607607Y832527D01*
X2606367Y831902D01*
X2603267D01*
G01X2541577Y865502D02*
Y878002D01*
X2545297D01*
X2546537Y877377D01*
X2547467Y875919D01*
X2547777Y874252D01*
X2547467Y872585D01*
X2546692Y871335D01*
X2545297Y870710D01*
X2541577D01*
G01X2553977Y878002D02*
Y865502D01*
X2560177D01*
G01X2565602D02*
X2569477Y878002D01*
X2573352Y865502D01*
G01X2571957Y869877D02*
X2566997D01*
G01X2581877Y878002D02*
Y865502D01*
G01X2578312Y878002D02*
X2585442D01*
G01X2597377Y865502D02*
X2591177D01*
Y878002D01*
X2597377D01*
G01X2594897Y871960D02*
X2591177D01*
G01X2603267Y865502D02*
Y878002D01*
X2606367D01*
X2607607Y877377D01*
X2608537Y876544D01*
X2609312Y875294D01*
X2609932Y873835D01*
X2610087Y871752D01*
X2609932Y869669D01*
X2609312Y868210D01*
X2608537Y866960D01*
X2607607Y866127D01*
X2606367Y865502D01*
X2603267D01*
G01X2541577Y899102D02*
Y911602D01*
X2545297D01*
X2546537Y910977D01*
X2547467Y909519D01*
X2547777Y907852D01*
X2547467Y906185D01*
X2546692Y904935D01*
X2545297Y904310D01*
X2541577D01*
G01X2553977Y911602D02*
Y899102D01*
X2560177D01*
G01X2565602D02*
X2569477Y911602D01*
X2573352Y899102D01*
G01X2571957Y903477D02*
X2566997D01*
G01X2581877Y911602D02*
Y899102D01*
G01X2578312Y911602D02*
X2585442D01*
G01X2597377Y899102D02*
X2591177D01*
Y911602D01*
X2597377D01*
G01X2594897Y905560D02*
X2591177D01*
G01X2603267Y899102D02*
Y911602D01*
X2606367D01*
X2607607Y910977D01*
X2608537Y910144D01*
X2609312Y908894D01*
X2609932Y907435D01*
X2610087Y905352D01*
X2609932Y903269D01*
X2609312Y901810D01*
X2608537Y900560D01*
X2607607Y899727D01*
X2606367Y899102D01*
X2603267D01*
G01X2541577Y932702D02*
Y945202D01*
X2545297D01*
X2546537Y944577D01*
X2547467Y943119D01*
X2547777Y941452D01*
X2547467Y939785D01*
X2546692Y938535D01*
X2545297Y937910D01*
X2541577D01*
G01X2553977Y945202D02*
Y932702D01*
X2560177D01*
G01X2565602D02*
X2569477Y945202D01*
X2573352Y932702D01*
G01X2571957Y937077D02*
X2566997D01*
G01X2581877Y945202D02*
Y932702D01*
G01X2578312Y945202D02*
X2585442D01*
G01X2597377Y932702D02*
X2591177D01*
Y945202D01*
X2597377D01*
G01X2594897Y939160D02*
X2591177D01*
G01X2603267Y932702D02*
Y945202D01*
X2606367D01*
X2607607Y944577D01*
X2608537Y943744D01*
X2609312Y942494D01*
X2609932Y941035D01*
X2610087Y938952D01*
X2609932Y936869D01*
X2609312Y935410D01*
X2608537Y934160D01*
X2607607Y933327D01*
X2606367Y932702D01*
X2603267D01*
G01X2541577Y966302D02*
Y978802D01*
X2545297D01*
X2546537Y978177D01*
X2547467Y976719D01*
X2547777Y975052D01*
X2547467Y973385D01*
X2546692Y972135D01*
X2545297Y971510D01*
X2541577D01*
G01X2553977Y978802D02*
Y966302D01*
X2560177D01*
G01X2565602D02*
X2569477Y978802D01*
X2573352Y966302D01*
G01X2571957Y970677D02*
X2566997D01*
G01X2581877Y978802D02*
Y966302D01*
G01X2578312Y978802D02*
X2585442D01*
G01X2597377Y966302D02*
X2591177D01*
Y978802D01*
X2597377D01*
G01X2594897Y972760D02*
X2591177D01*
G01X2603267Y966302D02*
Y978802D01*
X2606367D01*
X2607607Y978177D01*
X2608537Y977344D01*
X2609312Y976094D01*
X2609932Y974635D01*
X2610087Y972552D01*
X2609932Y970469D01*
X2609312Y969010D01*
X2608537Y967760D01*
X2607607Y966927D01*
X2606367Y966302D01*
X2603267D01*
G01X2541577Y999902D02*
Y1012402D01*
X2545297D01*
X2546537Y1011777D01*
X2547467Y1010319D01*
X2547777Y1008652D01*
X2547467Y1006985D01*
X2546692Y1005735D01*
X2545297Y1005110D01*
X2541577D01*
G01X2553977Y1012402D02*
Y999902D01*
X2560177D01*
G01X2565602D02*
X2569477Y1012402D01*
X2573352Y999902D01*
G01X2571957Y1004277D02*
X2566997D01*
G01X2581877Y1012402D02*
Y999902D01*
G01X2578312Y1012402D02*
X2585442D01*
G01X2597377Y999902D02*
X2591177D01*
Y1012402D01*
X2597377D01*
G01X2594897Y1006360D02*
X2591177D01*
G01X2603267Y999902D02*
Y1012402D01*
X2606367D01*
X2607607Y1011777D01*
X2608537Y1010944D01*
X2609312Y1009694D01*
X2609932Y1008235D01*
X2610087Y1006152D01*
X2609932Y1004069D01*
X2609312Y1002610D01*
X2608537Y1001360D01*
X2607607Y1000527D01*
X2606367Y999902D01*
X2603267D01*
G01X2541577Y1033502D02*
Y1046002D01*
X2545297D01*
X2546537Y1045377D01*
X2547467Y1043919D01*
X2547777Y1042252D01*
X2547467Y1040585D01*
X2546692Y1039335D01*
X2545297Y1038710D01*
X2541577D01*
G01X2553977Y1046002D02*
Y1033502D01*
X2560177D01*
G01X2565602D02*
X2569477Y1046002D01*
X2573352Y1033502D01*
G01X2571957Y1037877D02*
X2566997D01*
G01X2581877Y1046002D02*
Y1033502D01*
G01X2578312Y1046002D02*
X2585442D01*
G01X2597377Y1033502D02*
X2591177D01*
Y1046002D01*
X2597377D01*
G01X2594897Y1039960D02*
X2591177D01*
G01X2603267Y1033502D02*
Y1046002D01*
X2606367D01*
X2607607Y1045377D01*
X2608537Y1044544D01*
X2609312Y1043294D01*
X2609932Y1041835D01*
X2610087Y1039752D01*
X2609932Y1037669D01*
X2609312Y1036210D01*
X2608537Y1034960D01*
X2607607Y1034127D01*
X2606367Y1033502D01*
X2603267D01*
G01X2541577Y1067102D02*
Y1079602D01*
X2545297D01*
X2546537Y1078977D01*
X2547467Y1077519D01*
X2547777Y1075852D01*
X2547467Y1074185D01*
X2546692Y1072935D01*
X2545297Y1072310D01*
X2541577D01*
G01X2553977Y1079602D02*
Y1067102D01*
X2560177D01*
G01X2565602D02*
X2569477Y1079602D01*
X2573352Y1067102D01*
G01X2571957Y1071477D02*
X2566997D01*
G01X2581877Y1079602D02*
Y1067102D01*
G01X2578312Y1079602D02*
X2585442D01*
G01X2597377Y1067102D02*
X2591177D01*
Y1079602D01*
X2597377D01*
G01X2594897Y1073560D02*
X2591177D01*
G01X2603267Y1067102D02*
Y1079602D01*
X2606367D01*
X2607607Y1078977D01*
X2608537Y1078144D01*
X2609312Y1076894D01*
X2609932Y1075435D01*
X2610087Y1073352D01*
X2609932Y1071269D01*
X2609312Y1069810D01*
X2608537Y1068560D01*
X2607607Y1067727D01*
X2606367Y1067102D01*
X2603267D01*
G01X2541577Y1100702D02*
Y1113202D01*
X2545297D01*
X2546537Y1112577D01*
X2547467Y1111119D01*
X2547777Y1109452D01*
X2547467Y1107785D01*
X2546692Y1106535D01*
X2545297Y1105910D01*
X2541577D01*
G01X2553977Y1113202D02*
Y1100702D01*
X2560177D01*
G01X2565602D02*
X2569477Y1113202D01*
X2573352Y1100702D01*
G01X2571957Y1105077D02*
X2566997D01*
G01X2581877Y1113202D02*
Y1100702D01*
G01X2578312Y1113202D02*
X2585442D01*
G01X2597377Y1100702D02*
X2591177D01*
Y1113202D01*
X2597377D01*
G01X2594897Y1107160D02*
X2591177D01*
G01X2603267Y1100702D02*
Y1113202D01*
X2606367D01*
X2607607Y1112577D01*
X2608537Y1111744D01*
X2609312Y1110494D01*
X2609932Y1109035D01*
X2610087Y1106952D01*
X2609932Y1104869D01*
X2609312Y1103410D01*
X2608537Y1102160D01*
X2607607Y1101327D01*
X2606367Y1100702D01*
X2603267D01*
G01X2541577Y1134302D02*
Y1146802D01*
X2545297D01*
X2546537Y1146177D01*
X2547467Y1144719D01*
X2547777Y1143052D01*
X2547467Y1141385D01*
X2546692Y1140135D01*
X2545297Y1139510D01*
X2541577D01*
G01X2553977Y1146802D02*
Y1134302D01*
X2560177D01*
G01X2565602D02*
X2569477Y1146802D01*
X2573352Y1134302D01*
G01X2571957Y1138677D02*
X2566997D01*
G01X2581877Y1146802D02*
Y1134302D01*
G01X2578312Y1146802D02*
X2585442D01*
G01X2597377Y1134302D02*
X2591177D01*
Y1146802D01*
X2597377D01*
G01X2594897Y1140760D02*
X2591177D01*
G01X2603267Y1134302D02*
Y1146802D01*
X2606367D01*
X2607607Y1146177D01*
X2608537Y1145344D01*
X2609312Y1144094D01*
X2609932Y1142635D01*
X2610087Y1140552D01*
X2609932Y1138469D01*
X2609312Y1137010D01*
X2608537Y1135760D01*
X2607607Y1134927D01*
X2606367Y1134302D01*
X2603267D01*
G01X2541577Y1167902D02*
Y1180402D01*
X2545297D01*
X2546537Y1179777D01*
X2547467Y1178319D01*
X2547777Y1176652D01*
X2547467Y1174985D01*
X2546692Y1173735D01*
X2545297Y1173110D01*
X2541577D01*
G01X2553977Y1180402D02*
Y1167902D01*
X2560177D01*
G01X2565602D02*
X2569477Y1180402D01*
X2573352Y1167902D01*
G01X2571957Y1172277D02*
X2566997D01*
G01X2581877Y1180402D02*
Y1167902D01*
G01X2578312Y1180402D02*
X2585442D01*
G01X2597377Y1167902D02*
X2591177D01*
Y1180402D01*
X2597377D01*
G01X2594897Y1174360D02*
X2591177D01*
G01X2603267Y1167902D02*
Y1180402D01*
X2606367D01*
X2607607Y1179777D01*
X2608537Y1178944D01*
X2609312Y1177694D01*
X2609932Y1176235D01*
X2610087Y1174152D01*
X2609932Y1172069D01*
X2609312Y1170610D01*
X2608537Y1169360D01*
X2607607Y1168527D01*
X2606367Y1167902D01*
X2603267D01*
G01X2541577Y1201502D02*
Y1214002D01*
X2545297D01*
X2546537Y1213377D01*
X2547467Y1211919D01*
X2547777Y1210252D01*
X2547467Y1208585D01*
X2546692Y1207335D01*
X2545297Y1206710D01*
X2541577D01*
G01X2553977Y1214002D02*
Y1201502D01*
X2560177D01*
G01X2565602D02*
X2569477Y1214002D01*
X2573352Y1201502D01*
G01X2571957Y1205877D02*
X2566997D01*
G01X2581877Y1214002D02*
Y1201502D01*
G01X2578312Y1214002D02*
X2585442D01*
G01X2597377Y1201502D02*
X2591177D01*
Y1214002D01*
X2597377D01*
G01X2594897Y1207960D02*
X2591177D01*
G01X2603267Y1201502D02*
Y1214002D01*
X2606367D01*
X2607607Y1213377D01*
X2608537Y1212544D01*
X2609312Y1211294D01*
X2609932Y1209835D01*
X2610087Y1207752D01*
X2609932Y1205669D01*
X2609312Y1204210D01*
X2608537Y1202960D01*
X2607607Y1202127D01*
X2606367Y1201502D01*
X2603267D01*
G01X2541577Y1235102D02*
Y1247602D01*
X2545297D01*
X2546537Y1246977D01*
X2547467Y1245519D01*
X2547777Y1243852D01*
X2547467Y1242185D01*
X2546692Y1240935D01*
X2545297Y1240310D01*
X2541577D01*
G01X2553977Y1247602D02*
Y1235102D01*
X2560177D01*
G01X2565602D02*
X2569477Y1247602D01*
X2573352Y1235102D01*
G01X2571957Y1239477D02*
X2566997D01*
G01X2581877Y1247602D02*
Y1235102D01*
G01X2578312Y1247602D02*
X2585442D01*
G01X2597377Y1235102D02*
X2591177D01*
Y1247602D01*
X2597377D01*
G01X2594897Y1241560D02*
X2591177D01*
G01X2603267Y1235102D02*
Y1247602D01*
X2606367D01*
X2607607Y1246977D01*
X2608537Y1246144D01*
X2609312Y1244894D01*
X2609932Y1243435D01*
X2610087Y1241352D01*
X2609932Y1239269D01*
X2609312Y1237810D01*
X2608537Y1236560D01*
X2607607Y1235727D01*
X2606367Y1235102D01*
X2603267D01*
G01X2541577Y1268702D02*
Y1281202D01*
X2545297D01*
X2546537Y1280577D01*
X2547467Y1279119D01*
X2547777Y1277452D01*
X2547467Y1275785D01*
X2546692Y1274535D01*
X2545297Y1273910D01*
X2541577D01*
G01X2553977Y1281202D02*
Y1268702D01*
X2560177D01*
G01X2565602D02*
X2569477Y1281202D01*
X2573352Y1268702D01*
G01X2571957Y1273077D02*
X2566997D01*
G01X2581877Y1281202D02*
Y1268702D01*
G01X2578312Y1281202D02*
X2585442D01*
G01X2597377Y1268702D02*
X2591177D01*
Y1281202D01*
X2597377D01*
G01X2594897Y1275160D02*
X2591177D01*
G01X2603267Y1268702D02*
Y1281202D01*
X2606367D01*
X2607607Y1280577D01*
X2608537Y1279744D01*
X2609312Y1278494D01*
X2609932Y1277035D01*
X2610087Y1274952D01*
X2609932Y1272869D01*
X2609312Y1271410D01*
X2608537Y1270160D01*
X2607607Y1269327D01*
X2606367Y1268702D01*
X2603267D01*
G01X2541577Y1302302D02*
Y1314802D01*
X2545297D01*
X2546537Y1314177D01*
X2547467Y1312719D01*
X2547777Y1311052D01*
X2547467Y1309385D01*
X2546692Y1308135D01*
X2545297Y1307510D01*
X2541577D01*
G01X2553977Y1314802D02*
Y1302302D01*
X2560177D01*
G01X2565602D02*
X2569477Y1314802D01*
X2573352Y1302302D01*
G01X2571957Y1306677D02*
X2566997D01*
G01X2581877Y1314802D02*
Y1302302D01*
G01X2578312Y1314802D02*
X2585442D01*
G01X2597377Y1302302D02*
X2591177D01*
Y1314802D01*
X2597377D01*
G01X2594897Y1308760D02*
X2591177D01*
G01X2603267Y1302302D02*
Y1314802D01*
X2606367D01*
X2607607Y1314177D01*
X2608537Y1313344D01*
X2609312Y1312094D01*
X2609932Y1310635D01*
X2610087Y1308552D01*
X2609932Y1306469D01*
X2609312Y1305010D01*
X2608537Y1303760D01*
X2607607Y1302927D01*
X2606367Y1302302D01*
X2603267D01*
G01X2541577Y1335902D02*
Y1348402D01*
X2545297D01*
X2546537Y1347777D01*
X2547467Y1346319D01*
X2547777Y1344652D01*
X2547467Y1342985D01*
X2546692Y1341735D01*
X2545297Y1341110D01*
X2541577D01*
G01X2553977Y1348402D02*
Y1335902D01*
X2560177D01*
G01X2565602D02*
X2569477Y1348402D01*
X2573352Y1335902D01*
G01X2571957Y1340277D02*
X2566997D01*
G01X2581877Y1348402D02*
Y1335902D01*
G01X2578312Y1348402D02*
X2585442D01*
G01X2597377Y1335902D02*
X2591177D01*
Y1348402D01*
X2597377D01*
G01X2594897Y1342360D02*
X2591177D01*
G01X2603267Y1335902D02*
Y1348402D01*
X2606367D01*
X2607607Y1347777D01*
X2608537Y1346944D01*
X2609312Y1345694D01*
X2609932Y1344235D01*
X2610087Y1342152D01*
X2609932Y1340069D01*
X2609312Y1338610D01*
X2608537Y1337360D01*
X2607607Y1336527D01*
X2606367Y1335902D01*
X2603267D01*
G01X2541577Y1369502D02*
Y1382002D01*
X2545297D01*
X2546537Y1381377D01*
X2547467Y1379919D01*
X2547777Y1378252D01*
X2547467Y1376585D01*
X2546692Y1375335D01*
X2545297Y1374710D01*
X2541577D01*
G01X2553977Y1382002D02*
Y1369502D01*
X2560177D01*
G01X2565602D02*
X2569477Y1382002D01*
X2573352Y1369502D01*
G01X2571957Y1373877D02*
X2566997D01*
G01X2581877Y1382002D02*
Y1369502D01*
G01X2578312Y1382002D02*
X2585442D01*
G01X2597377Y1369502D02*
X2591177D01*
Y1382002D01*
X2597377D01*
G01X2594897Y1375960D02*
X2591177D01*
G01X2603267Y1369502D02*
Y1382002D01*
X2606367D01*
X2607607Y1381377D01*
X2608537Y1380544D01*
X2609312Y1379294D01*
X2609932Y1377835D01*
X2610087Y1375752D01*
X2609932Y1373669D01*
X2609312Y1372210D01*
X2608537Y1370960D01*
X2607607Y1370127D01*
X2606367Y1369502D01*
X2603267D01*
G01X2541577Y1403102D02*
Y1415602D01*
X2545297D01*
X2546537Y1414977D01*
X2547467Y1413519D01*
X2547777Y1411852D01*
X2547467Y1410185D01*
X2546692Y1408935D01*
X2545297Y1408310D01*
X2541577D01*
G01X2553977Y1415602D02*
Y1403102D01*
X2560177D01*
G01X2565602D02*
X2569477Y1415602D01*
X2573352Y1403102D01*
G01X2571957Y1407477D02*
X2566997D01*
G01X2581877Y1415602D02*
Y1403102D01*
G01X2578312Y1415602D02*
X2585442D01*
G01X2597377Y1403102D02*
X2591177D01*
Y1415602D01*
X2597377D01*
G01X2594897Y1409560D02*
X2591177D01*
G01X2603267Y1403102D02*
Y1415602D01*
X2606367D01*
X2607607Y1414977D01*
X2608537Y1414144D01*
X2609312Y1412894D01*
X2609932Y1411435D01*
X2610087Y1409352D01*
X2609932Y1407269D01*
X2609312Y1405810D01*
X2608537Y1404560D01*
X2607607Y1403727D01*
X2606367Y1403102D01*
X2603267D01*
G01X2541577Y1436702D02*
Y1449202D01*
X2545297D01*
X2546537Y1448577D01*
X2547467Y1447119D01*
X2547777Y1445452D01*
X2547467Y1443785D01*
X2546692Y1442535D01*
X2545297Y1441910D01*
X2541577D01*
G01X2553977Y1449202D02*
Y1436702D01*
X2560177D01*
G01X2565602D02*
X2569477Y1449202D01*
X2573352Y1436702D01*
G01X2571957Y1441077D02*
X2566997D01*
G01X2581877Y1449202D02*
Y1436702D01*
G01X2578312Y1449202D02*
X2585442D01*
G01X2597377Y1436702D02*
X2591177D01*
Y1449202D01*
X2597377D01*
G01X2594897Y1443160D02*
X2591177D01*
G01X2603267Y1436702D02*
Y1449202D01*
X2606367D01*
X2607607Y1448577D01*
X2608537Y1447744D01*
X2609312Y1446494D01*
X2609932Y1445035D01*
X2610087Y1442952D01*
X2609932Y1440869D01*
X2609312Y1439410D01*
X2608537Y1438160D01*
X2607607Y1437327D01*
X2606367Y1436702D01*
X2603267D01*
G01X2541577Y1470302D02*
Y1482802D01*
X2545297D01*
X2546537Y1482177D01*
X2547467Y1480719D01*
X2547777Y1479052D01*
X2547467Y1477385D01*
X2546692Y1476135D01*
X2545297Y1475510D01*
X2541577D01*
G01X2553977Y1482802D02*
Y1470302D01*
X2560177D01*
G01X2565602D02*
X2569477Y1482802D01*
X2573352Y1470302D01*
G01X2571957Y1474677D02*
X2566997D01*
G01X2581877Y1482802D02*
Y1470302D01*
G01X2578312Y1482802D02*
X2585442D01*
G01X2597377Y1470302D02*
X2591177D01*
Y1482802D01*
X2597377D01*
G01X2594897Y1476760D02*
X2591177D01*
G01X2603267Y1470302D02*
Y1482802D01*
X2606367D01*
X2607607Y1482177D01*
X2608537Y1481344D01*
X2609312Y1480094D01*
X2609932Y1478635D01*
X2610087Y1476552D01*
X2609932Y1474469D01*
X2609312Y1473010D01*
X2608537Y1471760D01*
X2607607Y1470927D01*
X2606367Y1470302D01*
X2603267D01*
G01X2541577Y1503902D02*
Y1516402D01*
X2545297D01*
X2546537Y1515777D01*
X2547467Y1514319D01*
X2547777Y1512652D01*
X2547467Y1510985D01*
X2546692Y1509735D01*
X2545297Y1509110D01*
X2541577D01*
G01X2553977Y1516402D02*
Y1503902D01*
X2560177D01*
G01X2565602D02*
X2569477Y1516402D01*
X2573352Y1503902D01*
G01X2571957Y1508277D02*
X2566997D01*
G01X2581877Y1516402D02*
Y1503902D01*
G01X2578312Y1516402D02*
X2585442D01*
G01X2597377Y1503902D02*
X2591177D01*
Y1516402D01*
X2597377D01*
G01X2594897Y1510360D02*
X2591177D01*
G01X2603267Y1503902D02*
Y1516402D01*
X2606367D01*
X2607607Y1515777D01*
X2608537Y1514944D01*
X2609312Y1513694D01*
X2609932Y1512235D01*
X2610087Y1510152D01*
X2609932Y1508069D01*
X2609312Y1506610D01*
X2608537Y1505360D01*
X2607607Y1504527D01*
X2606367Y1503902D01*
X2603267D01*
G01X2541577Y1537502D02*
Y1550002D01*
X2545297D01*
X2546537Y1549377D01*
X2547467Y1547919D01*
X2547777Y1546252D01*
X2547467Y1544585D01*
X2546692Y1543335D01*
X2545297Y1542710D01*
X2541577D01*
G01X2553977Y1550002D02*
Y1537502D01*
X2560177D01*
G01X2565602D02*
X2569477Y1550002D01*
X2573352Y1537502D01*
G01X2571957Y1541877D02*
X2566997D01*
G01X2581877Y1550002D02*
Y1537502D01*
G01X2578312Y1550002D02*
X2585442D01*
G01X2597377Y1537502D02*
X2591177D01*
Y1550002D01*
X2597377D01*
G01X2594897Y1543960D02*
X2591177D01*
G01X2603267Y1537502D02*
Y1550002D01*
X2606367D01*
X2607607Y1549377D01*
X2608537Y1548544D01*
X2609312Y1547294D01*
X2609932Y1545835D01*
X2610087Y1543752D01*
X2609932Y1541669D01*
X2609312Y1540210D01*
X2608537Y1538960D01*
X2607607Y1538127D01*
X2606367Y1537502D01*
X2603267D01*
G01X2541577Y1571102D02*
Y1583602D01*
X2545297D01*
X2546537Y1582977D01*
X2547467Y1581519D01*
X2547777Y1579852D01*
X2547467Y1578185D01*
X2546692Y1576935D01*
X2545297Y1576310D01*
X2541577D01*
G01X2553977Y1583602D02*
Y1571102D01*
X2560177D01*
G01X2565602D02*
X2569477Y1583602D01*
X2573352Y1571102D01*
G01X2571957Y1575477D02*
X2566997D01*
G01X2581877Y1583602D02*
Y1571102D01*
G01X2578312Y1583602D02*
X2585442D01*
G01X2597377Y1571102D02*
X2591177D01*
Y1583602D01*
X2597377D01*
G01X2594897Y1577560D02*
X2591177D01*
G01X2603267Y1571102D02*
Y1583602D01*
X2606367D01*
X2607607Y1582977D01*
X2608537Y1582144D01*
X2609312Y1580894D01*
X2609932Y1579435D01*
X2610087Y1577352D01*
X2609932Y1575269D01*
X2609312Y1573810D01*
X2608537Y1572560D01*
X2607607Y1571727D01*
X2606367Y1571102D01*
X2603267D01*
G01X2541577Y1604702D02*
Y1617202D01*
X2545297D01*
X2546537Y1616577D01*
X2547467Y1615119D01*
X2547777Y1613452D01*
X2547467Y1611785D01*
X2546692Y1610535D01*
X2545297Y1609910D01*
X2541577D01*
G01X2553977Y1617202D02*
Y1604702D01*
X2560177D01*
G01X2565602D02*
X2569477Y1617202D01*
X2573352Y1604702D01*
G01X2571957Y1609077D02*
X2566997D01*
G01X2581877Y1617202D02*
Y1604702D01*
G01X2578312Y1617202D02*
X2585442D01*
G01X2597377Y1604702D02*
X2591177D01*
Y1617202D01*
X2597377D01*
G01X2594897Y1611160D02*
X2591177D01*
G01X2603267Y1604702D02*
Y1617202D01*
X2606367D01*
X2607607Y1616577D01*
X2608537Y1615744D01*
X2609312Y1614494D01*
X2609932Y1613035D01*
X2610087Y1610952D01*
X2609932Y1608869D01*
X2609312Y1607410D01*
X2608537Y1606160D01*
X2607607Y1605327D01*
X2606367Y1604702D01*
X2603267D01*
G01X2541577Y1638302D02*
Y1650802D01*
X2545297D01*
X2546537Y1650177D01*
X2547467Y1648719D01*
X2547777Y1647052D01*
X2547467Y1645385D01*
X2546692Y1644135D01*
X2545297Y1643510D01*
X2541577D01*
G01X2553977Y1650802D02*
Y1638302D01*
X2560177D01*
G01X2565602D02*
X2569477Y1650802D01*
X2573352Y1638302D01*
G01X2571957Y1642677D02*
X2566997D01*
G01X2581877Y1650802D02*
Y1638302D01*
G01X2578312Y1650802D02*
X2585442D01*
G01X2597377Y1638302D02*
X2591177D01*
Y1650802D01*
X2597377D01*
G01X2594897Y1644760D02*
X2591177D01*
G01X2603267Y1638302D02*
Y1650802D01*
X2606367D01*
X2607607Y1650177D01*
X2608537Y1649344D01*
X2609312Y1648094D01*
X2609932Y1646635D01*
X2610087Y1644552D01*
X2609932Y1642469D01*
X2609312Y1641010D01*
X2608537Y1639760D01*
X2607607Y1638927D01*
X2606367Y1638302D01*
X2603267D01*
G01X2541577Y1671902D02*
Y1684402D01*
X2545297D01*
X2546537Y1683777D01*
X2547467Y1682319D01*
X2547777Y1680652D01*
X2547467Y1678985D01*
X2546692Y1677735D01*
X2545297Y1677110D01*
X2541577D01*
G01X2553977Y1684402D02*
Y1671902D01*
X2560177D01*
G01X2565602D02*
X2569477Y1684402D01*
X2573352Y1671902D01*
G01X2571957Y1676277D02*
X2566997D01*
G01X2581877Y1684402D02*
Y1671902D01*
G01X2578312Y1684402D02*
X2585442D01*
G01X2597377Y1671902D02*
X2591177D01*
Y1684402D01*
X2597377D01*
G01X2594897Y1678360D02*
X2591177D01*
G01X2603267Y1671902D02*
Y1684402D01*
X2606367D01*
X2607607Y1683777D01*
X2608537Y1682944D01*
X2609312Y1681694D01*
X2609932Y1680235D01*
X2610087Y1678152D01*
X2609932Y1676069D01*
X2609312Y1674610D01*
X2608537Y1673360D01*
X2607607Y1672527D01*
X2606367Y1671902D01*
X2603267D01*
G01X2541577Y1705502D02*
Y1718002D01*
X2545297D01*
X2546537Y1717377D01*
X2547467Y1715919D01*
X2547777Y1714252D01*
X2547467Y1712585D01*
X2546692Y1711335D01*
X2545297Y1710710D01*
X2541577D01*
G01X2553977Y1718002D02*
Y1705502D01*
X2560177D01*
G01X2565602D02*
X2569477Y1718002D01*
X2573352Y1705502D01*
G01X2571957Y1709877D02*
X2566997D01*
G01X2581877Y1718002D02*
Y1705502D01*
G01X2578312Y1718002D02*
X2585442D01*
G01X2597377Y1705502D02*
X2591177D01*
Y1718002D01*
X2597377D01*
G01X2594897Y1711960D02*
X2591177D01*
G01X2603267Y1705502D02*
Y1718002D01*
X2606367D01*
X2607607Y1717377D01*
X2608537Y1716544D01*
X2609312Y1715294D01*
X2609932Y1713835D01*
X2610087Y1711752D01*
X2609932Y1709669D01*
X2609312Y1708210D01*
X2608537Y1706960D01*
X2607607Y1706127D01*
X2606367Y1705502D01*
X2603267D01*
G01X2541577Y1739102D02*
Y1751602D01*
X2545297D01*
X2546537Y1750977D01*
X2547467Y1749519D01*
X2547777Y1747852D01*
X2547467Y1746185D01*
X2546692Y1744935D01*
X2545297Y1744310D01*
X2541577D01*
G01X2553977Y1751602D02*
Y1739102D01*
X2560177D01*
G01X2565602D02*
X2569477Y1751602D01*
X2573352Y1739102D01*
G01X2571957Y1743477D02*
X2566997D01*
G01X2581877Y1751602D02*
Y1739102D01*
G01X2578312Y1751602D02*
X2585442D01*
G01X2597377Y1739102D02*
X2591177D01*
Y1751602D01*
X2597377D01*
G01X2594897Y1745560D02*
X2591177D01*
G01X2603267Y1739102D02*
Y1751602D01*
X2606367D01*
X2607607Y1750977D01*
X2608537Y1750144D01*
X2609312Y1748894D01*
X2609932Y1747435D01*
X2610087Y1745352D01*
X2609932Y1743269D01*
X2609312Y1741810D01*
X2608537Y1740560D01*
X2607607Y1739727D01*
X2606367Y1739102D01*
X2603267D01*
G01X2541577Y1772702D02*
Y1785202D01*
X2545297D01*
X2546537Y1784577D01*
X2547467Y1783119D01*
X2547777Y1781452D01*
X2547467Y1779785D01*
X2546692Y1778535D01*
X2545297Y1777910D01*
X2541577D01*
G01X2553977Y1785202D02*
Y1772702D01*
X2560177D01*
G01X2565602D02*
X2569477Y1785202D01*
X2573352Y1772702D01*
G01X2571957Y1777077D02*
X2566997D01*
G01X2581877Y1785202D02*
Y1772702D01*
G01X2578312Y1785202D02*
X2585442D01*
G01X2597377Y1772702D02*
X2591177D01*
Y1785202D01*
X2597377D01*
G01X2594897Y1779160D02*
X2591177D01*
G01X2603267Y1772702D02*
Y1785202D01*
X2606367D01*
X2607607Y1784577D01*
X2608537Y1783744D01*
X2609312Y1782494D01*
X2609932Y1781035D01*
X2610087Y1778952D01*
X2609932Y1776869D01*
X2609312Y1775410D01*
X2608537Y1774160D01*
X2607607Y1773327D01*
X2606367Y1772702D01*
X2603267D01*
G01X2541577Y1806302D02*
Y1818802D01*
X2545297D01*
X2546537Y1818177D01*
X2547467Y1816719D01*
X2547777Y1815052D01*
X2547467Y1813385D01*
X2546692Y1812135D01*
X2545297Y1811510D01*
X2541577D01*
G01X2553977Y1818802D02*
Y1806302D01*
X2560177D01*
G01X2565602D02*
X2569477Y1818802D01*
X2573352Y1806302D01*
G01X2571957Y1810677D02*
X2566997D01*
G01X2581877Y1818802D02*
Y1806302D01*
G01X2578312Y1818802D02*
X2585442D01*
G01X2597377Y1806302D02*
X2591177D01*
Y1818802D01*
X2597377D01*
G01X2594897Y1812760D02*
X2591177D01*
G01X2603267Y1806302D02*
Y1818802D01*
X2606367D01*
X2607607Y1818177D01*
X2608537Y1817344D01*
X2609312Y1816094D01*
X2609932Y1814635D01*
X2610087Y1812552D01*
X2609932Y1810469D01*
X2609312Y1809010D01*
X2608537Y1807760D01*
X2607607Y1806927D01*
X2606367Y1806302D01*
X2603267D01*
G01X2541577Y1839902D02*
Y1852402D01*
X2545297D01*
X2546537Y1851777D01*
X2547467Y1850319D01*
X2547777Y1848652D01*
X2547467Y1846985D01*
X2546692Y1845735D01*
X2545297Y1845110D01*
X2541577D01*
G01X2553977Y1852402D02*
Y1839902D01*
X2560177D01*
G01X2565602D02*
X2569477Y1852402D01*
X2573352Y1839902D01*
G01X2571957Y1844277D02*
X2566997D01*
G01X2581877Y1852402D02*
Y1839902D01*
G01X2578312Y1852402D02*
X2585442D01*
G01X2597377Y1839902D02*
X2591177D01*
Y1852402D01*
X2597377D01*
G01X2594897Y1846360D02*
X2591177D01*
G01X2603267Y1839902D02*
Y1852402D01*
X2606367D01*
X2607607Y1851777D01*
X2608537Y1850944D01*
X2609312Y1849694D01*
X2609932Y1848235D01*
X2610087Y1846152D01*
X2609932Y1844069D01*
X2609312Y1842610D01*
X2608537Y1841360D01*
X2607607Y1840527D01*
X2606367Y1839902D01*
X2603267D01*
G01X2541577Y1869202D02*
Y1881702D01*
X2545297D01*
X2546537Y1881077D01*
X2547467Y1879619D01*
X2547777Y1877952D01*
X2547467Y1876285D01*
X2546692Y1875035D01*
X2545297Y1874410D01*
X2541577D01*
G01X2553977Y1881702D02*
Y1869202D01*
X2560177D01*
G01X2565602D02*
X2569477Y1881702D01*
X2573352Y1869202D01*
G01X2571957Y1873577D02*
X2566997D01*
G01X2581877Y1881702D02*
Y1869202D01*
G01X2578312Y1881702D02*
X2585442D01*
G01X2597377Y1869202D02*
X2591177D01*
Y1881702D01*
X2597377D01*
G01X2594897Y1875660D02*
X2591177D01*
G01X2603267Y1869202D02*
Y1881702D01*
X2606367D01*
X2607607Y1881077D01*
X2608537Y1880244D01*
X2609312Y1878994D01*
X2609932Y1877535D01*
X2610087Y1875452D01*
X2609932Y1873369D01*
X2609312Y1871910D01*
X2608537Y1870660D01*
X2607607Y1869827D01*
X2606367Y1869202D01*
X2603267D01*
G01X2679837Y-276898D02*
Y-264398D01*
X2674102Y-273356D01*
X2681852D01*
G01X2639227Y1887952D02*
Y-287448D01*
G01X2675032Y-232881D02*
X2675962Y-231632D01*
X2677047Y-231006D01*
X2678287Y-230798D01*
X2679837Y-231215D01*
X2680922Y-232256D01*
X2681232Y-233506D01*
X2681077Y-234757D01*
X2680457Y-235798D01*
X2677357Y-237881D01*
X2675962Y-239340D01*
X2675032Y-241423D01*
X2674722Y-243298D01*
X2681232D01*
G01X2668832Y-199281D02*
X2669762Y-198032D01*
X2670847Y-197406D01*
X2672087Y-197198D01*
X2673637Y-197615D01*
X2674722Y-198656D01*
X2675032Y-199906D01*
X2674877Y-201157D01*
X2674257Y-202198D01*
X2671157Y-204281D01*
X2669762Y-205740D01*
X2668832Y-207823D01*
X2668522Y-209698D01*
X2675032D01*
G01X2686037D02*
Y-197198D01*
X2680302Y-206156D01*
X2688052D01*
G01X2675032Y-165681D02*
X2675962Y-164432D01*
X2677047Y-163806D01*
X2678287Y-163598D01*
X2679837Y-164015D01*
X2680922Y-165056D01*
X2681232Y-166306D01*
X2681077Y-167557D01*
X2680457Y-168598D01*
X2677357Y-170681D01*
X2675962Y-172140D01*
X2675032Y-174223D01*
X2674722Y-176098D01*
X2681232D01*
G01X2675032Y-132081D02*
X2675962Y-130832D01*
X2677047Y-130206D01*
X2678287Y-129998D01*
X2679837Y-130415D01*
X2680922Y-131456D01*
X2681232Y-132706D01*
X2681077Y-133957D01*
X2680457Y-134998D01*
X2677357Y-137081D01*
X2675962Y-138540D01*
X2675032Y-140623D01*
X2674722Y-142498D01*
X2681232D01*
G01X2675032Y-98481D02*
X2675962Y-97232D01*
X2677047Y-96606D01*
X2678287Y-96398D01*
X2679837Y-96815D01*
X2680922Y-97856D01*
X2681232Y-99106D01*
X2681077Y-100357D01*
X2680457Y-101398D01*
X2677357Y-103481D01*
X2675962Y-104940D01*
X2675032Y-107023D01*
X2674722Y-108898D01*
X2681232D01*
G01X2675032Y-64881D02*
X2675962Y-63632D01*
X2677047Y-63006D01*
X2678287Y-62798D01*
X2679837Y-63215D01*
X2680922Y-64256D01*
X2681232Y-65506D01*
X2681077Y-66757D01*
X2680457Y-67798D01*
X2677357Y-69881D01*
X2675962Y-71340D01*
X2675032Y-73423D01*
X2674722Y-75298D01*
X2681232D01*
G01X2675032Y-31281D02*
X2675962Y-30032D01*
X2677047Y-29406D01*
X2678287Y-29198D01*
X2679837Y-29615D01*
X2680922Y-30656D01*
X2681232Y-31906D01*
X2681077Y-33157D01*
X2680457Y-34198D01*
X2677357Y-36281D01*
X2675962Y-37740D01*
X2675032Y-39823D01*
X2674722Y-41698D01*
X2681232D01*
G01X2671777Y-8098D02*
Y4402D01*
X2669917Y1902D01*
G01Y-8098D02*
X2673637D01*
G01X2686037D02*
Y4402D01*
X2680302Y-4556D01*
X2688052D01*
G01X2675032Y30710D02*
X2676117Y32169D01*
X2677047Y33002D01*
X2678287Y33419D01*
X2679372Y33002D01*
X2680147Y32169D01*
X2680767Y30919D01*
X2680922Y29460D01*
X2680767Y28210D01*
X2680147Y26960D01*
X2679217Y25919D01*
X2678132Y25502D01*
X2676892Y25919D01*
X2675807Y27168D01*
X2675187Y29044D01*
X2675032Y31127D01*
X2675342Y33835D01*
X2675807Y35294D01*
X2676582Y36752D01*
X2677667Y37794D01*
X2678752Y38002D01*
X2679837Y37585D01*
X2680612Y36544D01*
G01X2674567Y60977D02*
X2675497Y59935D01*
X2676582Y59310D01*
X2677977Y59102D01*
X2679372Y59519D01*
X2680457Y60352D01*
X2681232Y61810D01*
X2681387Y63477D01*
X2681077Y65144D01*
X2680302Y66185D01*
X2679217Y67019D01*
X2678132Y67227D01*
X2677047Y67019D01*
X2675652Y66185D01*
X2676117Y71602D01*
X2680302D01*
G01X2674567Y94577D02*
X2675497Y93535D01*
X2676582Y92910D01*
X2677977Y92702D01*
X2679372Y93119D01*
X2680457Y93952D01*
X2681232Y95410D01*
X2681387Y97077D01*
X2681077Y98744D01*
X2680302Y99785D01*
X2679217Y100619D01*
X2678132Y100827D01*
X2677047Y100619D01*
X2675652Y99785D01*
X2676117Y105202D01*
X2680302D01*
G01X2675032Y136719D02*
X2675962Y137968D01*
X2677047Y138594D01*
X2678287Y138802D01*
X2679837Y138385D01*
X2680922Y137344D01*
X2681232Y136094D01*
X2681077Y134843D01*
X2680457Y133802D01*
X2677357Y131719D01*
X2675962Y130260D01*
X2675032Y128177D01*
X2674722Y126302D01*
X2681232D01*
G01X2679837Y159902D02*
Y172402D01*
X2674102Y163444D01*
X2681852D01*
G01X2677977Y193502D02*
Y206002D01*
X2676117Y203502D01*
G01Y193502D02*
X2679837D01*
G01X2677977Y227102D02*
Y239602D01*
X2676117Y237102D01*
G01Y227102D02*
X2679837D01*
G01X2677977Y260702D02*
Y273202D01*
X2676117Y270702D01*
G01Y260702D02*
X2679837D01*
G01X2671777Y294302D02*
Y306802D01*
X2669917Y304302D01*
G01Y294302D02*
X2673637D01*
G01X2684177Y306802D02*
X2682937Y306385D01*
X2682007Y305344D01*
X2681387Y304094D01*
X2680922Y302427D01*
X2680767Y300552D01*
X2680922Y298677D01*
X2681387Y297010D01*
X2682007Y295760D01*
X2682937Y294719D01*
X2684177Y294302D01*
X2685417Y294719D01*
X2686347Y295760D01*
X2686967Y297010D01*
X2687432Y298677D01*
X2687587Y300552D01*
X2687432Y302427D01*
X2686967Y304094D01*
X2686347Y305344D01*
X2685417Y306385D01*
X2684177Y306802D01*
G01X2675032Y338319D02*
X2675962Y339568D01*
X2677047Y340194D01*
X2678287Y340402D01*
X2679837Y339985D01*
X2680922Y338944D01*
X2681232Y337694D01*
X2681077Y336443D01*
X2680457Y335402D01*
X2677357Y333319D01*
X2675962Y331860D01*
X2675032Y329777D01*
X2674722Y327902D01*
X2681232D01*
G01X2675032Y371919D02*
X2675962Y373168D01*
X2677047Y373794D01*
X2678287Y374002D01*
X2679837Y373585D01*
X2680922Y372544D01*
X2681232Y371294D01*
X2681077Y370043D01*
X2680457Y369002D01*
X2677357Y366919D01*
X2675962Y365460D01*
X2675032Y363377D01*
X2674722Y361502D01*
X2681232D01*
G01X2675032Y405519D02*
X2675962Y406768D01*
X2677047Y407394D01*
X2678287Y407602D01*
X2679837Y407185D01*
X2680922Y406144D01*
X2681232Y404894D01*
X2681077Y403643D01*
X2680457Y402602D01*
X2677357Y400519D01*
X2675962Y399060D01*
X2675032Y396977D01*
X2674722Y395102D01*
X2681232D01*
G01X2677977Y428702D02*
Y441202D01*
X2676117Y438702D01*
G01Y428702D02*
X2679837D01*
G01X2675032Y472719D02*
X2675962Y473968D01*
X2677047Y474594D01*
X2678287Y474802D01*
X2679837Y474385D01*
X2680922Y473344D01*
X2681232Y472094D01*
X2681077Y470843D01*
X2680457Y469802D01*
X2677357Y467719D01*
X2675962Y466260D01*
X2675032Y464177D01*
X2674722Y462302D01*
X2681232D01*
G01X2674567Y498402D02*
X2675497Y496943D01*
X2676737Y496110D01*
X2678132Y495902D01*
X2679372Y496110D01*
X2680612Y497152D01*
X2681387Y498402D01*
X2681542Y499652D01*
X2681232Y501110D01*
X2680147Y502152D01*
X2679062Y502569D01*
X2677667D01*
G01X2679062D02*
X2679992Y503194D01*
X2680767Y504235D01*
X2681077Y505485D01*
X2680767Y506735D01*
X2679992Y507777D01*
X2678597Y508402D01*
X2677202Y508194D01*
X2675807Y507360D01*
G01X2675032Y539919D02*
X2675962Y541168D01*
X2677047Y541794D01*
X2678287Y542002D01*
X2679837Y541585D01*
X2680922Y540544D01*
X2681232Y539294D01*
X2681077Y538043D01*
X2680457Y537002D01*
X2677357Y534919D01*
X2675962Y533460D01*
X2675032Y531377D01*
X2674722Y529502D01*
X2681232D01*
G01X2675032Y573519D02*
X2675962Y574768D01*
X2677047Y575394D01*
X2678287Y575602D01*
X2679837Y575185D01*
X2680922Y574144D01*
X2681232Y572894D01*
X2681077Y571643D01*
X2680457Y570602D01*
X2677357Y568519D01*
X2675962Y567060D01*
X2675032Y564977D01*
X2674722Y563102D01*
X2681232D01*
G01X2675032Y607119D02*
X2675962Y608368D01*
X2677047Y608994D01*
X2678287Y609202D01*
X2679837Y608785D01*
X2680922Y607744D01*
X2681232Y606494D01*
X2681077Y605243D01*
X2680457Y604202D01*
X2677357Y602119D01*
X2675962Y600660D01*
X2675032Y598577D01*
X2674722Y596702D01*
X2681232D01*
G01X2675032Y640719D02*
X2675962Y641968D01*
X2677047Y642594D01*
X2678287Y642802D01*
X2679837Y642385D01*
X2680922Y641344D01*
X2681232Y640094D01*
X2681077Y638843D01*
X2680457Y637802D01*
X2677357Y635719D01*
X2675962Y634260D01*
X2675032Y632177D01*
X2674722Y630302D01*
X2681232D01*
G01X2677977Y663902D02*
Y676402D01*
X2676117Y673902D01*
G01Y663902D02*
X2679837D01*
G01X2677977Y697502D02*
Y710002D01*
X2676117Y707502D01*
G01Y697502D02*
X2679837D01*
G01X2675032Y741519D02*
X2675962Y742768D01*
X2677047Y743394D01*
X2678287Y743602D01*
X2679837Y743185D01*
X2680922Y742144D01*
X2681232Y740894D01*
X2681077Y739643D01*
X2680457Y738602D01*
X2677357Y736519D01*
X2675962Y735060D01*
X2675032Y732977D01*
X2674722Y731102D01*
X2681232D01*
G01X2677977Y764702D02*
Y777202D01*
X2676117Y774702D01*
G01Y764702D02*
X2679837D01*
G01X2677977Y798302D02*
Y810802D01*
X2676117Y808302D01*
G01Y798302D02*
X2679837D01*
G01X2674567Y834402D02*
X2675497Y832943D01*
X2676737Y832110D01*
X2678132Y831902D01*
X2679372Y832110D01*
X2680612Y833152D01*
X2681387Y834402D01*
X2681542Y835652D01*
X2681232Y837110D01*
X2680147Y838152D01*
X2679062Y838569D01*
X2677667D01*
G01X2679062D02*
X2679992Y839194D01*
X2680767Y840235D01*
X2681077Y841485D01*
X2680767Y842735D01*
X2679992Y843777D01*
X2678597Y844402D01*
X2677202Y844194D01*
X2675807Y843360D01*
G01X2673637Y865502D02*
Y878002D01*
X2667902Y869044D01*
X2675652D01*
G01X2684177Y865502D02*
X2685262Y865710D01*
X2686502Y866335D01*
X2687277Y867377D01*
X2687587Y868835D01*
X2687277Y870293D01*
X2686347Y871544D01*
X2684952Y872169D01*
X2683402D01*
X2682472Y872585D01*
X2681697Y873627D01*
X2681387Y875085D01*
X2681852Y876544D01*
X2682937Y877585D01*
X2684177Y878002D01*
X2685417Y877585D01*
X2686502Y876544D01*
X2686967Y875085D01*
X2686657Y873627D01*
X2685882Y872585D01*
X2684952Y872169D01*
X2683402D01*
X2682007Y871544D01*
X2681077Y870293D01*
X2680767Y868835D01*
X2681077Y867377D01*
X2681852Y866335D01*
X2683092Y865710D01*
X2684177Y865502D01*
G01X2673637Y899102D02*
Y911602D01*
X2667902Y902644D01*
X2675652D01*
G01X2686037Y899102D02*
Y911602D01*
X2680302Y902644D01*
X2688052D01*
G01X2677977Y932702D02*
X2679062Y932910D01*
X2680302Y933535D01*
X2681077Y934577D01*
X2681387Y936035D01*
X2681077Y937493D01*
X2680147Y938744D01*
X2678752Y939369D01*
X2677202D01*
X2676272Y939785D01*
X2675497Y940827D01*
X2675187Y942285D01*
X2675652Y943744D01*
X2676737Y944785D01*
X2677977Y945202D01*
X2679217Y944785D01*
X2680302Y943744D01*
X2680767Y942285D01*
X2680457Y940827D01*
X2679682Y939785D01*
X2678752Y939369D01*
X2677202D01*
X2675807Y938744D01*
X2674877Y937493D01*
X2674567Y936035D01*
X2674877Y934577D01*
X2675652Y933535D01*
X2676892Y932910D01*
X2677977Y932702D01*
G01X2671777Y966302D02*
Y978802D01*
X2669917Y976302D01*
G01Y966302D02*
X2673637D01*
G01X2681232Y976719D02*
X2682162Y977968D01*
X2683247Y978594D01*
X2684487Y978802D01*
X2686037Y978385D01*
X2687122Y977344D01*
X2687432Y976094D01*
X2687277Y974843D01*
X2686657Y973802D01*
X2683557Y971719D01*
X2682162Y970260D01*
X2681232Y968177D01*
X2680922Y966302D01*
X2687432D01*
G01X2675032Y1010319D02*
X2675962Y1011568D01*
X2677047Y1012194D01*
X2678287Y1012402D01*
X2679837Y1011985D01*
X2680922Y1010944D01*
X2681232Y1009694D01*
X2681077Y1008443D01*
X2680457Y1007402D01*
X2677357Y1005319D01*
X2675962Y1003860D01*
X2675032Y1001777D01*
X2674722Y999902D01*
X2681232D01*
G01X2669142Y1034960D02*
X2670227Y1033919D01*
X2671467Y1033502D01*
X2672707Y1033919D01*
X2673792Y1035168D01*
X2674567Y1037044D01*
X2674877Y1038919D01*
Y1041210D01*
X2674567Y1043085D01*
X2673792Y1044752D01*
X2672862Y1045585D01*
X2671777Y1046002D01*
X2670537Y1045585D01*
X2669607Y1044752D01*
X2668987Y1043502D01*
X2668677Y1041835D01*
X2668987Y1040377D01*
X2669762Y1038919D01*
X2670692Y1038085D01*
X2671777Y1037877D01*
X2673017Y1038293D01*
X2673947Y1039335D01*
X2674877Y1041210D01*
G01X2681232Y1038710D02*
X2682317Y1040169D01*
X2683247Y1041002D01*
X2684487Y1041419D01*
X2685572Y1041002D01*
X2686347Y1040169D01*
X2686967Y1038919D01*
X2687122Y1037460D01*
X2686967Y1036210D01*
X2686347Y1034960D01*
X2685417Y1033919D01*
X2684332Y1033502D01*
X2683092Y1033919D01*
X2682007Y1035168D01*
X2681387Y1037044D01*
X2681232Y1039127D01*
X2681542Y1041835D01*
X2682007Y1043294D01*
X2682782Y1044752D01*
X2683867Y1045794D01*
X2684952Y1046002D01*
X2686037Y1045585D01*
X2686812Y1044544D01*
G01X2671777Y1067102D02*
Y1079602D01*
X2669917Y1077102D01*
G01Y1067102D02*
X2673637D01*
G01X2686037D02*
Y1079602D01*
X2680302Y1070644D01*
X2688052D01*
G01X2674567Y1103202D02*
X2675497Y1101743D01*
X2676737Y1100910D01*
X2678132Y1100702D01*
X2679372Y1100910D01*
X2680612Y1101952D01*
X2681387Y1103202D01*
X2681542Y1104452D01*
X2681232Y1105910D01*
X2680147Y1106952D01*
X2679062Y1107369D01*
X2677667D01*
G01X2679062D02*
X2679992Y1107994D01*
X2680767Y1109035D01*
X2681077Y1110285D01*
X2680767Y1111535D01*
X2679992Y1112577D01*
X2678597Y1113202D01*
X2677202Y1112994D01*
X2675807Y1112160D01*
G01X2674567Y1136802D02*
X2675497Y1135343D01*
X2676737Y1134510D01*
X2678132Y1134302D01*
X2679372Y1134510D01*
X2680612Y1135552D01*
X2681387Y1136802D01*
X2681542Y1138052D01*
X2681232Y1139510D01*
X2680147Y1140552D01*
X2679062Y1140969D01*
X2677667D01*
G01X2679062D02*
X2679992Y1141594D01*
X2680767Y1142635D01*
X2681077Y1143885D01*
X2680767Y1145135D01*
X2679992Y1146177D01*
X2678597Y1146802D01*
X2677202Y1146594D01*
X2675807Y1145760D01*
G01X2665577Y1167902D02*
Y1180402D01*
X2663717Y1177902D01*
G01Y1167902D02*
X2667437D01*
G01X2677977D02*
Y1180402D01*
X2676117Y1177902D01*
G01Y1167902D02*
X2679837D01*
G01X2690377D02*
Y1180402D01*
X2688517Y1177902D01*
G01Y1167902D02*
X2692237D01*
G01X2675032Y1211919D02*
X2675962Y1213168D01*
X2677047Y1213794D01*
X2678287Y1214002D01*
X2679837Y1213585D01*
X2680922Y1212544D01*
X2681232Y1211294D01*
X2681077Y1210043D01*
X2680457Y1209002D01*
X2677357Y1206919D01*
X2675962Y1205460D01*
X2675032Y1203377D01*
X2674722Y1201502D01*
X2681232D01*
G01X2679837Y1235102D02*
Y1247602D01*
X2674102Y1238644D01*
X2681852D01*
G01X2675032Y1273910D02*
X2676117Y1275369D01*
X2677047Y1276202D01*
X2678287Y1276619D01*
X2679372Y1276202D01*
X2680147Y1275369D01*
X2680767Y1274119D01*
X2680922Y1272660D01*
X2680767Y1271410D01*
X2680147Y1270160D01*
X2679217Y1269119D01*
X2678132Y1268702D01*
X2676892Y1269119D01*
X2675807Y1270368D01*
X2675187Y1272244D01*
X2675032Y1274327D01*
X2675342Y1277035D01*
X2675807Y1278494D01*
X2676582Y1279952D01*
X2677667Y1280994D01*
X2678752Y1281202D01*
X2679837Y1280785D01*
X2680612Y1279744D01*
G01X2675342Y1303760D02*
X2676427Y1302719D01*
X2677667Y1302302D01*
X2678907Y1302719D01*
X2679992Y1303968D01*
X2680767Y1305844D01*
X2681077Y1307719D01*
Y1310010D01*
X2680767Y1311885D01*
X2679992Y1313552D01*
X2679062Y1314385D01*
X2677977Y1314802D01*
X2676737Y1314385D01*
X2675807Y1313552D01*
X2675187Y1312302D01*
X2674877Y1310635D01*
X2675187Y1309177D01*
X2675962Y1307719D01*
X2676892Y1306885D01*
X2677977Y1306677D01*
X2679217Y1307093D01*
X2680147Y1308135D01*
X2681077Y1310010D01*
G01X2675032Y1341110D02*
X2676117Y1342569D01*
X2677047Y1343402D01*
X2678287Y1343819D01*
X2679372Y1343402D01*
X2680147Y1342569D01*
X2680767Y1341319D01*
X2680922Y1339860D01*
X2680767Y1338610D01*
X2680147Y1337360D01*
X2679217Y1336319D01*
X2678132Y1335902D01*
X2676892Y1336319D01*
X2675807Y1337568D01*
X2675187Y1339444D01*
X2675032Y1341527D01*
X2675342Y1344235D01*
X2675807Y1345694D01*
X2676582Y1347152D01*
X2677667Y1348194D01*
X2678752Y1348402D01*
X2679837Y1347985D01*
X2680612Y1346944D01*
G01X2668832Y1379919D02*
X2669762Y1381168D01*
X2670847Y1381794D01*
X2672087Y1382002D01*
X2673637Y1381585D01*
X2674722Y1380544D01*
X2675032Y1379294D01*
X2674877Y1378043D01*
X2674257Y1377002D01*
X2671157Y1374919D01*
X2669762Y1373460D01*
X2668832Y1371377D01*
X2668522Y1369502D01*
X2675032D01*
G01X2686037D02*
Y1382002D01*
X2680302Y1373044D01*
X2688052D01*
G01X2671777Y1403102D02*
Y1415602D01*
X2669917Y1413102D01*
G01Y1403102D02*
X2673637D01*
G01X2686037D02*
Y1415602D01*
X2680302Y1406644D01*
X2688052D01*
G01X2677977Y1436702D02*
X2679062Y1436910D01*
X2680302Y1437535D01*
X2681077Y1438577D01*
X2681387Y1440035D01*
X2681077Y1441493D01*
X2680147Y1442744D01*
X2678752Y1443369D01*
X2677202D01*
X2676272Y1443785D01*
X2675497Y1444827D01*
X2675187Y1446285D01*
X2675652Y1447744D01*
X2676737Y1448785D01*
X2677977Y1449202D01*
X2679217Y1448785D01*
X2680302Y1447744D01*
X2680767Y1446285D01*
X2680457Y1444827D01*
X2679682Y1443785D01*
X2678752Y1443369D01*
X2677202D01*
X2675807Y1442744D01*
X2674877Y1441493D01*
X2674567Y1440035D01*
X2674877Y1438577D01*
X2675652Y1437535D01*
X2676892Y1436910D01*
X2677977Y1436702D01*
G01X2671777Y1470302D02*
Y1482802D01*
X2669917Y1480302D01*
G01Y1470302D02*
X2673637D01*
G01X2681232Y1480719D02*
X2682162Y1481968D01*
X2683247Y1482594D01*
X2684487Y1482802D01*
X2686037Y1482385D01*
X2687122Y1481344D01*
X2687432Y1480094D01*
X2687277Y1478843D01*
X2686657Y1477802D01*
X2683557Y1475719D01*
X2682162Y1474260D01*
X2681232Y1472177D01*
X2680922Y1470302D01*
X2687432D01*
G01X2668367Y1505777D02*
X2669297Y1504735D01*
X2670382Y1504110D01*
X2671777Y1503902D01*
X2673172Y1504319D01*
X2674257Y1505152D01*
X2675032Y1506610D01*
X2675187Y1508277D01*
X2674877Y1509944D01*
X2674102Y1510985D01*
X2673017Y1511819D01*
X2671932Y1512027D01*
X2670847Y1511819D01*
X2669452Y1510985D01*
X2669917Y1516402D01*
X2674102D01*
G01X2681232Y1509110D02*
X2682317Y1510569D01*
X2683247Y1511402D01*
X2684487Y1511819D01*
X2685572Y1511402D01*
X2686347Y1510569D01*
X2686967Y1509319D01*
X2687122Y1507860D01*
X2686967Y1506610D01*
X2686347Y1505360D01*
X2685417Y1504319D01*
X2684332Y1503902D01*
X2683092Y1504319D01*
X2682007Y1505568D01*
X2681387Y1507444D01*
X2681232Y1509527D01*
X2681542Y1512235D01*
X2682007Y1513694D01*
X2682782Y1515152D01*
X2683867Y1516194D01*
X2684952Y1516402D01*
X2686037Y1515985D01*
X2686812Y1514944D01*
G01X2675032Y1547919D02*
X2675962Y1549168D01*
X2677047Y1549794D01*
X2678287Y1550002D01*
X2679837Y1549585D01*
X2680922Y1548544D01*
X2681232Y1547294D01*
X2681077Y1546043D01*
X2680457Y1545002D01*
X2677357Y1542919D01*
X2675962Y1541460D01*
X2675032Y1539377D01*
X2674722Y1537502D01*
X2681232D01*
G01X2665577Y1571102D02*
Y1583602D01*
X2663717Y1581102D01*
G01Y1571102D02*
X2667437D01*
G01X2674567Y1573602D02*
X2675497Y1572143D01*
X2676737Y1571310D01*
X2678132Y1571102D01*
X2679372Y1571310D01*
X2680612Y1572352D01*
X2681387Y1573602D01*
X2681542Y1574852D01*
X2681232Y1576310D01*
X2680147Y1577352D01*
X2679062Y1577769D01*
X2677667D01*
G01X2679062D02*
X2679992Y1578394D01*
X2680767Y1579435D01*
X2681077Y1580685D01*
X2680767Y1581935D01*
X2679992Y1582977D01*
X2678597Y1583602D01*
X2677202Y1583394D01*
X2675807Y1582560D01*
G01X2686967Y1572977D02*
X2687897Y1571935D01*
X2688982Y1571310D01*
X2690377Y1571102D01*
X2691772Y1571519D01*
X2692857Y1572352D01*
X2693632Y1573810D01*
X2693787Y1575477D01*
X2693477Y1577144D01*
X2692702Y1578185D01*
X2691617Y1579019D01*
X2690532Y1579227D01*
X2689447Y1579019D01*
X2688052Y1578185D01*
X2688517Y1583602D01*
X2692702D01*
G01X2669142Y1606160D02*
X2670227Y1605119D01*
X2671467Y1604702D01*
X2672707Y1605119D01*
X2673792Y1606368D01*
X2674567Y1608244D01*
X2674877Y1610119D01*
Y1612410D01*
X2674567Y1614285D01*
X2673792Y1615952D01*
X2672862Y1616785D01*
X2671777Y1617202D01*
X2670537Y1616785D01*
X2669607Y1615952D01*
X2668987Y1614702D01*
X2668677Y1613035D01*
X2668987Y1611577D01*
X2669762Y1610119D01*
X2670692Y1609285D01*
X2671777Y1609077D01*
X2673017Y1609493D01*
X2673947Y1610535D01*
X2674877Y1612410D01*
G01X2681232Y1609910D02*
X2682317Y1611369D01*
X2683247Y1612202D01*
X2684487Y1612619D01*
X2685572Y1612202D01*
X2686347Y1611369D01*
X2686967Y1610119D01*
X2687122Y1608660D01*
X2686967Y1607410D01*
X2686347Y1606160D01*
X2685417Y1605119D01*
X2684332Y1604702D01*
X2683092Y1605119D01*
X2682007Y1606368D01*
X2681387Y1608244D01*
X2681232Y1610327D01*
X2681542Y1613035D01*
X2682007Y1614494D01*
X2682782Y1615952D01*
X2683867Y1616994D01*
X2684952Y1617202D01*
X2686037Y1616785D01*
X2686812Y1615744D01*
G01X2671467Y1638302D02*
X2671777Y1641010D01*
X2672242Y1643302D01*
X2672862Y1645385D01*
X2673637Y1647677D01*
X2674877Y1650802D01*
X2668677D01*
G01X2681232Y1648719D02*
X2682162Y1649968D01*
X2683247Y1650594D01*
X2684487Y1650802D01*
X2686037Y1650385D01*
X2687122Y1649344D01*
X2687432Y1648094D01*
X2687277Y1646843D01*
X2686657Y1645802D01*
X2683557Y1643719D01*
X2682162Y1642260D01*
X2681232Y1640177D01*
X2680922Y1638302D01*
X2687432D01*
G01X2677667Y1671902D02*
X2677977Y1674610D01*
X2678442Y1676902D01*
X2679062Y1678985D01*
X2679837Y1681277D01*
X2681077Y1684402D01*
X2674877D01*
G01X2655967Y1708002D02*
X2656897Y1706543D01*
X2658137Y1705710D01*
X2659532Y1705502D01*
X2660772Y1705710D01*
X2662012Y1706752D01*
X2662787Y1708002D01*
X2662942Y1709252D01*
X2662632Y1710710D01*
X2661547Y1711752D01*
X2660462Y1712169D01*
X2659067D01*
G01X2660462D02*
X2661392Y1712794D01*
X2662167Y1713835D01*
X2662477Y1715085D01*
X2662167Y1716335D01*
X2661392Y1717377D01*
X2659997Y1718002D01*
X2658602Y1717794D01*
X2657207Y1716960D01*
G01X2669142Y1706960D02*
X2670227Y1705919D01*
X2671467Y1705502D01*
X2672707Y1705919D01*
X2673792Y1707168D01*
X2674567Y1709044D01*
X2674877Y1710919D01*
Y1713210D01*
X2674567Y1715085D01*
X2673792Y1716752D01*
X2672862Y1717585D01*
X2671777Y1718002D01*
X2670537Y1717585D01*
X2669607Y1716752D01*
X2668987Y1715502D01*
X2668677Y1713835D01*
X2668987Y1712377D01*
X2669762Y1710919D01*
X2670692Y1710085D01*
X2671777Y1709877D01*
X2673017Y1710293D01*
X2673947Y1711335D01*
X2674877Y1713210D01*
G01X2681232Y1715919D02*
X2682162Y1717168D01*
X2683247Y1717794D01*
X2684487Y1718002D01*
X2686037Y1717585D01*
X2687122Y1716544D01*
X2687432Y1715294D01*
X2687277Y1714043D01*
X2686657Y1713002D01*
X2683557Y1710919D01*
X2682162Y1709460D01*
X2681232Y1707377D01*
X2680922Y1705502D01*
X2687432D01*
G01X2696577Y1718002D02*
X2695337Y1717585D01*
X2694407Y1716544D01*
X2693787Y1715294D01*
X2693322Y1713627D01*
X2693167Y1711752D01*
X2693322Y1709877D01*
X2693787Y1708210D01*
X2694407Y1706960D01*
X2695337Y1705919D01*
X2696577Y1705502D01*
X2697817Y1705919D01*
X2698747Y1706960D01*
X2699367Y1708210D01*
X2699832Y1709877D01*
X2699987Y1711752D01*
X2699832Y1713627D01*
X2699367Y1715294D01*
X2698747Y1716544D01*
X2697817Y1717585D01*
X2696577Y1718002D01*
G01X2659377Y1739102D02*
Y1751602D01*
X2657517Y1749102D01*
G01Y1739102D02*
X2661237D01*
G01X2671777D02*
X2672862Y1739310D01*
X2674102Y1739935D01*
X2674877Y1740977D01*
X2675187Y1742435D01*
X2674877Y1743893D01*
X2673947Y1745144D01*
X2672552Y1745769D01*
X2671002D01*
X2670072Y1746185D01*
X2669297Y1747227D01*
X2668987Y1748685D01*
X2669452Y1750144D01*
X2670537Y1751185D01*
X2671777Y1751602D01*
X2673017Y1751185D01*
X2674102Y1750144D01*
X2674567Y1748685D01*
X2674257Y1747227D01*
X2673482Y1746185D01*
X2672552Y1745769D01*
X2671002D01*
X2669607Y1745144D01*
X2668677Y1743893D01*
X2668367Y1742435D01*
X2668677Y1740977D01*
X2669452Y1739935D01*
X2670692Y1739310D01*
X2671777Y1739102D01*
G01X2680767Y1741602D02*
X2681697Y1740143D01*
X2682937Y1739310D01*
X2684332Y1739102D01*
X2685572Y1739310D01*
X2686812Y1740352D01*
X2687587Y1741602D01*
X2687742Y1742852D01*
X2687432Y1744310D01*
X2686347Y1745352D01*
X2685262Y1745769D01*
X2683867D01*
G01X2685262D02*
X2686192Y1746394D01*
X2686967Y1747435D01*
X2687277Y1748685D01*
X2686967Y1749935D01*
X2686192Y1750977D01*
X2684797Y1751602D01*
X2683402Y1751394D01*
X2682007Y1750560D01*
G01X2693942Y1740560D02*
X2695027Y1739519D01*
X2696267Y1739102D01*
X2697507Y1739519D01*
X2698592Y1740768D01*
X2699367Y1742644D01*
X2699677Y1744519D01*
Y1746810D01*
X2699367Y1748685D01*
X2698592Y1750352D01*
X2697662Y1751185D01*
X2696577Y1751602D01*
X2695337Y1751185D01*
X2694407Y1750352D01*
X2693787Y1749102D01*
X2693477Y1747435D01*
X2693787Y1745977D01*
X2694562Y1744519D01*
X2695492Y1743685D01*
X2696577Y1743477D01*
X2697817Y1743893D01*
X2698747Y1744935D01*
X2699677Y1746810D01*
G01X2650232Y1783119D02*
X2651162Y1784368D01*
X2652247Y1784994D01*
X2653487Y1785202D01*
X2655037Y1784785D01*
X2656122Y1783744D01*
X2656432Y1782494D01*
X2656277Y1781243D01*
X2655657Y1780202D01*
X2652557Y1778119D01*
X2651162Y1776660D01*
X2650232Y1774577D01*
X2649922Y1772702D01*
X2656432D01*
G01X2665577D02*
Y1785202D01*
X2663717Y1782702D01*
G01Y1772702D02*
X2667437D01*
G01X2677977D02*
Y1785202D01*
X2676117Y1782702D01*
G01Y1772702D02*
X2679837D01*
G01X2686967Y1774577D02*
X2687897Y1773535D01*
X2688982Y1772910D01*
X2690377Y1772702D01*
X2691772Y1773119D01*
X2692857Y1773952D01*
X2693632Y1775410D01*
X2693787Y1777077D01*
X2693477Y1778744D01*
X2692702Y1779785D01*
X2691617Y1780619D01*
X2690532Y1780827D01*
X2689447Y1780619D01*
X2688052Y1779785D01*
X2688517Y1785202D01*
X2692702D01*
G01X2699367Y1775202D02*
X2700297Y1773743D01*
X2701537Y1772910D01*
X2702932Y1772702D01*
X2704172Y1772910D01*
X2705412Y1773952D01*
X2706187Y1775202D01*
X2706342Y1776452D01*
X2706032Y1777910D01*
X2704947Y1778952D01*
X2703862Y1779369D01*
X2702467D01*
G01X2703862D02*
X2704792Y1779994D01*
X2705567Y1781035D01*
X2705877Y1782285D01*
X2705567Y1783535D01*
X2704792Y1784577D01*
X2703397Y1785202D01*
X2702002Y1784994D01*
X2700607Y1784160D01*
G01X2659377Y1806302D02*
Y1818802D01*
X2657517Y1816302D01*
G01Y1806302D02*
X2661237D01*
G01X2668832Y1816719D02*
X2669762Y1817968D01*
X2670847Y1818594D01*
X2672087Y1818802D01*
X2673637Y1818385D01*
X2674722Y1817344D01*
X2675032Y1816094D01*
X2674877Y1814843D01*
X2674257Y1813802D01*
X2671157Y1811719D01*
X2669762Y1810260D01*
X2668832Y1808177D01*
X2668522Y1806302D01*
X2675032D01*
G01X2684177D02*
Y1818802D01*
X2682317Y1816302D01*
G01Y1806302D02*
X2686037D01*
G01X2693632Y1816719D02*
X2694562Y1817968D01*
X2695647Y1818594D01*
X2696887Y1818802D01*
X2698437Y1818385D01*
X2699522Y1817344D01*
X2699832Y1816094D01*
X2699677Y1814843D01*
X2699057Y1813802D01*
X2695957Y1811719D01*
X2694562Y1810260D01*
X2693632Y1808177D01*
X2693322Y1806302D01*
X2699832D01*
G01X2675032Y1850319D02*
X2675962Y1851568D01*
X2677047Y1852194D01*
X2678287Y1852402D01*
X2679837Y1851985D01*
X2680922Y1850944D01*
X2681232Y1849694D01*
X2681077Y1848443D01*
X2680457Y1847402D01*
X2677357Y1845319D01*
X2675962Y1843860D01*
X2675032Y1841777D01*
X2674722Y1839902D01*
X2681232D01*
G01X2665577Y1869202D02*
X2664337Y1869410D01*
X2663252Y1870243D01*
X2662322Y1871494D01*
X2661702Y1872952D01*
X2661392Y1874619D01*
Y1876285D01*
X2661702Y1877952D01*
X2662322Y1879410D01*
X2663252Y1880660D01*
X2664337Y1881494D01*
X2665577Y1881702D01*
X2666817Y1881494D01*
X2667902Y1880660D01*
X2668832Y1879410D01*
X2669452Y1877952D01*
X2669762Y1876285D01*
Y1874619D01*
X2669452Y1872952D01*
X2668832Y1871494D01*
X2667902Y1870243D01*
X2666817Y1869410D01*
X2665577Y1869202D01*
G01X2666817Y1872535D02*
X2668677Y1869202D01*
G01X2677977Y1881702D02*
Y1869202D01*
G01X2674412Y1881702D02*
X2681542D01*
G01X2690377Y1869202D02*
Y1874827D01*
X2687277Y1881702D01*
G01X2693477D02*
X2690377Y1874827D01*
G01X-7874Y-31496D02*
X-19685D01*
G01X-7874D02*
X-19685D01*
G01D02*
G03X-23622Y-35433I0J-3937D01*
G01D02*
Y-59055D01*
G01Y-35433D02*
Y-59055D01*
G01X-19685Y-31496D02*
G03X-23622Y-35433I0J-3937D01*
G01Y-59055D02*
G03X-19685Y-62992I3937J0D01*
G01D02*
X1972441D01*
G01X-19685D02*
X1972441D01*
G01X-23622Y-59055D02*
G03X-19685Y-62992I3937J0D01*
G01Y-23622D02*
X1972441D01*
G01X-19685D02*
X1972441D01*
G01X-19685D02*
X1972441D01*
G01X-19685D02*
X1972441D01*
G01X-23622Y622441D02*
Y-19685D01*
G01Y622441D02*
Y-19685D01*
G01Y622441D02*
Y-19685D01*
G01Y622441D02*
Y-19685D01*
G01D02*
G03X-19685Y-23622I3937J0D01*
G01X-23622Y-19685D02*
G03X-19685Y-23622I3937J0D01*
G01X-23622Y-19685D02*
G03X-19685Y-23622I3937J0D01*
G01X-23622Y-19685D02*
G03X-19685Y-23622I3937J0D01*
G01X-32695Y230713D02*
X-27695D01*
Y229113D01*
X-27945Y228580D01*
X-28528Y228180D01*
X-29195Y228047D01*
X-29862Y228180D01*
X-30362Y228513D01*
X-30612Y229113D01*
Y230713D01*
G01X-32695Y225213D02*
X-29362D01*
G01X-30028D02*
X-29695Y224880D01*
X-29445Y224547D01*
X-29362Y224080D01*
X-29445Y223747D01*
X-29695Y223347D01*
G01X-30445Y220180D02*
Y218047D01*
X-29862Y218247D01*
X-29528Y218580D01*
X-29362Y219047D01*
X-29445Y219513D01*
X-29695Y219913D01*
X-30278Y220180D01*
X-30778Y220313D01*
X-31278D01*
X-31778Y220180D01*
X-32278Y219847D01*
X-32612Y219447D01*
X-32695Y218980D01*
X-32528Y218513D01*
X-32028Y218047D01*
G01X-32112Y215080D02*
X-32445Y214747D01*
X-32695Y214280D01*
Y213880D01*
X-32528Y213480D01*
X-32278Y213213D01*
X-31945Y213080D01*
X-31445Y213147D01*
X-31195Y213413D01*
X-30695Y214613D01*
X-30112Y214880D01*
X-29695Y214747D01*
X-29445Y214480D01*
X-29362Y214080D01*
X-29445Y213680D01*
X-29695Y213280D01*
G01X-32112Y209980D02*
X-32445Y209647D01*
X-32695Y209180D01*
Y208780D01*
X-32528Y208380D01*
X-32278Y208113D01*
X-31945Y207980D01*
X-31445Y208047D01*
X-31195Y208313D01*
X-30695Y209513D01*
X-30112Y209780D01*
X-29695Y209647D01*
X-29445Y209380D01*
X-29362Y208980D01*
X-29445Y208580D01*
X-29695Y208180D01*
G01X-31028Y204747D02*
Y203013D01*
G01X-32695Y199180D02*
X-28445D01*
X-28028Y199047D01*
X-27778Y198780D01*
X-27695Y198380D01*
X-27862Y197980D01*
X-28278Y197780D01*
G01X-29695Y198580D02*
Y199913D01*
G01X-29362Y193680D02*
X-32695D01*
G01X-28028D02*
X-27945Y193813D01*
X-27778D01*
X-27695Y193680D01*
X-27778Y193547D01*
X-27945D01*
X-28028Y193680D01*
G01X-27695Y188580D02*
X-32695D01*
G01X-29362Y189513D02*
Y187647D01*
G01X-32695Y179713D02*
X-27695D01*
Y178113D01*
X-27945Y177580D01*
X-28528Y177180D01*
X-29195Y177047D01*
X-29862Y177180D01*
X-30362Y177513D01*
X-30612Y178113D01*
Y179713D01*
G01X-27695Y173280D02*
X-32695D01*
G01X-27695Y174813D02*
Y171747D01*
G01X-32695Y169580D02*
X-27695D01*
G01Y166780D02*
X-32695D01*
G01X-30195D02*
Y169580D01*
G01X-32695Y159113D02*
X-27695D01*
G01X-29362Y156980D02*
X-31278Y159113D01*
G01X-30528Y158247D02*
X-32695Y156847D01*
G01X-30445Y153880D02*
Y151747D01*
X-29862Y151947D01*
X-29528Y152280D01*
X-29362Y152747D01*
X-29445Y153213D01*
X-29695Y153613D01*
X-30278Y153880D01*
X-30778Y154013D01*
X-31278D01*
X-31778Y153880D01*
X-32278Y153547D01*
X-32612Y153147D01*
X-32695Y152680D01*
X-32528Y152213D01*
X-32028Y151747D01*
G01X-30445Y148780D02*
Y146647D01*
X-29862Y146847D01*
X-29528Y147180D01*
X-29362Y147647D01*
X-29445Y148113D01*
X-29695Y148513D01*
X-30278Y148780D01*
X-30778Y148913D01*
X-31278D01*
X-31778Y148780D01*
X-32278Y148447D01*
X-32612Y148047D01*
X-32695Y147580D01*
X-32528Y147113D01*
X-32028Y146647D01*
G01X-34362Y143880D02*
X-29362D01*
G01X-30112D02*
X-29695Y143547D01*
X-29445Y143213D01*
X-29362Y142680D01*
X-29445Y142213D01*
X-29862Y141747D01*
X-30445Y141547D01*
X-31028Y141480D01*
X-31612Y141547D01*
X-32195Y141747D01*
X-32528Y142147D01*
X-32695Y142680D01*
X-32612Y143147D01*
X-32362Y143613D01*
X-32028Y143880D01*
G01X-32695Y133613D02*
X-27695D01*
G01X-30112D02*
X-29695Y133280D01*
X-29445Y132947D01*
X-29362Y132413D01*
X-29445Y132013D01*
X-29778Y131547D01*
X-30278Y131347D01*
X-32695D01*
G01Y127380D02*
X-32612Y127780D01*
X-32278Y128180D01*
X-31695Y128447D01*
X-31028Y128580D01*
X-30362Y128447D01*
X-29778Y128180D01*
X-29445Y127780D01*
X-29362Y127380D01*
X-29445Y126980D01*
X-29778Y126580D01*
X-30362Y126313D01*
X-31028Y126247D01*
X-31695Y126313D01*
X-32278Y126580D01*
X-32612Y126980D01*
X-32695Y127380D01*
G01Y122280D02*
X-27695D01*
G01X-30445Y118180D02*
Y116047D01*
X-29862Y116247D01*
X-29528Y116580D01*
X-29362Y117047D01*
X-29445Y117513D01*
X-29695Y117913D01*
X-30278Y118180D01*
X-30778Y118313D01*
X-31278D01*
X-31778Y118180D01*
X-32278Y117847D01*
X-32612Y117447D01*
X-32695Y116980D01*
X-32528Y116513D01*
X-32028Y116047D01*
G01X-32112Y107980D02*
X-32445Y107647D01*
X-32695Y107180D01*
Y106780D01*
X-32528Y106380D01*
X-32278Y106113D01*
X-31945Y105980D01*
X-31445Y106047D01*
X-31195Y106313D01*
X-30695Y107513D01*
X-30112Y107780D01*
X-29695Y107647D01*
X-29445Y107380D01*
X-29362Y106980D01*
X-29445Y106580D01*
X-29695Y106180D01*
G01X-29362Y101880D02*
X-32695D01*
G01X-28028D02*
X-27945Y102013D01*
X-27778D01*
X-27695Y101880D01*
X-27778Y101747D01*
X-27945D01*
X-28028Y101880D01*
G01X-29362Y97780D02*
Y95780D01*
X-32695Y97780D01*
Y95780D01*
G01X-30445Y92680D02*
Y90547D01*
X-29862Y90747D01*
X-29528Y91080D01*
X-29362Y91547D01*
X-29445Y92013D01*
X-29695Y92413D01*
X-30278Y92680D01*
X-30778Y92813D01*
X-31278D01*
X-31778Y92680D01*
X-32278Y92347D01*
X-32612Y91947D01*
X-32695Y91480D01*
X-32528Y91013D01*
X-32028Y90547D01*
G01X-27695Y81480D02*
X-32695D01*
G01X-29362Y82413D02*
Y80547D01*
G01X-32695Y76380D02*
X-32612Y76780D01*
X-32278Y77180D01*
X-31695Y77447D01*
X-31028Y77580D01*
X-30362Y77447D01*
X-29778Y77180D01*
X-29445Y76780D01*
X-29362Y76380D01*
X-29445Y75980D01*
X-29778Y75580D01*
X-30362Y75313D01*
X-31028Y75247D01*
X-31695Y75313D01*
X-32278Y75580D01*
X-32612Y75980D01*
X-32695Y76380D01*
G01Y71280D02*
X-27695D01*
G01X-30445Y67180D02*
Y65047D01*
X-29862Y65247D01*
X-29528Y65580D01*
X-29362Y66047D01*
X-29445Y66513D01*
X-29695Y66913D01*
X-30278Y67180D01*
X-30778Y67313D01*
X-31278D01*
X-31778Y67180D01*
X-32278Y66847D01*
X-32612Y66447D01*
X-32695Y65980D01*
X-32528Y65513D01*
X-32028Y65047D01*
G01X-32695Y62013D02*
X-29362D01*
G01X-30028D02*
X-29695Y61680D01*
X-29445Y61347D01*
X-29362Y60880D01*
X-29445Y60547D01*
X-29695Y60147D01*
G01X-32695Y54780D02*
X-29362D01*
G01X-29945D02*
X-29612Y55047D01*
X-29445Y55447D01*
X-29362Y55913D01*
X-29528Y56380D01*
X-29862Y56780D01*
X-30362Y57047D01*
X-31028Y57180D01*
X-31695Y57047D01*
X-32195Y56780D01*
X-32528Y56380D01*
X-32695Y55913D01*
X-32612Y55447D01*
X-32362Y55047D01*
X-32028Y54780D01*
G01X-32695Y52013D02*
X-29362D01*
G01X-30195D02*
X-29778Y51747D01*
X-29445Y51347D01*
X-29362Y50813D01*
X-29445Y50347D01*
X-29778Y49947D01*
X-30362Y49747D01*
X-32695D01*
G01X-29778Y44713D02*
X-29445Y45180D01*
X-29362Y45580D01*
X-29528Y46113D01*
X-29862Y46513D01*
X-30445Y46780D01*
X-31028Y46847D01*
X-31612Y46780D01*
X-32112Y46513D01*
X-32528Y46113D01*
X-32695Y45580D01*
X-32528Y45113D01*
X-32195Y44713D01*
G01X-30445Y41680D02*
Y39547D01*
X-29862Y39747D01*
X-29528Y40080D01*
X-29362Y40547D01*
X-29445Y41013D01*
X-29695Y41413D01*
X-30278Y41680D01*
X-30778Y41813D01*
X-31278D01*
X-31778Y41680D01*
X-32278Y41347D01*
X-32612Y40947D01*
X-32695Y40480D01*
X-32528Y40013D01*
X-32028Y39547D01*
G01X-31028Y31213D02*
Y29613D01*
G01X-29945Y30480D02*
X-32112D01*
G01X-32862Y26580D02*
X-27695Y24180D01*
G01X-31028Y21147D02*
Y19413D01*
G01X-28528Y16447D02*
X-28028Y16047D01*
X-27778Y15580D01*
X-27695Y15047D01*
X-27862Y14380D01*
X-28278Y13913D01*
X-28778Y13780D01*
X-29278Y13847D01*
X-29695Y14113D01*
X-30528Y15447D01*
X-31112Y16047D01*
X-31945Y16447D01*
X-32695Y16580D01*
Y13780D01*
G01Y6980D02*
X-29362D01*
G01X-30278D02*
X-29862Y6780D01*
X-29528Y6447D01*
X-29362Y5980D01*
X-29528Y5513D01*
X-29862Y5180D01*
X-30278Y4980D01*
X-32695D01*
G01X-30278D02*
X-29862Y4780D01*
X-29528Y4447D01*
X-29362Y3980D01*
X-29528Y3513D01*
X-29862Y3180D01*
X-30362Y2980D01*
X-32695D01*
G01X-29362Y-120D02*
X-32695D01*
G01X-28028D02*
X-27945Y13D01*
X-27778D01*
X-27695Y-120D01*
X-27778Y-253D01*
X-27945D01*
X-28028Y-120D01*
G01X-32695Y-5220D02*
X-27695D01*
G01X-32112Y-9320D02*
X-32445Y-9653D01*
X-32695Y-10120D01*
Y-10520D01*
X-32528Y-10920D01*
X-32278Y-11187D01*
X-31945Y-11320D01*
X-31445Y-11253D01*
X-31195Y-10987D01*
X-30695Y-9787D01*
X-30112Y-9520D01*
X-29695Y-9653D01*
X-29445Y-9920D01*
X-29362Y-10320D01*
X-29445Y-10720D01*
X-29695Y-11120D01*
G01X-29629Y323339D02*
X-24629D01*
Y321739D01*
X-24879Y321206D01*
X-25462Y320806D01*
X-26129Y320673D01*
X-26796Y320806D01*
X-27296Y321139D01*
X-27546Y321739D01*
Y323339D01*
G01X-29629Y317839D02*
X-26296D01*
G01X-26962D02*
X-26629Y317506D01*
X-26379Y317173D01*
X-26296Y316706D01*
X-26379Y316373D01*
X-26629Y315973D01*
G01X-27379Y312806D02*
Y310673D01*
X-26796Y310873D01*
X-26462Y311206D01*
X-26296Y311673D01*
X-26379Y312139D01*
X-26629Y312539D01*
X-27212Y312806D01*
X-27712Y312939D01*
X-28212D01*
X-28712Y312806D01*
X-29212Y312473D01*
X-29546Y312073D01*
X-29629Y311606D01*
X-29462Y311139D01*
X-28962Y310673D01*
G01X-29046Y307706D02*
X-29379Y307373D01*
X-29629Y306906D01*
Y306506D01*
X-29462Y306106D01*
X-29212Y305839D01*
X-28879Y305706D01*
X-28379Y305773D01*
X-28129Y306039D01*
X-27629Y307239D01*
X-27046Y307506D01*
X-26629Y307373D01*
X-26379Y307106D01*
X-26296Y306706D01*
X-26379Y306306D01*
X-26629Y305906D01*
G01X-29046Y302606D02*
X-29379Y302273D01*
X-29629Y301806D01*
Y301406D01*
X-29462Y301006D01*
X-29212Y300739D01*
X-28879Y300606D01*
X-28379Y300673D01*
X-28129Y300939D01*
X-27629Y302139D01*
X-27046Y302406D01*
X-26629Y302273D01*
X-26379Y302006D01*
X-26296Y301606D01*
X-26379Y301206D01*
X-26629Y300806D01*
G01X-27962Y297373D02*
Y295639D01*
G01X-29629Y291806D02*
X-25379D01*
X-24962Y291673D01*
X-24712Y291406D01*
X-24629Y291006D01*
X-24796Y290606D01*
X-25212Y290406D01*
G01X-26629Y291206D02*
Y292539D01*
G01X-26296Y286306D02*
X-29629D01*
G01X-24962D02*
X-24879Y286439D01*
X-24712D01*
X-24629Y286306D01*
X-24712Y286173D01*
X-24879D01*
X-24962Y286306D01*
G01X-24629Y281206D02*
X-29629D01*
G01X-26296Y282139D02*
Y280273D01*
G01X-29629Y272339D02*
X-24629D01*
Y270739D01*
X-24879Y270206D01*
X-25462Y269806D01*
X-26129Y269673D01*
X-26796Y269806D01*
X-27296Y270139D01*
X-27546Y270739D01*
Y272339D01*
G01X-24629Y265906D02*
X-29629D01*
G01X-24629Y267439D02*
Y264373D01*
G01X-29629Y262206D02*
X-24629D01*
G01Y259406D02*
X-29629D01*
G01X-27129D02*
Y262206D01*
G01X-29629Y251739D02*
X-24629D01*
G01X-26296Y249606D02*
X-28212Y251739D01*
G01X-27462Y250873D02*
X-29629Y249473D01*
G01X-27379Y246506D02*
Y244373D01*
X-26796Y244573D01*
X-26462Y244906D01*
X-26296Y245373D01*
X-26379Y245839D01*
X-26629Y246239D01*
X-27212Y246506D01*
X-27712Y246639D01*
X-28212D01*
X-28712Y246506D01*
X-29212Y246173D01*
X-29546Y245773D01*
X-29629Y245306D01*
X-29462Y244839D01*
X-28962Y244373D01*
G01X-27379Y241406D02*
Y239273D01*
X-26796Y239473D01*
X-26462Y239806D01*
X-26296Y240273D01*
X-26379Y240739D01*
X-26629Y241139D01*
X-27212Y241406D01*
X-27712Y241539D01*
X-28212D01*
X-28712Y241406D01*
X-29212Y241073D01*
X-29546Y240673D01*
X-29629Y240206D01*
X-29462Y239739D01*
X-28962Y239273D01*
G01X-31296Y236506D02*
X-26296D01*
G01X-27046D02*
X-26629Y236173D01*
X-26379Y235839D01*
X-26296Y235306D01*
X-26379Y234839D01*
X-26796Y234373D01*
X-27379Y234173D01*
X-27962Y234106D01*
X-28546Y234173D01*
X-29129Y234373D01*
X-29462Y234773D01*
X-29629Y235306D01*
X-29546Y235773D01*
X-29296Y236239D01*
X-28962Y236506D01*
G01X-29629Y226239D02*
X-24629D01*
G01X-27046D02*
X-26629Y225906D01*
X-26379Y225573D01*
X-26296Y225039D01*
X-26379Y224639D01*
X-26712Y224173D01*
X-27212Y223973D01*
X-29629D01*
G01Y220006D02*
X-29546Y220406D01*
X-29212Y220806D01*
X-28629Y221073D01*
X-27962Y221206D01*
X-27296Y221073D01*
X-26712Y220806D01*
X-26379Y220406D01*
X-26296Y220006D01*
X-26379Y219606D01*
X-26712Y219206D01*
X-27296Y218939D01*
X-27962Y218873D01*
X-28629Y218939D01*
X-29212Y219206D01*
X-29546Y219606D01*
X-29629Y220006D01*
G01Y214906D02*
X-24629D01*
G01X-27379Y210806D02*
Y208673D01*
X-26796Y208873D01*
X-26462Y209206D01*
X-26296Y209673D01*
X-26379Y210139D01*
X-26629Y210539D01*
X-27212Y210806D01*
X-27712Y210939D01*
X-28212D01*
X-28712Y210806D01*
X-29212Y210473D01*
X-29546Y210073D01*
X-29629Y209606D01*
X-29462Y209139D01*
X-28962Y208673D01*
G01X-29046Y200606D02*
X-29379Y200273D01*
X-29629Y199806D01*
Y199406D01*
X-29462Y199006D01*
X-29212Y198739D01*
X-28879Y198606D01*
X-28379Y198673D01*
X-28129Y198939D01*
X-27629Y200139D01*
X-27046Y200406D01*
X-26629Y200273D01*
X-26379Y200006D01*
X-26296Y199606D01*
X-26379Y199206D01*
X-26629Y198806D01*
G01X-26296Y194506D02*
X-29629D01*
G01X-24962D02*
X-24879Y194639D01*
X-24712D01*
X-24629Y194506D01*
X-24712Y194373D01*
X-24879D01*
X-24962Y194506D01*
G01X-26296Y190406D02*
Y188406D01*
X-29629Y190406D01*
Y188406D01*
G01X-27379Y185306D02*
Y183173D01*
X-26796Y183373D01*
X-26462Y183706D01*
X-26296Y184173D01*
X-26379Y184639D01*
X-26629Y185039D01*
X-27212Y185306D01*
X-27712Y185439D01*
X-28212D01*
X-28712Y185306D01*
X-29212Y184973D01*
X-29546Y184573D01*
X-29629Y184106D01*
X-29462Y183639D01*
X-28962Y183173D01*
G01X-24629Y174106D02*
X-29629D01*
G01X-26296Y175039D02*
Y173173D01*
G01X-29629Y169006D02*
X-29546Y169406D01*
X-29212Y169806D01*
X-28629Y170073D01*
X-27962Y170206D01*
X-27296Y170073D01*
X-26712Y169806D01*
X-26379Y169406D01*
X-26296Y169006D01*
X-26379Y168606D01*
X-26712Y168206D01*
X-27296Y167939D01*
X-27962Y167873D01*
X-28629Y167939D01*
X-29212Y168206D01*
X-29546Y168606D01*
X-29629Y169006D01*
G01Y163906D02*
X-24629D01*
G01X-27379Y159806D02*
Y157673D01*
X-26796Y157873D01*
X-26462Y158206D01*
X-26296Y158673D01*
X-26379Y159139D01*
X-26629Y159539D01*
X-27212Y159806D01*
X-27712Y159939D01*
X-28212D01*
X-28712Y159806D01*
X-29212Y159473D01*
X-29546Y159073D01*
X-29629Y158606D01*
X-29462Y158139D01*
X-28962Y157673D01*
G01X-29629Y154639D02*
X-26296D01*
G01X-26962D02*
X-26629Y154306D01*
X-26379Y153973D01*
X-26296Y153506D01*
X-26379Y153173D01*
X-26629Y152773D01*
G01X-29629Y147406D02*
X-26296D01*
G01X-26879D02*
X-26546Y147673D01*
X-26379Y148073D01*
X-26296Y148539D01*
X-26462Y149006D01*
X-26796Y149406D01*
X-27296Y149673D01*
X-27962Y149806D01*
X-28629Y149673D01*
X-29129Y149406D01*
X-29462Y149006D01*
X-29629Y148539D01*
X-29546Y148073D01*
X-29296Y147673D01*
X-28962Y147406D01*
G01X-29629Y144639D02*
X-26296D01*
G01X-27129D02*
X-26712Y144373D01*
X-26379Y143973D01*
X-26296Y143439D01*
X-26379Y142973D01*
X-26712Y142573D01*
X-27296Y142373D01*
X-29629D01*
G01X-26712Y137339D02*
X-26379Y137806D01*
X-26296Y138206D01*
X-26462Y138739D01*
X-26796Y139139D01*
X-27379Y139406D01*
X-27962Y139473D01*
X-28546Y139406D01*
X-29046Y139139D01*
X-29462Y138739D01*
X-29629Y138206D01*
X-29462Y137739D01*
X-29129Y137339D01*
G01X-27379Y134306D02*
Y132173D01*
X-26796Y132373D01*
X-26462Y132706D01*
X-26296Y133173D01*
X-26379Y133639D01*
X-26629Y134039D01*
X-27212Y134306D01*
X-27712Y134439D01*
X-28212D01*
X-28712Y134306D01*
X-29212Y133973D01*
X-29546Y133573D01*
X-29629Y133106D01*
X-29462Y132639D01*
X-28962Y132173D01*
G01X-27962Y123839D02*
Y122239D01*
G01X-26879Y123106D02*
X-29046D01*
G01X-29796Y119206D02*
X-24629Y116806D01*
G01X-27962Y113773D02*
Y112039D01*
G01X-25462Y109073D02*
X-24962Y108673D01*
X-24712Y108206D01*
X-24629Y107673D01*
X-24796Y107006D01*
X-25212Y106539D01*
X-25712Y106406D01*
X-26212Y106473D01*
X-26629Y106739D01*
X-27462Y108073D01*
X-28046Y108673D01*
X-28879Y109073D01*
X-29629Y109206D01*
Y106406D01*
G01Y104706D02*
X-26296D01*
G01X-27212D02*
X-26796Y104506D01*
X-26462Y104173D01*
X-26296Y103706D01*
X-26462Y103239D01*
X-26796Y102906D01*
X-27212Y102706D01*
X-29629D01*
G01X-27212D02*
X-26796Y102506D01*
X-26462Y102173D01*
X-26296Y101706D01*
X-26462Y101239D01*
X-26796Y100906D01*
X-27296Y100706D01*
X-29629D01*
G01X-26296Y97606D02*
X-29629D01*
G01X-24962D02*
X-24879Y97739D01*
X-24712D01*
X-24629Y97606D01*
X-24712Y97473D01*
X-24879D01*
X-24962Y97606D01*
G01X-29629Y92506D02*
X-24629D01*
G01X-29046Y88406D02*
X-29379Y88073D01*
X-29629Y87606D01*
Y87206D01*
X-29462Y86806D01*
X-29212Y86539D01*
X-28879Y86406D01*
X-28379Y86473D01*
X-28129Y86739D01*
X-27629Y87939D01*
X-27046Y88206D01*
X-26629Y88073D01*
X-26379Y87806D01*
X-26296Y87406D01*
X-26379Y87006D01*
X-26629Y86606D01*
G01X-23622Y194134D02*
Y63426D01*
G01Y291181D02*
Y141181D01*
G01X-39978Y163280D02*
X-40395Y162747D01*
X-40645Y162147D01*
Y161613D01*
X-40395Y161080D01*
X-39978Y160680D01*
X-39395Y160480D01*
X-38812Y160613D01*
X-38312Y160947D01*
X-37978Y161547D01*
X-37812Y162347D01*
X-37478Y162813D01*
X-36895Y163013D01*
X-36312Y162880D01*
X-35895Y162547D01*
X-35645Y162080D01*
Y161613D01*
X-35812Y161147D01*
X-36228Y160747D01*
G01X-40645Y156780D02*
X-35645D01*
G01X-37312Y151680D02*
X-40645D01*
G01X-35978D02*
X-35895Y151813D01*
X-35728D01*
X-35645Y151680D01*
X-35728Y151547D01*
X-35895D01*
X-35978Y151680D01*
G01X-35645Y146580D02*
X-40645D01*
G01X-37312Y147513D02*
Y145647D01*
G01X-23445Y158780D02*
X-25945Y161280D01*
Y156280D01*
X-23445Y158780D01*
X-35945D01*
G01X36558Y159039D02*
Y98521D01*
X-18448D01*
Y159039D01*
X36558D01*
G01X-28448Y128780D02*
X-18748D01*
X-23748Y123780D01*
Y133780D01*
X-18748Y128780D01*
G01X-35802Y224606D02*
X-36219Y224073D01*
X-36469Y223473D01*
Y222939D01*
X-36219Y222406D01*
X-35802Y222006D01*
X-35219Y221806D01*
X-34636Y221939D01*
X-34136Y222273D01*
X-33802Y222873D01*
X-33636Y223673D01*
X-33302Y224139D01*
X-32719Y224339D01*
X-32136Y224206D01*
X-31719Y223873D01*
X-31469Y223406D01*
Y222939D01*
X-31636Y222473D01*
X-32052Y222073D01*
G01X-36469Y218106D02*
X-31469D01*
G01X-33136Y213006D02*
X-36469D01*
G01X-31802D02*
X-31719Y213139D01*
X-31552D01*
X-31469Y213006D01*
X-31552Y212873D01*
X-31719D01*
X-31802Y213006D01*
G01X-31469Y207906D02*
X-36469D01*
G01X-33136Y208839D02*
Y206973D01*
G01X-24163Y216637D02*
X-26163Y218637D01*
Y214637D01*
X-24163Y216637D01*
X-32163D01*
G01X-29629Y432473D02*
X-24629D01*
Y430873D01*
X-24879Y430340D01*
X-25462Y429940D01*
X-26129Y429807D01*
X-26796Y429940D01*
X-27296Y430273D01*
X-27546Y430873D01*
Y432473D01*
G01X-29629Y426973D02*
X-26296D01*
G01X-26962D02*
X-26629Y426640D01*
X-26379Y426307D01*
X-26296Y425840D01*
X-26379Y425507D01*
X-26629Y425107D01*
G01X-27379Y421940D02*
Y419807D01*
X-26796Y420007D01*
X-26462Y420340D01*
X-26296Y420807D01*
X-26379Y421273D01*
X-26629Y421673D01*
X-27212Y421940D01*
X-27712Y422073D01*
X-28212D01*
X-28712Y421940D01*
X-29212Y421607D01*
X-29546Y421207D01*
X-29629Y420740D01*
X-29462Y420273D01*
X-28962Y419807D01*
G01X-29046Y416840D02*
X-29379Y416507D01*
X-29629Y416040D01*
Y415640D01*
X-29462Y415240D01*
X-29212Y414973D01*
X-28879Y414840D01*
X-28379Y414907D01*
X-28129Y415173D01*
X-27629Y416373D01*
X-27046Y416640D01*
X-26629Y416507D01*
X-26379Y416240D01*
X-26296Y415840D01*
X-26379Y415440D01*
X-26629Y415040D01*
G01X-29046Y411740D02*
X-29379Y411407D01*
X-29629Y410940D01*
Y410540D01*
X-29462Y410140D01*
X-29212Y409873D01*
X-28879Y409740D01*
X-28379Y409807D01*
X-28129Y410073D01*
X-27629Y411273D01*
X-27046Y411540D01*
X-26629Y411407D01*
X-26379Y411140D01*
X-26296Y410740D01*
X-26379Y410340D01*
X-26629Y409940D01*
G01X-27962Y406507D02*
Y404773D01*
G01X-29629Y400940D02*
X-25379D01*
X-24962Y400807D01*
X-24712Y400540D01*
X-24629Y400140D01*
X-24796Y399740D01*
X-25212Y399540D01*
G01X-26629Y400340D02*
Y401673D01*
G01X-26296Y395440D02*
X-29629D01*
G01X-24962D02*
X-24879Y395573D01*
X-24712D01*
X-24629Y395440D01*
X-24712Y395307D01*
X-24879D01*
X-24962Y395440D01*
G01X-24629Y390340D02*
X-29629D01*
G01X-26296Y391273D02*
Y389407D01*
G01X-29629Y381473D02*
X-24629D01*
Y379873D01*
X-24879Y379340D01*
X-25462Y378940D01*
X-26129Y378807D01*
X-26796Y378940D01*
X-27296Y379273D01*
X-27546Y379873D01*
Y381473D01*
G01X-24629Y375040D02*
X-29629D01*
G01X-24629Y376573D02*
Y373507D01*
G01X-29629Y371340D02*
X-24629D01*
G01Y368540D02*
X-29629D01*
G01X-27129D02*
Y371340D01*
G01X-29629Y360873D02*
X-24629D01*
G01X-26296Y358740D02*
X-28212Y360873D01*
G01X-27462Y360007D02*
X-29629Y358607D01*
G01X-27379Y355640D02*
Y353507D01*
X-26796Y353707D01*
X-26462Y354040D01*
X-26296Y354507D01*
X-26379Y354973D01*
X-26629Y355373D01*
X-27212Y355640D01*
X-27712Y355773D01*
X-28212D01*
X-28712Y355640D01*
X-29212Y355307D01*
X-29546Y354907D01*
X-29629Y354440D01*
X-29462Y353973D01*
X-28962Y353507D01*
G01X-27379Y350540D02*
Y348407D01*
X-26796Y348607D01*
X-26462Y348940D01*
X-26296Y349407D01*
X-26379Y349873D01*
X-26629Y350273D01*
X-27212Y350540D01*
X-27712Y350673D01*
X-28212D01*
X-28712Y350540D01*
X-29212Y350207D01*
X-29546Y349807D01*
X-29629Y349340D01*
X-29462Y348873D01*
X-28962Y348407D01*
G01X-31296Y345640D02*
X-26296D01*
G01X-27046D02*
X-26629Y345307D01*
X-26379Y344973D01*
X-26296Y344440D01*
X-26379Y343973D01*
X-26796Y343507D01*
X-27379Y343307D01*
X-27962Y343240D01*
X-28546Y343307D01*
X-29129Y343507D01*
X-29462Y343907D01*
X-29629Y344440D01*
X-29546Y344907D01*
X-29296Y345373D01*
X-28962Y345640D01*
G01X-29629Y335373D02*
X-24629D01*
G01X-27046D02*
X-26629Y335040D01*
X-26379Y334707D01*
X-26296Y334173D01*
X-26379Y333773D01*
X-26712Y333307D01*
X-27212Y333107D01*
X-29629D01*
G01Y329140D02*
X-29546Y329540D01*
X-29212Y329940D01*
X-28629Y330207D01*
X-27962Y330340D01*
X-27296Y330207D01*
X-26712Y329940D01*
X-26379Y329540D01*
X-26296Y329140D01*
X-26379Y328740D01*
X-26712Y328340D01*
X-27296Y328073D01*
X-27962Y328007D01*
X-28629Y328073D01*
X-29212Y328340D01*
X-29546Y328740D01*
X-29629Y329140D01*
G01Y324040D02*
X-24629D01*
G01X-27379Y319940D02*
Y317807D01*
X-26796Y318007D01*
X-26462Y318340D01*
X-26296Y318807D01*
X-26379Y319273D01*
X-26629Y319673D01*
X-27212Y319940D01*
X-27712Y320073D01*
X-28212D01*
X-28712Y319940D01*
X-29212Y319607D01*
X-29546Y319207D01*
X-29629Y318740D01*
X-29462Y318273D01*
X-28962Y317807D01*
G01X-29046Y309740D02*
X-29379Y309407D01*
X-29629Y308940D01*
Y308540D01*
X-29462Y308140D01*
X-29212Y307873D01*
X-28879Y307740D01*
X-28379Y307807D01*
X-28129Y308073D01*
X-27629Y309273D01*
X-27046Y309540D01*
X-26629Y309407D01*
X-26379Y309140D01*
X-26296Y308740D01*
X-26379Y308340D01*
X-26629Y307940D01*
G01X-26296Y303640D02*
X-29629D01*
G01X-24962D02*
X-24879Y303773D01*
X-24712D01*
X-24629Y303640D01*
X-24712Y303507D01*
X-24879D01*
X-24962Y303640D01*
G01X-26296Y299540D02*
Y297540D01*
X-29629Y299540D01*
Y297540D01*
G01X-27379Y294440D02*
Y292307D01*
X-26796Y292507D01*
X-26462Y292840D01*
X-26296Y293307D01*
X-26379Y293773D01*
X-26629Y294173D01*
X-27212Y294440D01*
X-27712Y294573D01*
X-28212D01*
X-28712Y294440D01*
X-29212Y294107D01*
X-29546Y293707D01*
X-29629Y293240D01*
X-29462Y292773D01*
X-28962Y292307D01*
G01X-24629Y283240D02*
X-29629D01*
G01X-26296Y284173D02*
Y282307D01*
G01X-29629Y278140D02*
X-29546Y278540D01*
X-29212Y278940D01*
X-28629Y279207D01*
X-27962Y279340D01*
X-27296Y279207D01*
X-26712Y278940D01*
X-26379Y278540D01*
X-26296Y278140D01*
X-26379Y277740D01*
X-26712Y277340D01*
X-27296Y277073D01*
X-27962Y277007D01*
X-28629Y277073D01*
X-29212Y277340D01*
X-29546Y277740D01*
X-29629Y278140D01*
G01Y273040D02*
X-24629D01*
G01X-27379Y268940D02*
Y266807D01*
X-26796Y267007D01*
X-26462Y267340D01*
X-26296Y267807D01*
X-26379Y268273D01*
X-26629Y268673D01*
X-27212Y268940D01*
X-27712Y269073D01*
X-28212D01*
X-28712Y268940D01*
X-29212Y268607D01*
X-29546Y268207D01*
X-29629Y267740D01*
X-29462Y267273D01*
X-28962Y266807D01*
G01X-29629Y263773D02*
X-26296D01*
G01X-26962D02*
X-26629Y263440D01*
X-26379Y263107D01*
X-26296Y262640D01*
X-26379Y262307D01*
X-26629Y261907D01*
G01X-29629Y256540D02*
X-26296D01*
G01X-26879D02*
X-26546Y256807D01*
X-26379Y257207D01*
X-26296Y257673D01*
X-26462Y258140D01*
X-26796Y258540D01*
X-27296Y258807D01*
X-27962Y258940D01*
X-28629Y258807D01*
X-29129Y258540D01*
X-29462Y258140D01*
X-29629Y257673D01*
X-29546Y257207D01*
X-29296Y256807D01*
X-28962Y256540D01*
G01X-29629Y253773D02*
X-26296D01*
G01X-27129D02*
X-26712Y253507D01*
X-26379Y253107D01*
X-26296Y252573D01*
X-26379Y252107D01*
X-26712Y251707D01*
X-27296Y251507D01*
X-29629D01*
G01X-26712Y246473D02*
X-26379Y246940D01*
X-26296Y247340D01*
X-26462Y247873D01*
X-26796Y248273D01*
X-27379Y248540D01*
X-27962Y248607D01*
X-28546Y248540D01*
X-29046Y248273D01*
X-29462Y247873D01*
X-29629Y247340D01*
X-29462Y246873D01*
X-29129Y246473D01*
G01X-27379Y243440D02*
Y241307D01*
X-26796Y241507D01*
X-26462Y241840D01*
X-26296Y242307D01*
X-26379Y242773D01*
X-26629Y243173D01*
X-27212Y243440D01*
X-27712Y243573D01*
X-28212D01*
X-28712Y243440D01*
X-29212Y243107D01*
X-29546Y242707D01*
X-29629Y242240D01*
X-29462Y241773D01*
X-28962Y241307D01*
G01X-27962Y232973D02*
Y231373D01*
G01X-26879Y232240D02*
X-29046D01*
G01X-29796Y228340D02*
X-24629Y225940D01*
G01X-27962Y222907D02*
Y221173D01*
G01X-25462Y218207D02*
X-24962Y217807D01*
X-24712Y217340D01*
X-24629Y216807D01*
X-24796Y216140D01*
X-25212Y215673D01*
X-25712Y215540D01*
X-26212Y215607D01*
X-26629Y215873D01*
X-27462Y217207D01*
X-28046Y217807D01*
X-28879Y218207D01*
X-29629Y218340D01*
Y215540D01*
G01Y213840D02*
X-26296D01*
G01X-27212D02*
X-26796Y213640D01*
X-26462Y213307D01*
X-26296Y212840D01*
X-26462Y212373D01*
X-26796Y212040D01*
X-27212Y211840D01*
X-29629D01*
G01X-27212D02*
X-26796Y211640D01*
X-26462Y211307D01*
X-26296Y210840D01*
X-26462Y210373D01*
X-26796Y210040D01*
X-27296Y209840D01*
X-29629D01*
G01X-26296Y206740D02*
X-29629D01*
G01X-24962D02*
X-24879Y206873D01*
X-24712D01*
X-24629Y206740D01*
X-24712Y206607D01*
X-24879D01*
X-24962Y206740D01*
G01X-29629Y201640D02*
X-24629D01*
G01X-29046Y197540D02*
X-29379Y197207D01*
X-29629Y196740D01*
Y196340D01*
X-29462Y195940D01*
X-29212Y195673D01*
X-28879Y195540D01*
X-28379Y195607D01*
X-28129Y195873D01*
X-27629Y197073D01*
X-27046Y197340D01*
X-26629Y197207D01*
X-26379Y196940D01*
X-26296Y196540D01*
X-26379Y196140D01*
X-26629Y195740D01*
G01X-15283Y227128D02*
X-17283Y229128D01*
Y225128D01*
X-15283Y227128D01*
X-27283D01*
G01X-23622Y400315D02*
Y250315D01*
G01X-32695Y486854D02*
X-27695D01*
Y485254D01*
X-27945Y484721D01*
X-28528Y484321D01*
X-29195Y484188D01*
X-29862Y484321D01*
X-30362Y484654D01*
X-30612Y485254D01*
Y486854D01*
G01X-32695Y481354D02*
X-29362D01*
G01X-30028D02*
X-29695Y481021D01*
X-29445Y480688D01*
X-29362Y480221D01*
X-29445Y479888D01*
X-29695Y479488D01*
G01X-30445Y476321D02*
Y474188D01*
X-29862Y474388D01*
X-29528Y474721D01*
X-29362Y475188D01*
X-29445Y475654D01*
X-29695Y476054D01*
X-30278Y476321D01*
X-30778Y476454D01*
X-31278D01*
X-31778Y476321D01*
X-32278Y475988D01*
X-32612Y475588D01*
X-32695Y475121D01*
X-32528Y474654D01*
X-32028Y474188D01*
G01X-32112Y471221D02*
X-32445Y470888D01*
X-32695Y470421D01*
Y470021D01*
X-32528Y469621D01*
X-32278Y469354D01*
X-31945Y469221D01*
X-31445Y469288D01*
X-31195Y469554D01*
X-30695Y470754D01*
X-30112Y471021D01*
X-29695Y470888D01*
X-29445Y470621D01*
X-29362Y470221D01*
X-29445Y469821D01*
X-29695Y469421D01*
G01X-32112Y466121D02*
X-32445Y465788D01*
X-32695Y465321D01*
Y464921D01*
X-32528Y464521D01*
X-32278Y464254D01*
X-31945Y464121D01*
X-31445Y464188D01*
X-31195Y464454D01*
X-30695Y465654D01*
X-30112Y465921D01*
X-29695Y465788D01*
X-29445Y465521D01*
X-29362Y465121D01*
X-29445Y464721D01*
X-29695Y464321D01*
G01X-31028Y460888D02*
Y459154D01*
G01X-32695Y455321D02*
X-28445D01*
X-28028Y455188D01*
X-27778Y454921D01*
X-27695Y454521D01*
X-27862Y454121D01*
X-28278Y453921D01*
G01X-29695Y454721D02*
Y456054D01*
G01X-29362Y449821D02*
X-32695D01*
G01X-28028D02*
X-27945Y449954D01*
X-27778D01*
X-27695Y449821D01*
X-27778Y449688D01*
X-27945D01*
X-28028Y449821D01*
G01X-27695Y444721D02*
X-32695D01*
G01X-29362Y445654D02*
Y443788D01*
G01X-32695Y435854D02*
X-27695D01*
Y434254D01*
X-27945Y433721D01*
X-28528Y433321D01*
X-29195Y433188D01*
X-29862Y433321D01*
X-30362Y433654D01*
X-30612Y434254D01*
Y435854D01*
G01X-27695Y429421D02*
X-32695D01*
G01X-27695Y430954D02*
Y427888D01*
G01X-32695Y425721D02*
X-27695D01*
G01Y422921D02*
X-32695D01*
G01X-30195D02*
Y425721D01*
G01X-32695Y415254D02*
X-27695D01*
G01X-29362Y413121D02*
X-31278Y415254D01*
G01X-30528Y414388D02*
X-32695Y412988D01*
G01X-30445Y410021D02*
Y407888D01*
X-29862Y408088D01*
X-29528Y408421D01*
X-29362Y408888D01*
X-29445Y409354D01*
X-29695Y409754D01*
X-30278Y410021D01*
X-30778Y410154D01*
X-31278D01*
X-31778Y410021D01*
X-32278Y409688D01*
X-32612Y409288D01*
X-32695Y408821D01*
X-32528Y408354D01*
X-32028Y407888D01*
G01X-30445Y404921D02*
Y402788D01*
X-29862Y402988D01*
X-29528Y403321D01*
X-29362Y403788D01*
X-29445Y404254D01*
X-29695Y404654D01*
X-30278Y404921D01*
X-30778Y405054D01*
X-31278D01*
X-31778Y404921D01*
X-32278Y404588D01*
X-32612Y404188D01*
X-32695Y403721D01*
X-32528Y403254D01*
X-32028Y402788D01*
G01X-34362Y400021D02*
X-29362D01*
G01X-30112D02*
X-29695Y399688D01*
X-29445Y399354D01*
X-29362Y398821D01*
X-29445Y398354D01*
X-29862Y397888D01*
X-30445Y397688D01*
X-31028Y397621D01*
X-31612Y397688D01*
X-32195Y397888D01*
X-32528Y398288D01*
X-32695Y398821D01*
X-32612Y399288D01*
X-32362Y399754D01*
X-32028Y400021D01*
G01X-32695Y389754D02*
X-27695D01*
G01X-30112D02*
X-29695Y389421D01*
X-29445Y389088D01*
X-29362Y388554D01*
X-29445Y388154D01*
X-29778Y387688D01*
X-30278Y387488D01*
X-32695D01*
G01Y383521D02*
X-32612Y383921D01*
X-32278Y384321D01*
X-31695Y384588D01*
X-31028Y384721D01*
X-30362Y384588D01*
X-29778Y384321D01*
X-29445Y383921D01*
X-29362Y383521D01*
X-29445Y383121D01*
X-29778Y382721D01*
X-30362Y382454D01*
X-31028Y382388D01*
X-31695Y382454D01*
X-32278Y382721D01*
X-32612Y383121D01*
X-32695Y383521D01*
G01Y378421D02*
X-27695D01*
G01X-30445Y374321D02*
Y372188D01*
X-29862Y372388D01*
X-29528Y372721D01*
X-29362Y373188D01*
X-29445Y373654D01*
X-29695Y374054D01*
X-30278Y374321D01*
X-30778Y374454D01*
X-31278D01*
X-31778Y374321D01*
X-32278Y373988D01*
X-32612Y373588D01*
X-32695Y373121D01*
X-32528Y372654D01*
X-32028Y372188D01*
G01X-32112Y364121D02*
X-32445Y363788D01*
X-32695Y363321D01*
Y362921D01*
X-32528Y362521D01*
X-32278Y362254D01*
X-31945Y362121D01*
X-31445Y362188D01*
X-31195Y362454D01*
X-30695Y363654D01*
X-30112Y363921D01*
X-29695Y363788D01*
X-29445Y363521D01*
X-29362Y363121D01*
X-29445Y362721D01*
X-29695Y362321D01*
G01X-29362Y358021D02*
X-32695D01*
G01X-28028D02*
X-27945Y358154D01*
X-27778D01*
X-27695Y358021D01*
X-27778Y357888D01*
X-27945D01*
X-28028Y358021D01*
G01X-29362Y353921D02*
Y351921D01*
X-32695Y353921D01*
Y351921D01*
G01X-30445Y348821D02*
Y346688D01*
X-29862Y346888D01*
X-29528Y347221D01*
X-29362Y347688D01*
X-29445Y348154D01*
X-29695Y348554D01*
X-30278Y348821D01*
X-30778Y348954D01*
X-31278D01*
X-31778Y348821D01*
X-32278Y348488D01*
X-32612Y348088D01*
X-32695Y347621D01*
X-32528Y347154D01*
X-32028Y346688D01*
G01X-27695Y337621D02*
X-32695D01*
G01X-29362Y338554D02*
Y336688D01*
G01X-32695Y332521D02*
X-32612Y332921D01*
X-32278Y333321D01*
X-31695Y333588D01*
X-31028Y333721D01*
X-30362Y333588D01*
X-29778Y333321D01*
X-29445Y332921D01*
X-29362Y332521D01*
X-29445Y332121D01*
X-29778Y331721D01*
X-30362Y331454D01*
X-31028Y331388D01*
X-31695Y331454D01*
X-32278Y331721D01*
X-32612Y332121D01*
X-32695Y332521D01*
G01Y327421D02*
X-27695D01*
G01X-30445Y323321D02*
Y321188D01*
X-29862Y321388D01*
X-29528Y321721D01*
X-29362Y322188D01*
X-29445Y322654D01*
X-29695Y323054D01*
X-30278Y323321D01*
X-30778Y323454D01*
X-31278D01*
X-31778Y323321D01*
X-32278Y322988D01*
X-32612Y322588D01*
X-32695Y322121D01*
X-32528Y321654D01*
X-32028Y321188D01*
G01X-32695Y318154D02*
X-29362D01*
G01X-30028D02*
X-29695Y317821D01*
X-29445Y317488D01*
X-29362Y317021D01*
X-29445Y316688D01*
X-29695Y316288D01*
G01X-32695Y310921D02*
X-29362D01*
G01X-29945D02*
X-29612Y311188D01*
X-29445Y311588D01*
X-29362Y312054D01*
X-29528Y312521D01*
X-29862Y312921D01*
X-30362Y313188D01*
X-31028Y313321D01*
X-31695Y313188D01*
X-32195Y312921D01*
X-32528Y312521D01*
X-32695Y312054D01*
X-32612Y311588D01*
X-32362Y311188D01*
X-32028Y310921D01*
G01X-32695Y308154D02*
X-29362D01*
G01X-30195D02*
X-29778Y307888D01*
X-29445Y307488D01*
X-29362Y306954D01*
X-29445Y306488D01*
X-29778Y306088D01*
X-30362Y305888D01*
X-32695D01*
G01X-29778Y300854D02*
X-29445Y301321D01*
X-29362Y301721D01*
X-29528Y302254D01*
X-29862Y302654D01*
X-30445Y302921D01*
X-31028Y302988D01*
X-31612Y302921D01*
X-32112Y302654D01*
X-32528Y302254D01*
X-32695Y301721D01*
X-32528Y301254D01*
X-32195Y300854D01*
G01X-30445Y297821D02*
Y295688D01*
X-29862Y295888D01*
X-29528Y296221D01*
X-29362Y296688D01*
X-29445Y297154D01*
X-29695Y297554D01*
X-30278Y297821D01*
X-30778Y297954D01*
X-31278D01*
X-31778Y297821D01*
X-32278Y297488D01*
X-32612Y297088D01*
X-32695Y296621D01*
X-32528Y296154D01*
X-32028Y295688D01*
G01X-31028Y287354D02*
Y285754D01*
G01X-29945Y286621D02*
X-32112D01*
G01X-32862Y282721D02*
X-27695Y280321D01*
G01X-31028Y277288D02*
Y275554D01*
G01X-28528Y272588D02*
X-28028Y272188D01*
X-27778Y271721D01*
X-27695Y271188D01*
X-27862Y270521D01*
X-28278Y270054D01*
X-28778Y269921D01*
X-29278Y269988D01*
X-29695Y270254D01*
X-30528Y271588D01*
X-31112Y272188D01*
X-31945Y272588D01*
X-32695Y272721D01*
Y269921D01*
G01Y263121D02*
X-29362D01*
G01X-30278D02*
X-29862Y262921D01*
X-29528Y262588D01*
X-29362Y262121D01*
X-29528Y261654D01*
X-29862Y261321D01*
X-30278Y261121D01*
X-32695D01*
G01X-30278D02*
X-29862Y260921D01*
X-29528Y260588D01*
X-29362Y260121D01*
X-29528Y259654D01*
X-29862Y259321D01*
X-30362Y259121D01*
X-32695D01*
G01X-29362Y256021D02*
X-32695D01*
G01X-28028D02*
X-27945Y256154D01*
X-27778D01*
X-27695Y256021D01*
X-27778Y255888D01*
X-27945D01*
X-28028Y256021D01*
G01X-32695Y250921D02*
X-27695D01*
G01X-32112Y246821D02*
X-32445Y246488D01*
X-32695Y246021D01*
Y245621D01*
X-32528Y245221D01*
X-32278Y244954D01*
X-31945Y244821D01*
X-31445Y244888D01*
X-31195Y245154D01*
X-30695Y246354D01*
X-30112Y246621D01*
X-29695Y246488D01*
X-29445Y246221D01*
X-29362Y245821D01*
X-29445Y245421D01*
X-29695Y245021D01*
G01X-35802Y333740D02*
X-36219Y333207D01*
X-36469Y332607D01*
Y332073D01*
X-36219Y331540D01*
X-35802Y331140D01*
X-35219Y330940D01*
X-34636Y331073D01*
X-34136Y331407D01*
X-33802Y332007D01*
X-33636Y332807D01*
X-33302Y333273D01*
X-32719Y333473D01*
X-32136Y333340D01*
X-31719Y333007D01*
X-31469Y332540D01*
Y332073D01*
X-31636Y331607D01*
X-32052Y331207D01*
G01X-36469Y327240D02*
X-31469D01*
G01X-33136Y322140D02*
X-36469D01*
G01X-31802D02*
X-31719Y322273D01*
X-31552D01*
X-31469Y322140D01*
X-31552Y322007D01*
X-31719D01*
X-31802Y322140D01*
G01X-31469Y317040D02*
X-36469D01*
G01X-33136Y317973D02*
Y316107D01*
G01X-24163Y325771D02*
X-26163Y327771D01*
Y323771D01*
X-24163Y325771D01*
X-32163D01*
G01X-15283Y336262D02*
X-17283Y338262D01*
Y334262D01*
X-15283Y336262D01*
X-27283D01*
G01X-23622Y450275D02*
Y319567D01*
G01X-39978Y419421D02*
X-40395Y418888D01*
X-40645Y418288D01*
Y417754D01*
X-40395Y417221D01*
X-39978Y416821D01*
X-39395Y416621D01*
X-38812Y416754D01*
X-38312Y417088D01*
X-37978Y417688D01*
X-37812Y418488D01*
X-37478Y418954D01*
X-36895Y419154D01*
X-36312Y419021D01*
X-35895Y418688D01*
X-35645Y418221D01*
Y417754D01*
X-35812Y417288D01*
X-36228Y416888D01*
G01X-40645Y412921D02*
X-35645D01*
G01X-37312Y407821D02*
X-40645D01*
G01X-35978D02*
X-35895Y407954D01*
X-35728D01*
X-35645Y407821D01*
X-35728Y407688D01*
X-35895D01*
X-35978Y407821D01*
G01X-35645Y402721D02*
X-40645D01*
G01X-37312Y403654D02*
Y401788D01*
G01X36558Y415180D02*
Y354662D01*
X-18448D01*
Y415180D01*
X36558D01*
G01X-28448Y384921D02*
X-18748D01*
X-23748Y379921D01*
Y389921D01*
X-18748Y384921D01*
G01X-23445Y414921D02*
X-25945Y417421D01*
Y412421D01*
X-23445Y414921D01*
X-35945D01*
G01X1972441Y626378D02*
X-19685D01*
G01X1972441D02*
X-19685D01*
G01X1972441D02*
X-19685D01*
G01X1972441D02*
X-19685D01*
G01D02*
G03X-23622Y622441I0J-3937D01*
G01X-19685Y626378D02*
G03X-23622Y622441I0J-3937D01*
G01X-19685Y626378D02*
G03X-23622Y622441I0J-3937D01*
G01X-19685Y626378D02*
G03X-23622Y622441I0J-3937D01*
G01X-19685Y634252D02*
X-7874D01*
G01X-19685D02*
X-7874D01*
G01X-23622Y661811D02*
Y638189D01*
G01Y661811D02*
Y638189D01*
G01D02*
G03X-19685Y634252I3937J0D01*
G01X-23622Y638189D02*
G03X-19685Y634252I3937J0D01*
G01X1972441Y665748D02*
X-19685D01*
G01X1972441D02*
X-19685D01*
G01D02*
G03X-23622Y661811I0J-3937D01*
G01X-19685Y665748D02*
G03X-23622Y661811I0J-3937D01*
G01X-7874Y-31496D02*
G03Y-23622I0J3937D01*
G01Y-31496D02*
G03Y-23622I0J3937D01*
G01X22835D02*
G03Y-31496I0J-3937D01*
G01X137795D02*
X22835D01*
G01X137795D02*
X22835D01*
G01Y-23622D02*
G03Y-31496I0J-3937D01*
G01X-14811Y230992D02*
Y222181D01*
X-1874D01*
Y210181D01*
X-14811D01*
Y201370D01*
X38433D01*
Y230992D01*
X-14811D01*
G01Y340126D02*
Y331315D01*
X-1874D01*
Y319315D01*
X-14811D01*
Y310504D01*
X38433D01*
Y340126D01*
X-14811D01*
G01X0Y616535D02*
G03Y604724I0J-5905D01*
G01Y616535D02*
G03Y604724I0J-5905D01*
G01Y616535D02*
X2646D01*
G01X2644D02*
X0D01*
G01Y604724D02*
X2644D01*
G01X2646D02*
X0D01*
G01X2646D02*
X0D01*
G01D02*
X2644D01*
G01Y616535D02*
X0D01*
G01D02*
X2646D01*
G01X0D02*
G03Y604724I0J-5905D01*
G01Y616535D02*
G03Y604724I0J-5905D01*
G01X2646Y616535D02*
G03X7595Y618285I0J7874D01*
G01X2644Y616535D02*
G03X7593Y618285I0J7874D01*
G01X2644Y616535D02*
G03X7593Y618285I0J7874D01*
G01X7595Y602975D02*
G03X2646Y604724I-4948J-6125D01*
G01X7593Y602975D02*
G03X2644Y604724I-4948J-6125D01*
G01X7593Y602975D02*
G03X2644Y604724I-4948J-6125D01*
G01X7593Y602975D02*
G03X2644Y604724I-4948J-6125D01*
G01X7593Y602975D02*
G03X2644Y604724I-4948J-6125D01*
G01X7595Y602975D02*
G03X2646Y604724I-4948J-6125D01*
G01X2644Y616535D02*
G03X7593Y618285I0J7874D01*
G01X2644Y616535D02*
G03X7593Y618285I0J7874D01*
G01X2646Y616535D02*
G03X7595Y618285I0J7874D01*
G01Y602975D02*
G03Y618285I6186J7655D01*
G01X7593Y602975D02*
G03Y618285I6187J7655D01*
G01Y602975D02*
G03Y618285I6187J7655D01*
G01Y602975D02*
G03Y618285I6187J7655D01*
G01Y602975D02*
G03Y618285I6187J7655D01*
G01X7595Y602975D02*
G03Y618285I6186J7655D01*
G01X-7874Y626378D02*
G03Y634252I0J3937D01*
G01Y626378D02*
G03Y634252I0J3937D01*
G01X22835D02*
G03Y626378I0J-3937D01*
G01Y634252D02*
X137795D01*
G01X22835D02*
X137795D01*
G01X22835D02*
G03Y626378I0J-3937D01*
G01X168504Y-23622D02*
G03Y-31496I0J-3937D01*
G01X137795D02*
G03Y-23622I0J3937D01*
G01X341732Y-31496D02*
X168504D01*
G01X341732D02*
X168504D01*
G01X137795D02*
G03Y-23622I0J3937D01*
G01X168504D02*
G03Y-31496I0J-3937D01*
G01Y634252D02*
G03Y626378I0J-3937D01*
G01X137795D02*
G03Y634252I0J3937D01*
G01X168504D02*
X341732D01*
G01X168504D02*
X341732D01*
G01X137795Y626378D02*
G03Y634252I0J3937D01*
G01X168504D02*
G03Y626378I0J-3937D01*
G01X341732Y-31496D02*
G03Y-23622I0J3937D01*
G01Y-31496D02*
G03Y-23622I0J3937D01*
G01Y626378D02*
G03Y634252I0J3937D01*
G01Y626378D02*
G03Y634252I0J3937D01*
G01X372441Y-23622D02*
G03Y-31496I0J-3937D01*
G01X529921D02*
X372441D01*
G01X529921D02*
X372441D01*
G01Y-23622D02*
G03Y-31496I0J-3937D01*
G01Y634252D02*
G03Y626378I0J-3937D01*
G01Y634252D02*
X529921D01*
G01X372441D02*
X529921D01*
G01X372441D02*
G03Y626378I0J-3937D01*
G01X529921Y-31496D02*
G03Y-23622I0J3937D01*
G01Y-31496D02*
G03Y-23622I0J3937D01*
G01Y626378D02*
G03Y634252I0J3937D01*
G01Y626378D02*
G03Y634252I0J3937D01*
G01X560630Y-23622D02*
G03Y-31496I0J-3937D01*
G01X788976D02*
X560630D01*
G01X788976D02*
X560630D01*
G01Y-23622D02*
G03Y-31496I0J-3937D01*
G01Y634252D02*
G03Y626378I0J-3937D01*
G01Y634252D02*
X788976D01*
G01X560630D02*
X788976D01*
G01X560630D02*
G03Y626378I0J-3937D01*
G01X684760Y-15529D02*
G03Y-219I6187J7655D01*
G01X684759Y-15529D02*
G03X679809Y-13780I-4948J-6125D01*
G01X679811Y-1969D02*
G03X684760Y-219I0J7874D01*
G01X677165Y-1969D02*
X679811D01*
G01X677165D02*
G03Y-13780I0J-5906D01*
G01D02*
X679809D01*
G01X684760Y602975D02*
G03Y618285I6187J7655D01*
G01X684759Y602975D02*
G03Y618285I6186J7655D01*
G01Y602975D02*
G03Y618285I6186J7655D01*
G01Y602975D02*
G03Y618285I6186J7655D01*
G01Y602975D02*
G03Y618285I6186J7655D01*
G01X684760Y602975D02*
G03Y618285I6187J7655D01*
G01X679811Y616535D02*
G03X684760Y618285I0J7874D01*
G01X679809Y616535D02*
G03X684759Y618285I0J7874D01*
G01X679809Y616535D02*
G03X684759Y618285I0J7874D01*
G01X684760Y602975D02*
G03X679811Y604724I-4948J-6125D01*
G01X684759Y602975D02*
G03X679809Y604724I-4948J-6125D01*
G01X684759Y602975D02*
G03X679809Y604724I-4948J-6125D01*
G01X684759Y602975D02*
G03X679809Y604724I-4948J-6125D01*
G01X684759Y602975D02*
G03X679809Y604724I-4948J-6125D01*
G01X684760Y602975D02*
G03X679811Y604724I-4948J-6125D01*
G01X679809Y616535D02*
G03X684759Y618285I0J7874D01*
G01X679809Y616535D02*
G03X684759Y618285I0J7874D01*
G01X679811Y616535D02*
G03X684760Y618285I0J7874D01*
G01X677165Y616535D02*
X679811D01*
G01X677165D02*
G03Y604724I0J-5905D01*
G01D02*
X679809D01*
G01X788976Y-31496D02*
G03Y-23622I0J3937D01*
G01Y-31496D02*
G03Y-23622I0J3937D01*
G01X819685D02*
G03Y-31496I0J-3937D01*
G01X975591D02*
X819685D01*
G01X975591D02*
X819685D01*
G01Y-23622D02*
G03Y-31496I0J-3937D01*
G01X788976Y626378D02*
G03Y634252I0J3937D01*
G01Y626378D02*
G03Y634252I0J3937D01*
G01X819685D02*
G03Y626378I0J-3937D01*
G01Y634252D02*
X975591D01*
G01X819685D02*
X975591D01*
G01X819685D02*
G03Y626378I0J-3937D01*
G01X975591Y-31496D02*
G03Y-23622I0J3937D01*
G01Y-31496D02*
G03Y-23622I0J3937D01*
G01X1006299D02*
G03Y-31496I0J-3937D01*
G01X1162205D02*
X1006299D01*
G01X1162205D02*
X1006299D01*
G01Y-23622D02*
G03Y-31496I0J-3937D01*
G01Y634252D02*
X1162205D01*
G01X1006299D02*
X1162205D01*
G01X975591Y626378D02*
G03Y634252I0J3937D01*
G01Y626378D02*
G03Y634252I0J3937D01*
G01X1006299D02*
G03Y626378I0J-3937D01*
G01Y634252D02*
G03Y626378I0J-3937D01*
G01X1162205Y-31496D02*
G03Y-23622I0J3937D01*
G01Y-31496D02*
G03Y-23622I0J3937D01*
G01X1192913D02*
G03Y-31496I0J-3937D01*
G01X1398425D02*
X1192913D01*
G01X1398425D02*
X1192913D01*
G01Y-23622D02*
G03Y-31496I0J-3937D01*
G01Y634252D02*
X1394488D01*
G01X1192913D02*
X1394488D01*
G01X1162205Y626378D02*
G03Y634252I0J3937D01*
G01Y626378D02*
G03Y634252I0J3937D01*
G01X1192913D02*
G03Y626378I0J-3937D01*
G01Y634252D02*
G03Y626378I0J-3937D01*
G01X1398425Y-31496D02*
G03Y-23622I0J3937D01*
G01Y-31496D02*
G03Y-23622I0J3937D01*
G01X1405512Y-1968D02*
G03Y-13779I0J-5906D01*
G01Y-1968D02*
G03Y-13779I0J-5906D01*
G01Y-1968D02*
G03Y-13779I0J-5906D01*
G01Y-1968D02*
G03Y-13779I0J-5906D01*
G01X1394488Y626378D02*
G03Y634252I0J3937D01*
G01Y626378D02*
G03Y634252I0J3937D01*
G01X1405512Y616535D02*
G03Y604724I0J-5905D01*
G01Y616535D02*
G03Y604724I0J-5905D01*
G01Y616535D02*
G03Y604724I0J-5905D01*
G01Y616535D02*
G03Y604724I0J-5905D01*
G01X1429134Y-23622D02*
G03Y-31496I0J-3937D01*
G01X1851181D02*
X1429134D01*
G01X1851181D02*
X1429134D01*
G01Y-23622D02*
G03Y-31496I0J-3937D01*
G01X1413107Y-15529D02*
G03Y-218I6186J7655D01*
G01X1413105Y-15529D02*
G03Y-218I6186J7655D01*
G01Y-15529D02*
G03Y-218I6186J7655D01*
G01Y-15529D02*
G03Y-218I6186J7655D01*
G01Y-15529D02*
G03Y-218I6186J7655D01*
G01X1413107Y-15529D02*
G03Y-218I6186J7655D01*
G01X1408157Y-1968D02*
G03X1413107Y-218I1J7874D01*
G01X1408156Y-1968D02*
G03X1413105Y-218I0J7874D01*
G01X1408156Y-1968D02*
G03X1413105Y-218I0J7874D01*
G01X1408156Y-1968D02*
G03X1413105Y-218I0J7874D01*
G01X1408156Y-1968D02*
G03X1413105Y-218I0J7874D01*
G01X1408157Y-1968D02*
G03X1413107Y-218I1J7874D01*
G01Y-15529D02*
G03X1408157Y-13779I-4949J-6124D01*
G01X1413105Y-15529D02*
G03X1408156Y-13779I-4949J-6124D01*
G01X1413105Y-15529D02*
G03X1408156Y-13779I-4949J-6124D01*
G01X1413105Y-15529D02*
G03X1408156Y-13779I-4949J-6124D01*
G01X1413105Y-15529D02*
G03X1408156Y-13779I-4949J-6124D01*
G01X1413107Y-15529D02*
G03X1408157Y-13779I-4949J-6124D01*
G01X1405512D02*
X1408156D01*
G01X1408157D02*
X1405512D01*
G01X1408157D02*
X1405512D01*
G01D02*
X1408156D01*
G01X1405512Y-1968D02*
X1408157D01*
G01X1408156D02*
X1405512D01*
G01X1408156D02*
X1405512D01*
G01D02*
X1408157D01*
G01X1425197Y634252D02*
X1851181D01*
G01X1425197D02*
X1851181D01*
G01X1425197D02*
G03Y626378I0J-3937D01*
G01Y634252D02*
G03Y626378I0J-3937D01*
G01X1408157Y616535D02*
G03X1413107Y618285I1J7874D01*
G01X1408156Y616535D02*
G03X1413105Y618285I0J7874D01*
G01X1408156Y616535D02*
G03X1413105Y618285I0J7874D01*
G01X1413107Y602975D02*
G03Y618285I6186J7655D01*
G01X1413105Y602975D02*
G03Y618285I6187J7655D01*
G01Y602975D02*
G03Y618285I6187J7655D01*
G01X1413107Y602975D02*
G03X1408157Y604724I-4948J-6125D01*
G01X1413105Y602975D02*
G03X1408156Y604724I-4948J-6125D01*
G01X1413105Y602975D02*
G03X1408156Y604724I-4948J-6125D01*
G01X1413105Y602975D02*
G03X1408156Y604724I-4948J-6125D01*
G01X1413105Y602975D02*
G03X1408156Y604724I-4948J-6125D01*
G01X1413107Y602975D02*
G03X1408157Y604724I-4948J-6125D01*
G01X1413105Y602975D02*
G03Y618285I6187J7655D01*
G01Y602975D02*
G03Y618285I6187J7655D01*
G01X1413107Y602975D02*
G03Y618285I6186J7655D01*
G01X1408156Y616535D02*
G03X1413105Y618285I0J7874D01*
G01X1408156Y616535D02*
G03X1413105Y618285I0J7874D01*
G01X1408157Y616535D02*
G03X1413107Y618285I1J7874D01*
G01X1405512Y616535D02*
X1408157D01*
G01X1408156D02*
X1405512D01*
G01Y604724D02*
X1408156D01*
G01X1408157D02*
X1405512D01*
G01X1408157D02*
X1405512D01*
G01D02*
X1408156D01*
G01Y616535D02*
X1405512D01*
G01D02*
X1408157D01*
G01X1685866Y267244D02*
X1883780D01*
G01X1685866D02*
X1883780D01*
G01X1685866D02*
X1883780D01*
G01X1685866D02*
X1883780D01*
G01X1681929Y271181D02*
G03X1685866Y267244I3937J0D01*
G01X1681929Y271181D02*
G03X1685866Y267244I3937J0D01*
G01X1681929Y271181D02*
G03X1685866Y267244I3937J0D01*
G01X1681929Y271181D02*
G03X1685866Y267244I3937J0D01*
G01X1681929Y428661D02*
Y271181D01*
G01Y428661D02*
Y271181D01*
G01Y428661D02*
Y271181D01*
G01Y428661D02*
Y271181D01*
G01X1685866Y432598D02*
G03X1681929Y428661I0J-3937D01*
G01X1685866Y432598D02*
G03X1681929Y428661I0J-3937D01*
G01X1972441Y432598D02*
X1685866D01*
G01X1972441D02*
X1685866D01*
G01X1972441D02*
X1685866D01*
G01X1972441D02*
X1685866D01*
G01D02*
G03X1681929Y428661I0J-3937D01*
G01X1685866Y432598D02*
G03X1681929Y428661I0J-3937D01*
G01X1851181Y-31496D02*
G03Y-23622I0J3937D01*
G01Y-31496D02*
G03Y-23622I0J3937D01*
G01X1881890D02*
G03Y-31496I0J-3937D01*
G01X1972441D02*
X1881890D01*
G01X1972441D02*
X1881890D01*
G01Y-23622D02*
G03Y-31496I0J-3937D01*
G01X1861926Y-15529D02*
G03X1856976Y-13780I-4948J-6125D01*
G01X1861924Y-15529D02*
G03X1856975Y-13780I-4948J-6125D01*
G01X1861924Y-15529D02*
G03X1856975Y-13780I-4948J-6125D01*
G01X1861924Y-15529D02*
G03X1856975Y-13780I-4948J-6125D01*
G01X1861924Y-15529D02*
G03X1856975Y-13780I-4948J-6125D01*
G01X1861926Y-15529D02*
G03X1856976Y-13780I-4948J-6125D01*
G01Y-1969D02*
G03X1861926Y-219I0J7874D01*
G01X1856975Y-1969D02*
G03X1861924Y-219I0J7874D01*
G01X1856975Y-1969D02*
G03X1861924Y-219I0J7874D01*
G01X1861926Y-15529D02*
G03Y-219I6186J7655D01*
G01X1861924Y-15529D02*
G03Y-219I6186J7655D01*
G01Y-15529D02*
G03Y-219I6186J7655D01*
G01Y-15529D02*
G03Y-219I6186J7655D01*
G01Y-15529D02*
G03Y-219I6186J7655D01*
G01X1861926Y-15529D02*
G03Y-219I6186J7655D01*
G01X1856975Y-1969D02*
G03X1861924Y-219I0J7874D01*
G01X1856975Y-1969D02*
G03X1861924Y-219I0J7874D01*
G01X1856976Y-1969D02*
G03X1861926Y-219I0J7874D01*
G01X1854331Y-1969D02*
G03Y-13780I0J-5906D01*
G01Y-1969D02*
G03Y-13780I0J-5906D01*
G01D02*
X1856975D01*
G01X1856976D02*
X1854331D01*
G01X1856976D02*
X1854331D01*
G01D02*
X1856975D01*
G01X1854331Y-1969D02*
G03Y-13780I0J-5906D01*
G01Y-1969D02*
G03Y-13780I0J-5906D01*
G01Y-1969D02*
X1856976D01*
G01X1856975D02*
X1854331D01*
G01X1856975D02*
X1854331D01*
G01D02*
X1856976D01*
G01X1891654Y246772D02*
X1972441D01*
G01X1891654D02*
X1972441D01*
G01X1891654D02*
X1972441D01*
G01X1891654D02*
X1972441D01*
G01X1887717Y250709D02*
G03X1891654Y246772I3937J0D01*
G01X1887717Y250709D02*
G03X1891654Y246772I3937J0D01*
G01X1887717Y263307D02*
Y250709D01*
G01Y263307D02*
Y250709D01*
G01Y263307D02*
Y250709D01*
G01Y263307D02*
Y250709D01*
G01D02*
G03X1891654Y246772I3937J0D01*
G01X1887717Y250709D02*
G03X1891654Y246772I3937J0D01*
G01X1887717Y263307D02*
G03X1883780Y267244I-3937J0D01*
G01X1887717Y263307D02*
G03X1883780Y267244I-3937J0D01*
G01X1887717Y263307D02*
G03X1883780Y267244I-3937J0D01*
G01X1887717Y263307D02*
G03X1883780Y267244I-3937J0D01*
G01X1881890Y634252D02*
G03Y626378I0J-3937D01*
G01Y634252D02*
X1972441D01*
G01X1881890D02*
X1972441D01*
G01X1881890D02*
G03Y626378I0J-3937D01*
G01X1851181D02*
G03Y634252I0J3937D01*
G01Y626378D02*
G03Y634252I0J3937D01*
G01X1856976Y616535D02*
G03X1861926Y618285I0J7874D01*
G01X1856975Y616535D02*
G03X1861924Y618285I0J7874D01*
G01X1856975Y616535D02*
G03X1861924Y618285I0J7874D01*
G01X1861926Y602975D02*
G03Y618285I6186J7655D01*
G01X1861924Y602975D02*
G03Y618285I6186J7655D01*
G01Y602975D02*
G03Y618285I6186J7655D01*
G01Y602975D02*
G03Y618285I6186J7655D01*
G01Y602975D02*
G03Y618285I6186J7655D01*
G01X1861926Y602975D02*
G03Y618285I6186J7655D01*
G01X1856975Y616535D02*
G03X1861924Y618285I0J7874D01*
G01X1856975Y616535D02*
G03X1861924Y618285I0J7874D01*
G01X1856976Y616535D02*
G03X1861926Y618285I0J7874D01*
G01Y602975D02*
G03X1856976Y604724I-4948J-6125D01*
G01X1861924Y602975D02*
G03X1856975Y604724I-4948J-6125D01*
G01X1861924Y602975D02*
G03X1856975Y604724I-4948J-6125D01*
G01X1861924Y602975D02*
G03X1856975Y604724I-4948J-6125D01*
G01X1861924Y602975D02*
G03X1856975Y604724I-4948J-6125D01*
G01X1861926Y602975D02*
G03X1856976Y604724I-4948J-6125D01*
G01X1854331Y616535D02*
G03Y604724I0J-5905D01*
G01Y616535D02*
G03Y604724I0J-5905D01*
G01D02*
X1856975D01*
G01X1856976D02*
X1854331D01*
G01X1856976D02*
X1854331D01*
G01D02*
X1856975D01*
G01X1854331Y616535D02*
G03Y604724I0J-5905D01*
G01Y616535D02*
G03Y604724I0J-5905D01*
G01Y616535D02*
X1856976D01*
G01X1856975D02*
X1854331D01*
G01X1856975D02*
X1854331D01*
G01D02*
X1856976D01*
G01X1972441Y-11811D02*
X1906890D01*
G01X1904921Y-9843D02*
G03X1906890Y-11811I1969J1D01*
G01X1904921Y53150D02*
Y-9843D01*
G01X1972441Y-11811D02*
X1906890D01*
G01X1904921Y-9843D02*
G03X1906890Y-11811I1969J1D01*
G01X1904921Y53150D02*
Y-9843D01*
G01X1923071Y53150D02*
Y-9843D01*
G01X1940787Y-3937D02*
X1972441D01*
G01X1940787D02*
G03X1938819Y-5906I0J-1968D01*
G01Y-9843D02*
Y-5906D01*
G01Y-9843D02*
G03X1940787Y-11811I1968J0D01*
G01X1921102D02*
G03X1923071Y-9843I0J1969D01*
G01X1925089Y13754D02*
X1925506Y14287D01*
X1925756Y14887D01*
Y15421D01*
X1925506Y15954D01*
X1925089Y16354D01*
X1924506Y16554D01*
X1923923Y16421D01*
X1923423Y16087D01*
X1923089Y15487D01*
X1922923Y14687D01*
X1922589Y14221D01*
X1922006Y14021D01*
X1921423Y14154D01*
X1921006Y14487D01*
X1920756Y14954D01*
Y15421D01*
X1920923Y15887D01*
X1921339Y16287D01*
G01X1925756Y20254D02*
X1920756D01*
G01X1922423Y25354D02*
X1925756D01*
G01X1921089D02*
X1921006Y25221D01*
X1920839D01*
X1920756Y25354D01*
X1920839Y25487D01*
X1921006D01*
X1921089Y25354D01*
G01X1920756Y30454D02*
X1925756D01*
G01X1922423Y29521D02*
Y31387D01*
G01X1954256Y-21846D02*
X1949256D01*
X1950256Y-22646D01*
G01X1954256D02*
Y-21046D01*
G01X1922256Y21654D02*
X1905256D01*
Y21154D01*
X1907756Y18654D01*
Y24654D01*
X1905256Y22154D01*
Y21654D01*
G01X1949256Y-24846D02*
X1956256D01*
Y-20346D01*
X1952756Y-17846D01*
X1949256Y-20346D01*
Y-24846D01*
G01X1961406Y-17710D02*
Y-11810D01*
X1944106D01*
Y-17710D01*
X1961406D01*
G01X1976339Y66654D02*
Y55119D01*
X1906851D01*
G03X1904882Y53150I0J-1969D01*
G01Y-9842D01*
G03X1906851Y-11811I1969J0D01*
G01X1976339D01*
Y-23346D01*
G01X1906890Y55118D02*
G03X1904921Y53150I0J-1969D01*
G01X1972441Y55118D02*
X1906890D01*
G01X1972441D02*
X1906890D01*
G01X1972441D02*
X1906890D01*
G01X1972441D02*
X1906890D01*
G01D02*
G03X1904921Y53150I0J-1969D01*
G01X1923071D02*
G03X1921102Y55118I-1969J-1D01*
G01X1940787D02*
G03X1938819Y53150I0J-1968D01*
G01Y49213D02*
Y53150D01*
G01Y49213D02*
G03X1940787Y47244I1968J-1D01*
G01X1972441D02*
X1940787D01*
G01X1954256Y65654D02*
X1949256D01*
X1950256Y64854D01*
G01X1954256D02*
Y66454D01*
G01X1956256Y68154D02*
X1949256D01*
Y63654D01*
X1952756Y61154D01*
X1956256Y63654D01*
Y68154D01*
G01X1961406Y61018D02*
Y55118D01*
X1944106D01*
Y61018D01*
X1961406D01*
G01X1942950Y214044D02*
X1943533Y214444D01*
X1943867Y214978D01*
X1943950Y215578D01*
X1943867Y216111D01*
X1943450Y216644D01*
X1942950Y216978D01*
X1942450Y217044D01*
X1941867Y216911D01*
X1941450Y216444D01*
X1941283Y215978D01*
Y215378D01*
G01Y215978D02*
X1941033Y216378D01*
X1940617Y216711D01*
X1940117Y216844D01*
X1939617Y216711D01*
X1939200Y216378D01*
X1938950Y215778D01*
X1939033Y215178D01*
X1939367Y214578D01*
G01X1939783Y219344D02*
X1939283Y219744D01*
X1939033Y220211D01*
X1938950Y220744D01*
X1939117Y221411D01*
X1939533Y221878D01*
X1940033Y222011D01*
X1940533Y221944D01*
X1940950Y221678D01*
X1941783Y220344D01*
X1942367Y219744D01*
X1943200Y219344D01*
X1943950Y219211D01*
Y222011D01*
G01Y224311D02*
X1938950Y227111D01*
G01Y224311D02*
X1943950Y227111D01*
G01X1939783Y229544D02*
X1939283Y229944D01*
X1939033Y230411D01*
X1938950Y230944D01*
X1939117Y231611D01*
X1939533Y232078D01*
X1940033Y232211D01*
X1940533Y232144D01*
X1940950Y231878D01*
X1941783Y230544D01*
X1942367Y229944D01*
X1943200Y229544D01*
X1943950Y229411D01*
Y232211D01*
G01X1938950Y235911D02*
X1939117Y235378D01*
X1939533Y234978D01*
X1940033Y234711D01*
X1940700Y234511D01*
X1941450Y234444D01*
X1942200Y234511D01*
X1942867Y234711D01*
X1943367Y234978D01*
X1943783Y235378D01*
X1943950Y235911D01*
X1943783Y236444D01*
X1943367Y236844D01*
X1942867Y237111D01*
X1942200Y237311D01*
X1941450Y237378D01*
X1940700Y237311D01*
X1940033Y237111D01*
X1939533Y236844D01*
X1939117Y236444D01*
X1938950Y235911D01*
G01X1976378Y-35433D02*
G03X1972441Y-31496I-3937J0D01*
G01X1976378Y-59055D02*
Y-35433D01*
G01Y-59055D02*
Y-35433D01*
G01D02*
G03X1972441Y-31496I-3937J0D01*
G01Y-62992D02*
G03X1976378Y-59055I0J3937D01*
G01X1972441Y-62992D02*
G03X1976378Y-59055I0J3937D01*
G01X1990256Y-30313D02*
X1985256D01*
Y-28979D01*
X1985506Y-28446D01*
X1985839Y-28046D01*
X1986339Y-27713D01*
X1986923Y-27446D01*
X1987756Y-27379D01*
X1988589Y-27446D01*
X1989173Y-27713D01*
X1989673Y-28046D01*
X1990006Y-28446D01*
X1990256Y-28979D01*
Y-30313D01*
G01Y-23746D02*
X1990173Y-24146D01*
X1989839Y-24546D01*
X1989256Y-24813D01*
X1988589Y-24946D01*
X1987923Y-24813D01*
X1987339Y-24546D01*
X1987006Y-24146D01*
X1986923Y-23746D01*
X1987006Y-23346D01*
X1987339Y-22946D01*
X1987923Y-22679D01*
X1988589Y-22613D01*
X1989256Y-22679D01*
X1989839Y-22946D01*
X1990173Y-23346D01*
X1990256Y-23746D01*
G01Y-19779D02*
X1986923D01*
G01X1987756D02*
X1987339Y-19513D01*
X1987006Y-19113D01*
X1986923Y-18579D01*
X1987006Y-18113D01*
X1987339Y-17713D01*
X1987923Y-17513D01*
X1990256D01*
G01X1986923Y-13546D02*
X1985881Y-12879D01*
X1985256D01*
Y-13379D01*
X1985881D01*
Y-12879D01*
G01X1985256Y-8446D02*
X1990256D01*
G01X1986923Y-9379D02*
Y-7513D01*
G01X1990256Y421D02*
X1985256D01*
Y2087D01*
X1985506Y2621D01*
X1985839Y2954D01*
X1986506Y3087D01*
X1987173Y2954D01*
X1987589Y2554D01*
X1987839Y2087D01*
Y421D01*
G01Y2087D02*
X1990256Y3087D01*
G01X1988006Y5854D02*
Y7987D01*
X1987423Y7787D01*
X1987089Y7454D01*
X1986923Y6987D01*
X1987006Y6521D01*
X1987256Y6121D01*
X1987839Y5854D01*
X1988339Y5721D01*
X1988839D01*
X1989339Y5854D01*
X1989839Y6187D01*
X1990173Y6587D01*
X1990256Y7054D01*
X1990089Y7521D01*
X1989589Y7987D01*
G01X1985256Y13154D02*
X1990256D01*
G01X1989506D02*
X1989923Y12887D01*
X1990173Y12487D01*
X1990256Y12021D01*
X1990089Y11487D01*
X1989673Y11087D01*
X1989173Y10821D01*
X1988589Y10754D01*
X1988006Y10821D01*
X1987506Y11087D01*
X1987089Y11487D01*
X1986923Y12021D01*
X1987006Y12487D01*
X1987173Y12821D01*
X1987506Y13154D01*
G01X1986923Y15921D02*
X1989256D01*
X1989839Y16187D01*
X1990173Y16587D01*
X1990256Y17054D01*
X1990173Y17521D01*
X1989839Y17921D01*
X1989256Y18187D01*
G01X1990256D02*
X1986923D01*
G01X1987339Y23221D02*
X1987006Y22754D01*
X1986923Y22354D01*
X1987089Y21821D01*
X1987423Y21421D01*
X1988006Y21154D01*
X1988589Y21087D01*
X1989173Y21154D01*
X1989673Y21421D01*
X1990089Y21821D01*
X1990256Y22354D01*
X1990089Y22821D01*
X1989756Y23221D01*
G01X1988006Y26254D02*
Y28387D01*
X1987423Y28187D01*
X1987089Y27854D01*
X1986923Y27387D01*
X1987006Y26921D01*
X1987256Y26521D01*
X1987839Y26254D01*
X1988339Y26121D01*
X1988839D01*
X1989339Y26254D01*
X1989839Y26587D01*
X1990173Y26987D01*
X1990256Y27454D01*
X1990089Y27921D01*
X1989589Y28387D01*
G01X1990256Y36121D02*
X1985256D01*
Y37721D01*
X1985506Y38254D01*
X1986089Y38654D01*
X1986756Y38787D01*
X1987423Y38654D01*
X1987923Y38321D01*
X1988173Y37721D01*
Y36121D01*
G01X1990256Y43754D02*
X1986923D01*
G01X1987506D02*
X1987173Y43487D01*
X1987006Y43087D01*
X1986923Y42621D01*
X1987089Y42154D01*
X1987423Y41754D01*
X1987923Y41487D01*
X1988589Y41354D01*
X1989256Y41487D01*
X1989756Y41754D01*
X1990089Y42154D01*
X1990256Y42621D01*
X1990173Y43087D01*
X1989923Y43487D01*
X1989589Y43754D01*
G01X1985256Y48854D02*
X1990256D01*
G01X1989506D02*
X1989923Y48587D01*
X1990173Y48187D01*
X1990256Y47721D01*
X1990089Y47187D01*
X1989673Y46787D01*
X1989173Y46521D01*
X1988589Y46454D01*
X1988006Y46521D01*
X1987506Y46787D01*
X1987089Y47187D01*
X1986923Y47721D01*
X1987006Y48187D01*
X1987173Y48521D01*
X1987506Y48854D01*
G01X1989589Y56454D02*
X1990006Y56987D01*
X1990256Y57587D01*
Y58121D01*
X1990006Y58654D01*
X1989589Y59054D01*
X1989006Y59254D01*
X1988423Y59121D01*
X1987923Y58787D01*
X1987589Y58187D01*
X1987423Y57387D01*
X1987089Y56921D01*
X1986506Y56721D01*
X1985923Y56854D01*
X1985506Y57187D01*
X1985256Y57654D01*
Y58121D01*
X1985423Y58587D01*
X1985839Y58987D01*
G01X1986923Y62954D02*
X1990256D01*
G01X1985589D02*
X1985506Y62821D01*
X1985339D01*
X1985256Y62954D01*
X1985339Y63087D01*
X1985506D01*
X1985589Y62954D01*
G01X1986923Y67054D02*
Y69054D01*
X1990256Y67054D01*
Y69054D01*
G01X1988006Y72154D02*
Y74287D01*
X1987423Y74087D01*
X1987089Y73754D01*
X1986923Y73287D01*
X1987006Y72821D01*
X1987256Y72421D01*
X1987839Y72154D01*
X1988339Y72021D01*
X1988839D01*
X1989339Y72154D01*
X1989839Y72487D01*
X1990173Y72887D01*
X1990256Y73354D01*
X1990089Y73821D01*
X1989589Y74287D01*
G01X1990423Y78254D02*
X1990339Y78121D01*
X1990173D01*
X1990089Y78254D01*
X1990173Y78387D01*
X1990339D01*
X1990423Y78254D01*
G01X1985256Y-30379D02*
X1980256D01*
X1985256Y-27313D01*
X1980256D01*
G01X1985256Y-23746D02*
X1985173Y-24146D01*
X1984839Y-24546D01*
X1984256Y-24813D01*
X1983589Y-24946D01*
X1982923Y-24813D01*
X1982339Y-24546D01*
X1982006Y-24146D01*
X1981923Y-23746D01*
X1982006Y-23346D01*
X1982339Y-22946D01*
X1982923Y-22679D01*
X1983589Y-22613D01*
X1984256Y-22679D01*
X1984839Y-22946D01*
X1985173Y-23346D01*
X1985256Y-23746D01*
G01X1980256Y-18646D02*
X1985256D01*
G01X1981923Y-19579D02*
Y-17713D01*
G01X1983006Y-14546D02*
Y-12413D01*
X1982423Y-12613D01*
X1982089Y-12946D01*
X1981923Y-13413D01*
X1982006Y-13879D01*
X1982256Y-14279D01*
X1982839Y-14546D01*
X1983339Y-14679D01*
X1983839D01*
X1984339Y-14546D01*
X1984839Y-14213D01*
X1985173Y-13813D01*
X1985256Y-13346D01*
X1985089Y-12879D01*
X1984589Y-12413D01*
G01X1985256Y-8446D02*
X1980256D01*
X1981256Y-9246D01*
G01X1985256D02*
Y-7646D01*
G01X1985423Y-3346D02*
X1985339Y-3479D01*
X1985173D01*
X1985089Y-3346D01*
X1985173Y-3213D01*
X1985339D01*
X1985423Y-3346D01*
G01X1983173D02*
X1983089Y-3479D01*
X1982923D01*
X1982839Y-3346D01*
X1982923Y-3213D01*
X1983089D01*
X1983173Y-3346D01*
G01X1985256Y487D02*
X1980256D01*
Y3021D01*
G01X1982673Y2087D02*
Y487D01*
G01X1985256Y6854D02*
X1985173Y6454D01*
X1984839Y6054D01*
X1984256Y5787D01*
X1983589Y5654D01*
X1982923Y5787D01*
X1982339Y6054D01*
X1982006Y6454D01*
X1981923Y6854D01*
X1982006Y7254D01*
X1982339Y7654D01*
X1982923Y7921D01*
X1983589Y7987D01*
X1984256Y7921D01*
X1984839Y7654D01*
X1985173Y7254D01*
X1985256Y6854D01*
G01Y11954D02*
X1980256D01*
G01X1985256Y17054D02*
X1980256D01*
G01X1985256Y22154D02*
X1985173Y21754D01*
X1984839Y21354D01*
X1984256Y21087D01*
X1983589Y20954D01*
X1982923Y21087D01*
X1982339Y21354D01*
X1982006Y21754D01*
X1981923Y22154D01*
X1982006Y22554D01*
X1982339Y22954D01*
X1982923Y23221D01*
X1983589Y23287D01*
X1984256Y23221D01*
X1984839Y22954D01*
X1985173Y22554D01*
X1985256Y22154D01*
G01X1981923Y25587D02*
X1985256Y26387D01*
X1981923Y27254D01*
X1985256Y28121D01*
X1981923Y28921D01*
G01X1982756Y37854D02*
Y39187D01*
X1984256D01*
X1984756Y38787D01*
X1985089Y38321D01*
X1985256Y37654D01*
X1985089Y36987D01*
X1984756Y36521D01*
X1984256Y36121D01*
X1983673Y35854D01*
X1983006Y35721D01*
X1982423D01*
X1981923Y35854D01*
X1981339Y36121D01*
X1980839Y36521D01*
X1980506Y36921D01*
X1980256Y37454D01*
Y37921D01*
X1980423Y38454D01*
X1980756Y38854D01*
G01X1983006Y41554D02*
Y43687D01*
X1982423Y43487D01*
X1982089Y43154D01*
X1981923Y42687D01*
X1982006Y42221D01*
X1982256Y41821D01*
X1982839Y41554D01*
X1983339Y41421D01*
X1983839D01*
X1984339Y41554D01*
X1984839Y41887D01*
X1985173Y42287D01*
X1985256Y42754D01*
X1985089Y43221D01*
X1984589Y43687D01*
G01X1985256Y46721D02*
X1981923D01*
G01X1982589D02*
X1982256Y47054D01*
X1982006Y47387D01*
X1981923Y47854D01*
X1982006Y48187D01*
X1982256Y48587D01*
G01X1985256Y51554D02*
X1980256D01*
G01X1982756D02*
X1982256Y51887D01*
X1982006Y52287D01*
X1981923Y52687D01*
X1982089Y53287D01*
X1982423Y53687D01*
X1983006Y53954D01*
X1983673D01*
X1984339Y53821D01*
X1984839Y53554D01*
X1985173Y53087D01*
X1985256Y52687D01*
X1985173Y52287D01*
X1984923Y51887D01*
X1984506Y51554D01*
G01X1983006Y56854D02*
Y58987D01*
X1982423Y58787D01*
X1982089Y58454D01*
X1981923Y57987D01*
X1982006Y57521D01*
X1982256Y57121D01*
X1982839Y56854D01*
X1983339Y56721D01*
X1983839D01*
X1984339Y56854D01*
X1984839Y57187D01*
X1985173Y57587D01*
X1985256Y58054D01*
X1985089Y58521D01*
X1984589Y58987D01*
G01X1985256Y62021D02*
X1981923D01*
G01X1982589D02*
X1982256Y62354D01*
X1982006Y62687D01*
X1981923Y63154D01*
X1982006Y63487D01*
X1982256Y63887D01*
G01X1985256Y71687D02*
X1980256D01*
Y73021D01*
X1980506Y73554D01*
X1980839Y73954D01*
X1981339Y74287D01*
X1981923Y74554D01*
X1982756Y74621D01*
X1983589Y74554D01*
X1984173Y74287D01*
X1984673Y73954D01*
X1985006Y73554D01*
X1985256Y73021D01*
Y71687D01*
G01Y79454D02*
X1981923D01*
G01X1982506D02*
X1982173Y79187D01*
X1982006Y78787D01*
X1981923Y78321D01*
X1982089Y77854D01*
X1982423Y77454D01*
X1982923Y77187D01*
X1983589Y77054D01*
X1984256Y77187D01*
X1984756Y77454D01*
X1985089Y77854D01*
X1985256Y78321D01*
X1985173Y78787D01*
X1984923Y79187D01*
X1984589Y79454D01*
G01X1980256Y83354D02*
X1985256D01*
G01X1981923Y82421D02*
Y84287D01*
G01X1985256Y89654D02*
X1981923D01*
G01X1982506D02*
X1982173Y89387D01*
X1982006Y88987D01*
X1981923Y88521D01*
X1982089Y88054D01*
X1982423Y87654D01*
X1982923Y87387D01*
X1983589Y87254D01*
X1984256Y87387D01*
X1984756Y87654D01*
X1985089Y88054D01*
X1985256Y88521D01*
X1985173Y88987D01*
X1984923Y89387D01*
X1984589Y89654D01*
G01X1985423Y93554D02*
X1985339Y93421D01*
X1985173D01*
X1985089Y93554D01*
X1985173Y93687D01*
X1985339D01*
X1985423Y93554D01*
G01X1984256Y-37346D02*
X1979256D01*
X1980256Y-38146D01*
G01X1984256D02*
Y-36546D01*
G01X1979256Y-40346D02*
X1986256D01*
Y-35846D01*
X1982756Y-33346D01*
X1979256Y-35846D01*
Y-40346D01*
G01X1972441Y-23622D02*
G03X1976378Y-19685I0J3937D01*
G01X1972441Y-23622D02*
G03X1976378Y-19685I0J3937D01*
G01X1972441Y-23622D02*
G03X1976378Y-19685I0J3937D01*
G01X1972441Y-23622D02*
G03X1976378Y-19685I0J3937D01*
G01D02*
Y-15748D01*
G01Y-19685D02*
Y-15748D01*
G01Y-19685D02*
Y-15748D01*
G01Y-19685D02*
Y-15748D01*
G01D02*
G03X1972441Y-11811I-3937J0D01*
G01X1976378Y-15748D02*
G03X1972441Y-11811I-3937J0D01*
G01X1976378Y-15748D02*
G03X1972441Y-11811I-3937J0D01*
G01X1976378Y-15748D02*
G03X1972441Y-11811I-3937J0D01*
G01X1976378Y0D02*
Y43307D01*
G01X1972441Y-3937D02*
G03X1976378Y0I0J3937D01*
G01X1965589Y10887D02*
X1965089Y11287D01*
X1964839Y11754D01*
X1964756Y12287D01*
X1964923Y12954D01*
X1965339Y13421D01*
X1965839Y13554D01*
X1966339Y13487D01*
X1966756Y13221D01*
X1967589Y11887D01*
X1968173Y11287D01*
X1969006Y10887D01*
X1969756Y10754D01*
Y13554D01*
G01X1964756Y17254D02*
X1964923Y16721D01*
X1965339Y16321D01*
X1965839Y16054D01*
X1966506Y15854D01*
X1967256Y15787D01*
X1968006Y15854D01*
X1968673Y16054D01*
X1969173Y16321D01*
X1969589Y16721D01*
X1969756Y17254D01*
X1969589Y17787D01*
X1969173Y18187D01*
X1968673Y18454D01*
X1968006Y18654D01*
X1967256Y18721D01*
X1966506Y18654D01*
X1965839Y18454D01*
X1965339Y18187D01*
X1964923Y17787D01*
X1964756Y17254D01*
G01X1969756Y20954D02*
X1964756Y23754D01*
G01Y20954D02*
X1969756Y23754D01*
G01Y27321D02*
X1968673Y27454D01*
X1967756Y27654D01*
X1966923Y27921D01*
X1966006Y28254D01*
X1964756Y28787D01*
Y26121D01*
G01X1969756Y32554D02*
X1964756D01*
X1965756Y31754D01*
G01X1969756D02*
Y33354D01*
G01X1972441Y55118D02*
G03X1976378Y59055I0J3937D01*
G01X1972441Y55118D02*
G03X1976378Y59055I0J3937D01*
G01X1972441Y55118D02*
G03X1976378Y59055I0J3937D01*
G01X1972441Y55118D02*
G03X1976378Y59055I0J3937D01*
G01D02*
Y242835D01*
G01Y59055D02*
Y242835D01*
G01Y59055D02*
Y242835D01*
G01Y59055D02*
Y242835D01*
G01Y43307D02*
G03X1972441Y47244I-3937J0D01*
G01X1977873Y214257D02*
X1977373Y214657D01*
X1977123Y215124D01*
X1977040Y215657D01*
X1977207Y216324D01*
X1977623Y216791D01*
X1978123Y216924D01*
X1978623Y216857D01*
X1979040Y216591D01*
X1979873Y215257D01*
X1980457Y214657D01*
X1981290Y214257D01*
X1982040Y214124D01*
Y216924D01*
G01X1977040Y220624D02*
X1977207Y220091D01*
X1977623Y219691D01*
X1978123Y219424D01*
X1978790Y219224D01*
X1979540Y219157D01*
X1980290Y219224D01*
X1980957Y219424D01*
X1981457Y219691D01*
X1981873Y220091D01*
X1982040Y220624D01*
X1981873Y221157D01*
X1981457Y221557D01*
X1980957Y221824D01*
X1980290Y222024D01*
X1979540Y222091D01*
X1978790Y222024D01*
X1978123Y221824D01*
X1977623Y221557D01*
X1977207Y221157D01*
X1977040Y220624D01*
G01X1982040Y224324D02*
X1977040Y227124D01*
G01Y224324D02*
X1982040Y227124D01*
G01X1979957Y229557D02*
X1979373Y230024D01*
X1979040Y230424D01*
X1978873Y230957D01*
X1979040Y231424D01*
X1979373Y231757D01*
X1979873Y232024D01*
X1980457Y232091D01*
X1980957Y232024D01*
X1981457Y231757D01*
X1981873Y231357D01*
X1982040Y230891D01*
X1981873Y230357D01*
X1981373Y229891D01*
X1980623Y229624D01*
X1979790Y229557D01*
X1978707Y229691D01*
X1978123Y229891D01*
X1977540Y230224D01*
X1977123Y230691D01*
X1977040Y231157D01*
X1977207Y231624D01*
X1977623Y231957D01*
G01X1977040Y235924D02*
X1977207Y235391D01*
X1977623Y234991D01*
X1978123Y234724D01*
X1978790Y234524D01*
X1979540Y234457D01*
X1980290Y234524D01*
X1980957Y234724D01*
X1981457Y234991D01*
X1981873Y235391D01*
X1982040Y235924D01*
X1981873Y236457D01*
X1981457Y236857D01*
X1980957Y237124D01*
X1980290Y237324D01*
X1979540Y237391D01*
X1978790Y237324D01*
X1978123Y237124D01*
X1977623Y236857D01*
X1977207Y236457D01*
X1977040Y235924D01*
G01X1971990Y214357D02*
X1972407Y214757D01*
X1972657Y215224D01*
X1972740Y215824D01*
X1972573Y216424D01*
X1972240Y216891D01*
X1971657Y217224D01*
X1970990Y217291D01*
X1970323Y217157D01*
X1969907Y216824D01*
X1969573Y216357D01*
X1969490Y215891D01*
X1969573Y215424D01*
X1969907Y214824D01*
X1967740Y215024D01*
Y216824D01*
G01X1968573Y219657D02*
X1968073Y220057D01*
X1967823Y220524D01*
X1967740Y221057D01*
X1967907Y221724D01*
X1968323Y222191D01*
X1968823Y222324D01*
X1969323Y222257D01*
X1969740Y221991D01*
X1970573Y220657D01*
X1971157Y220057D01*
X1971990Y219657D01*
X1972740Y219524D01*
Y222324D01*
G01Y224624D02*
X1967740Y227424D01*
G01Y224624D02*
X1972740Y227424D01*
G01Y230991D02*
X1971657Y231124D01*
X1970740Y231324D01*
X1969907Y231591D01*
X1968990Y231924D01*
X1967740Y232457D01*
Y229791D01*
G01X1971740Y234757D02*
X1972323Y235157D01*
X1972657Y235691D01*
X1972740Y236291D01*
X1972657Y236824D01*
X1972240Y237357D01*
X1971740Y237691D01*
X1971240Y237757D01*
X1970657Y237624D01*
X1970240Y237157D01*
X1970073Y236691D01*
Y236091D01*
G01Y236691D02*
X1969823Y237091D01*
X1969407Y237424D01*
X1968907Y237557D01*
X1968407Y237424D01*
X1967990Y237091D01*
X1967740Y236491D01*
X1967823Y235891D01*
X1968157Y235291D01*
G01X1976378Y242835D02*
G03X1972441Y246772I-3937J0D01*
G01X1976378Y242835D02*
G03X1972441Y246772I-3937J0D01*
G01X1976378Y242835D02*
G03X1972441Y246772I-3937J0D01*
G01X1976378Y242835D02*
G03X1972441Y246772I-3937J0D01*
G01Y432598D02*
G03X1976378Y436535I0J3937D01*
G01X1972441Y432598D02*
G03X1976378Y436535I0J3937D01*
G01X1972441Y432598D02*
G03X1976378Y436535I0J3937D01*
G01X1972441Y432598D02*
G03X1976378Y436535I0J3937D01*
G01D02*
Y622441D01*
G01Y436535D02*
Y622441D01*
G01Y436535D02*
Y622441D01*
G01Y436535D02*
Y622441D01*
G01D02*
G03X1972441Y626378I-3937J0D01*
G01X1976378Y622441D02*
G03X1972441Y626378I-3937J0D01*
G01X1976378Y622441D02*
G03X1972441Y626378I-3937J0D01*
G01X1976378Y622441D02*
G03X1972441Y626378I-3937J0D01*
G01Y634252D02*
G03X1976378Y638189I0J3937D01*
G01X1972441Y634252D02*
G03X1976378Y638189I0J3937D01*
G01D02*
Y661811D01*
G01Y638189D02*
Y661811D01*
G01D02*
G03X1972441Y665748I-3937J0D01*
G01X1976378Y661811D02*
G03X1972441Y665748I-3937J0D01*
G54D57*
X1836693Y120158D03*
X1954804D03*
X2088977Y-237048D03*
G54D39*
X1462000Y-5000D03*
Y-15000D03*
X1452000Y-5000D03*
Y-15000D03*
X1442000Y-5000D03*
Y-15000D03*
X1525000D03*
X1515000D03*
X1482000D03*
X1472000Y-5000D03*
Y-15000D03*
X1492000Y-5000D03*
Y-15000D03*
X1482000Y-5000D03*
X1505000Y-15000D03*
X1575000D03*
X1565000D03*
X1555000D03*
X1545000D03*
X1535000D03*
X1713503Y-5000D03*
Y-15000D03*
X1703503Y-5000D03*
Y-15000D03*
X1743503D03*
X1733503Y-5000D03*
Y-15000D03*
X1723503Y-5000D03*
Y-15000D03*
X1753503Y-5000D03*
Y-15000D03*
X1743503Y-5000D03*
X1769504D03*
Y-15000D03*
X1809504D03*
X1799504Y-5000D03*
Y-15000D03*
X1789504Y-5000D03*
Y-15000D03*
X1779504Y-5000D03*
Y-15000D03*
X1819504Y-5000D03*
Y-15000D03*
X1809504Y-5000D03*
X2088977Y905352D03*
G54D66*
X1950000Y220787D03*
Y228661D03*
X2088977Y-35448D03*
G54D48*
X1611283Y567874D03*
Y615236D03*
X1658528Y567874D03*
X1705772D03*
Y615236D03*
X2088977Y65352D03*
G54D49*
X1629039Y580079D03*
X1626087Y585591D03*
X1629039Y565118D03*
X1626087Y570630D03*
X1637898Y580079D03*
X1634945Y585591D03*
X1637898Y565118D03*
X1634945Y570630D03*
X1643803D03*
X1646756Y565118D03*
Y580079D03*
X1643803Y585591D03*
X1640850Y582835D03*
X1631992D03*
X1623134D03*
X1640850Y567874D03*
X1631992D03*
X1623134D03*
X1646756Y610000D03*
Y595039D03*
X1643803Y600551D03*
Y615512D03*
X1629039Y610000D03*
X1626087Y615512D03*
X1629039Y595039D03*
X1626087Y600551D03*
X1637898Y610000D03*
X1634945Y615512D03*
X1637898Y595039D03*
X1634945Y600551D03*
X1623134Y612756D03*
X1640850Y597795D03*
X1631992D03*
X1623134D03*
X1640850Y612756D03*
X1631992D03*
X1676283Y580079D03*
X1673331Y585591D03*
X1676283Y565118D03*
X1673331Y570630D03*
X1685142Y580079D03*
X1682189Y585591D03*
X1685142Y565118D03*
X1682189Y570630D03*
X1691047D03*
X1694000Y565118D03*
Y580079D03*
X1691047Y585591D03*
X1688094Y582835D03*
X1679236D03*
X1670378D03*
X1688094Y567874D03*
X1679236D03*
X1670378D03*
X1694000Y595039D03*
X1691047Y600551D03*
Y615512D03*
X1676283Y610000D03*
X1673331Y615512D03*
X1676283Y595039D03*
X1673331Y600551D03*
X1685142Y610000D03*
X1682189Y615512D03*
X1685142Y595039D03*
X1682189Y600551D03*
X1688094Y612756D03*
X1679236D03*
X1670378D03*
X1688094Y597795D03*
X1679236D03*
X1670378D03*
X1694000Y610000D03*
X2088977Y1644552D03*
G54D67*
X1956890Y211535D03*
X2088977Y670152D03*
G54D58*
X1800986Y523267D03*
X1800985Y602503D03*
X2088977Y468552D03*
G54D59*
X1809665Y618663D03*
X1819665D03*
X1829665D03*
X2088977Y1106952D03*
G54D68*
X1950000Y207893D03*
Y241555D03*
X2088977Y1846152D03*
G54D69*
X1956890Y237126D03*
X2088977Y703752D03*
M02*
